FILE_TYPE = EXPANDEDNETLIST;
{ Packager-XL run on 16-Jun-2017 AT 17:50:48 CONSTRAINTS_VIEW_GENERATED}
NET_NAME
'AGND_HSC'
 '@BASEBOARD_FAB2_LIB.BASEBOARD_FAB2(SCH_1):AGND_HSC':
 C_SIGNAL='@baseboard_fab2_lib.baseboard_fab2(sch_1):agnd_hsc';
NODE_NAME     C1D25 2
 '@BASEBOARD_FAB2_LIB.BASEBOARD_FAB2(SCH_1):PAGE199_I3@MSTR_DISCRETE.CAP(CHIPS)':
 'B': CDS_PINID='B';
NODE_NAME     C1D27 2
 '@BASEBOARD_FAB2_LIB.BASEBOARD_FAB2(SCH_1):PAGE199_I7@DEV_DISCRETE.CAP_A(CHIPS)':
 'B': CDS_PINID='B';
NODE_NAME     R1D43 2
 '@BASEBOARD_FAB2_LIB.BASEBOARD_FAB2(SCH_1):PAGE199_I9@MSTR_DISCRETE.RES(CHIPS)':
 'B': CDS_PINID='B';
NODE_NAME     EU1D2 33
 '@BASEBOARD_FAB2_LIB.BASEBOARD_FAB2(SCH_1):PAGE199_I10@MSTR_CONTROLLER.ADM1278(CHIPS)':
 'EP': CDS_PINID='EP';
NODE_NAME     EU1D2 22
 '@BASEBOARD_FAB2_LIB.BASEBOARD_FAB2(SCH_1):PAGE199_I10@MSTR_CONTROLLER.ADM1278(CHIPS)':
 'GND': CDS_PINID='GND';
NODE_NAME     R1D42 2
 '@BASEBOARD_FAB2_LIB.BASEBOARD_FAB2(SCH_1):PAGE199_I13@MSTR_DISCRETE.RES(CHIPS)':
 'B': CDS_PINID='B';
NODE_NAME     R1D41 2
 '@BASEBOARD_FAB2_LIB.BASEBOARD_FAB2(SCH_1):PAGE199_I19@MSTR_DISCRETE.RES(CHIPS)':
 'B': CDS_PINID='B';
NODE_NAME     C9P14 2
 '@BASEBOARD_FAB2_LIB.BASEBOARD_FAB2(SCH_1):PAGE199_I24@MSTR_DISCRETE.CAP(CHIPS)':
 'B': CDS_PINID='B';
NODE_NAME     R1D28 2
 '@BASEBOARD_FAB2_LIB.BASEBOARD_FAB2(SCH_1):PAGE199_I26@MSTR_DISCRETE.RES(CHIPS)':
 'B': CDS_PINID='B';
NODE_NAME     R9P17 2
 '@BASEBOARD_FAB2_LIB.BASEBOARD_FAB2(SCH_1):PAGE199_I33@MSTR_DISCRETE.RES(CHIPS)':
 'B': CDS_PINID='B';
NODE_NAME     R9P16 2
 '@BASEBOARD_FAB2_LIB.BASEBOARD_FAB2(SCH_1):PAGE199_I36@MSTR_DISCRETE.RES(CHIPS)':
 'B': CDS_PINID='B';
NODE_NAME     C1D11 2
 '@BASEBOARD_FAB2_LIB.BASEBOARD_FAB2(SCH_1):PAGE199_I53@DEV_DISCRETE.CAP_A(CHIPS)':
 'B': CDS_PINID='B';
NODE_NAME     R9P24 2
 '@BASEBOARD_FAB2_LIB.BASEBOARD_FAB2(SCH_1):PAGE199_I55@MSTR_DISCRETE.RES(CHIPS)':
 'B': CDS_PINID='B';
NODE_NAME     C9P12 2
 '@BASEBOARD_FAB2_LIB.BASEBOARD_FAB2(SCH_1):PAGE199_I67@DEV_DISCRETE.CAP_A(CHIPS)':
 'B': CDS_PINID='B';
NODE_NAME     Q1D1 4
 '@BASEBOARD_FAB2_LIB.BASEBOARD_FAB2(SCH_1):PAGE199_I82@MSTR_DISCRETE.FET_N_DUAL(CHIPS)':
 'SOURCE'<0>: CDS_PINID='SOURCE(0)';
NODE_NAME     Q1D1 1
 '@BASEBOARD_FAB2_LIB.BASEBOARD_FAB2(SCH_1):PAGE199_I86@MSTR_DISCRETE.FET_N_DUAL(CHIPS)':
 'SOURCE'<0>: CDS_PINID='SOURCE(0)';
NODE_NAME     R1D40 2
 '@BASEBOARD_FAB2_LIB.BASEBOARD_FAB2(SCH_1):PAGE199_I100@MSTR_DISCRETE.RES(CHIPS)':
 'B': CDS_PINID='B';
NODE_NAME     R1D34 2
 '@BASEBOARD_FAB2_LIB.BASEBOARD_FAB2(SCH_1):PAGE199_I102@MSTR_DISCRETE.RES(CHIPS)':
 'B': CDS_PINID='B';
NODE_NAME     C9P15 2
 '@BASEBOARD_FAB2_LIB.BASEBOARD_FAB2(SCH_1):PAGE199_I105@DEV_DISCRETE.CAP_A(CHIPS)':
 'B': CDS_PINID='B';
NODE_NAME     C1D26 2
 '@BASEBOARD_FAB2_LIB.BASEBOARD_FAB2(SCH_1):PAGE199_I107@DEV_DISCRETE.CAP_A(CHIPS)':
 'B': CDS_PINID='B';
NODE_NAME     C1D19 2
 '@BASEBOARD_FAB2_LIB.BASEBOARD_FAB2(SCH_1):PAGE199_I119@MSTR_DISCRETE.CAP(CHIPS)':
 'B': CDS_PINID='B';
NODE_NAME     C1D21 2
 '@BASEBOARD_FAB2_LIB.BASEBOARD_FAB2(SCH_1):PAGE199_I121@DEV_DISCRETE.CAP_A(CHIPS)':
 'B': CDS_PINID='B';
NODE_NAME     C9P17 2
 '@BASEBOARD_FAB2_LIB.BASEBOARD_FAB2(SCH_1):PAGE200_I36@DEV_DISCRETE.CAP_A(CHIPS)':
 'B': CDS_PINID='B';
NODE_NAME     C9P16 2
 '@BASEBOARD_FAB2_LIB.BASEBOARD_FAB2(SCH_1):PAGE200_I40@DEV_DISCRETE.CAP_A(CHIPS)':
 'B': CDS_PINID='B';
NODE_NAME     R9P19 2
 '@BASEBOARD_FAB2_LIB.BASEBOARD_FAB2(SCH_1):PAGE200_I70@MSTR_DISCRETE.RES(CHIPS)':
 'B': CDS_PINID='B';
NODE_NAME     R9P11 2
 '@BASEBOARD_FAB2_LIB.BASEBOARD_FAB2(SCH_1):PAGE200_I108@MSTR_DISCRETE.RES(CHIPS)':
 'B': CDS_PINID='B';
NODE_NAME     R1D12 2
 '@BASEBOARD_FAB2_LIB.BASEBOARD_FAB2(SCH_1):PAGE200_I174@MSTR_DISCRETE.RES(CHIPS)':
 'B': CDS_PINID='B';
NODE_NAME     R1D19 2
 '@BASEBOARD_FAB2_LIB.BASEBOARD_FAB2(SCH_1):PAGE200_I175@MSTR_DISCRETE.RES(CHIPS)':
 'B': CDS_PINID='B';
NODE_NAME     C9P6 2
 '@BASEBOARD_FAB2_LIB.BASEBOARD_FAB2(SCH_1):PAGE200_I185@DEV_DISCRETE.CAP_A(CHIPS)':
 'B': CDS_PINID='B';
NODE_NAME     C1D9 2
 '@BASEBOARD_FAB2_LIB.BASEBOARD_FAB2(SCH_1):PAGE200_I187@DEV_DISCRETE.CAP_A(CHIPS)':
 'B': CDS_PINID='B';
NODE_NAME     R9P12 2
 '@BASEBOARD_FAB2_LIB.BASEBOARD_FAB2(SCH_1):PAGE200_I218@MSTR_DISCRETE.RES(CHIPS)':
 'B': CDS_PINID='B';
NODE_NAME     C9W1 2
 '@BASEBOARD_FAB2_LIB.BASEBOARD_FAB2(SCH_1):PAGE200_I235@W_HDL.SC22P50V2JN-4GP(CHIPS)':
 '2': CDS_PINID='\2\';
NODE_NAME     C9W2 2
 '@BASEBOARD_FAB2_LIB.BASEBOARD_FAB2(SCH_1):PAGE200_I236@W_HDL.SC22P50V2JN-4GP(CHIPS)':
 '2': CDS_PINID='\2\';
NODE_NAME     R1D18 2
 '@BASEBOARD_FAB2_LIB.BASEBOARD_FAB2(SCH_1):PAGE199_I87@MSTR_DISCRETE.RES(CHIPS)':
 'B': CDS_PINID='B';
NODE_NAME     R1D11 2
 '@BASEBOARD_FAB2_LIB.BASEBOARD_FAB2(SCH_1):PAGE199_I88@MSTR_DISCRETE.RES(CHIPS)':
 'B': CDS_PINID='B';
NODE_NAME     R9P9 2
 '@BASEBOARD_FAB2_LIB.BASEBOARD_FAB2(SCH_1):PAGE200_I251@MSTR_DISCRETE.RES(CHIPS)':
 'B': CDS_PINID='B';
NET_NAME
'AGND_P3V3_STBY'
 '@BASEBOARD_FAB2_LIB.BASEBOARD_FAB2(SCH_1):AGND_P3V3_STBY':
 C_SIGNAL='@baseboard_fab2_lib.baseboard_fab2(sch_1):agnd_p3v3_stby';
NODE_NAME     C8E17 2
 '@BASEBOARD_FAB2_LIB.BASEBOARD_FAB2(SCH_1):PAGE240_I113@MSTR_DISCRETE.CAP(CHIPS)':
 'B': CDS_PINID='B';
NODE_NAME     EU8F1 11
 '@BASEBOARD_FAB2_LIB.BASEBOARD_FAB2(SCH_1):PAGE240_I125@MSTR_VREG.RT8240(CHIPS)':
 'G0': CDS_PINID='G0';
NODE_NAME     EU8F1 12
 '@BASEBOARD_FAB2_LIB.BASEBOARD_FAB2(SCH_1):PAGE240_I125@MSTR_VREG.RT8240(CHIPS)':
 'GND'<0>: CDS_PINID='GND(0)';
NODE_NAME     EU8F1 13
 '@BASEBOARD_FAB2_LIB.BASEBOARD_FAB2(SCH_1):PAGE240_I125@MSTR_VREG.RT8240(CHIPS)':
 'GND'<1>: CDS_PINID='GND(1)';
NODE_NAME     R8E38 2
 '@BASEBOARD_FAB2_LIB.BASEBOARD_FAB2(SCH_1):PAGE240_I140@MSTR_DISCRETE.RES(CHIPS)':
 'B': CDS_PINID='B';
NODE_NAME     R8E34 2
 '@BASEBOARD_FAB2_LIB.BASEBOARD_FAB2(SCH_1):PAGE240_I142@MSTR_DISCRETE.RES(CHIPS)':
 'B': CDS_PINID='B';
NODE_NAME     R8F11 2
 '@BASEBOARD_FAB2_LIB.BASEBOARD_FAB2(SCH_1):PAGE240_I146@MSTR_DISCRETE.RES(CHIPS)':
 'B': CDS_PINID='B';
NODE_NAME     C2R11 2
 '@BASEBOARD_FAB2_LIB.BASEBOARD_FAB2(SCH_1):PAGE240_I191@W_HDL.SC4D7U16V3KX-GP(CHIPS)':
 '2': CDS_PINID='\2\';
NODE_NAME     R8F9 2
 '@BASEBOARD_FAB2_LIB.BASEBOARD_FAB2(SCH_1):PAGE240_I195@MSTR_DISCRETE.RES(CHIPS)':
 'B': CDS_PINID='B';
NET_NAME
'AGND_P5V_STBY'
 '@BASEBOARD_FAB2_LIB.BASEBOARD_FAB2(SCH_1):AGND_P5V_STBY':
 C_SIGNAL='@baseboard_fab2_lib.baseboard_fab2(sch_1):agnd_p5v_stby';
NODE_NAME     R7E14 2
 '@BASEBOARD_FAB2_LIB.BASEBOARD_FAB2(SCH_1):PAGE241_I18@MSTR_DISCRETE.RES(CHIPS)':
 'B': CDS_PINID='B';
NODE_NAME     C8E13 2
 '@BASEBOARD_FAB2_LIB.BASEBOARD_FAB2(SCH_1):PAGE241_I41@MSTR_DISCRETE.CAP(CHIPS)':
 'B': CDS_PINID='B';
NODE_NAME     R7E16 2
 '@BASEBOARD_FAB2_LIB.BASEBOARD_FAB2(SCH_1):PAGE241_I51@MSTR_DISCRETE.RES(CHIPS)':
 'B': CDS_PINID='B';
NODE_NAME     C8E16 2
 '@BASEBOARD_FAB2_LIB.BASEBOARD_FAB2(SCH_1):PAGE241_I53@MSTR_DISCRETE.CAP(CHIPS)':
 'B': CDS_PINID='B';
NODE_NAME     C8F1 2
 '@BASEBOARD_FAB2_LIB.BASEBOARD_FAB2(SCH_1):PAGE241_I57@MSTR_DISCRETE.CAP(CHIPS)':
 'B': CDS_PINID='B';
NODE_NAME     R7E13 2
 '@BASEBOARD_FAB2_LIB.BASEBOARD_FAB2(SCH_1):PAGE241_I58@MSTR_DISCRETE.RES(CHIPS)':
 'B': CDS_PINID='B';
NODE_NAME     C8E15 2
 '@BASEBOARD_FAB2_LIB.BASEBOARD_FAB2(SCH_1):PAGE241_I63@MSTR_DISCRETE.CAP(CHIPS)':
 'B': CDS_PINID='B';
NET_NAME
'AGND_PVPP_ABC'
 '@BASEBOARD_FAB2_LIB.BASEBOARD_FAB2(SCH_1):AGND_PVPP_ABC':
 C_SIGNAL='@baseboard_fab2_lib.baseboard_fab2(sch_1):agnd_pvpp_abc';
NODE_NAME     R7F15 2
 '@BASEBOARD_FAB2_LIB.BASEBOARD_FAB2(SCH_1):PAGE231_I134@MSTR_DISCRETE.RES(CHIPS)':
 'B': CDS_PINID='B';
NODE_NAME     C7F8 2
 '@BASEBOARD_FAB2_LIB.BASEBOARD_FAB2(SCH_1):PAGE231_I140@MSTR_DISCRETE.CAP(CHIPS)':
 'B': CDS_PINID='B';
NODE_NAME     R7F35 2
 '@BASEBOARD_FAB2_LIB.BASEBOARD_FAB2(SCH_1):PAGE231_I170@MSTR_DISCRETE.RES(CHIPS)':
 'B': CDS_PINID='B';
NODE_NAME     EU7F1 5
 '@BASEBOARD_FAB2_LIB.BASEBOARD_FAB2(SCH_1):PAGE231_I193@MSTR_VREG.NCP3232L(CHIPS)':
 'AGND': CDS_PINID='AGND';
NODE_NAME     EU7F1 6
 '@BASEBOARD_FAB2_LIB.BASEBOARD_FAB2(SCH_1):PAGE231_I193@MSTR_VREG.NCP3232L(CHIPS)':
 'OTS': CDS_PINID='OTS';
NODE_NAME     C7F10 2
 '@BASEBOARD_FAB2_LIB.BASEBOARD_FAB2(SCH_1):PAGE231_I194@MSTR_DISCRETE.CAP(CHIPS)':
 'B': CDS_PINID='B';
NODE_NAME     C3T11 2
 '@BASEBOARD_FAB2_LIB.BASEBOARD_FAB2(SCH_1):PAGE231_I202@MSTR_DISCRETE.CAP(CHIPS)':
 'B': CDS_PINID='B';
NODE_NAME     R7F11 2
 '@BASEBOARD_FAB2_LIB.BASEBOARD_FAB2(SCH_1):PAGE231_I230@MSTR_DISCRETE.RES(CHIPS)':
 'B': CDS_PINID='B';
NET_NAME
'AGND_PVPP_DEF'
 '@BASEBOARD_FAB2_LIB.BASEBOARD_FAB2(SCH_1):AGND_PVPP_DEF':
 C_SIGNAL='@baseboard_fab2_lib.baseboard_fab2(sch_1):agnd_pvpp_def';
NODE_NAME     R7B20 2
 '@BASEBOARD_FAB2_LIB.BASEBOARD_FAB2(SCH_1):PAGE232_I150@MSTR_DISCRETE.RES(CHIPS)':
 'B': CDS_PINID='B';
NODE_NAME     C7B9 2
 '@BASEBOARD_FAB2_LIB.BASEBOARD_FAB2(SCH_1):PAGE232_I185@MSTR_DISCRETE.CAP(CHIPS)':
 'B': CDS_PINID='B';
NODE_NAME     C7B11 2
 '@BASEBOARD_FAB2_LIB.BASEBOARD_FAB2(SCH_1):PAGE232_I197@MSTR_DISCRETE.CAP(CHIPS)':
 'B': CDS_PINID='B';
NODE_NAME     EU7B1 5
 '@BASEBOARD_FAB2_LIB.BASEBOARD_FAB2(SCH_1):PAGE232_I214@MSTR_VREG.NCP3232L(CHIPS)':
 'AGND': CDS_PINID='AGND';
NODE_NAME     EU7B1 6
 '@BASEBOARD_FAB2_LIB.BASEBOARD_FAB2(SCH_1):PAGE232_I214@MSTR_VREG.NCP3232L(CHIPS)':
 'OTS': CDS_PINID='OTS';
NODE_NAME     C3M10 2
 '@BASEBOARD_FAB2_LIB.BASEBOARD_FAB2(SCH_1):PAGE232_I253@MSTR_DISCRETE.CAP(CHIPS)':
 'B': CDS_PINID='B';
NODE_NAME     R7B13 2
 '@BASEBOARD_FAB2_LIB.BASEBOARD_FAB2(SCH_1):PAGE232_I314@MSTR_DISCRETE.RES(CHIPS)':
 'B': CDS_PINID='B';
NODE_NAME     R7B14 2
 '@BASEBOARD_FAB2_LIB.BASEBOARD_FAB2(SCH_1):PAGE232_I315@MSTR_DISCRETE.RES(CHIPS)':
 'B': CDS_PINID='B';
NET_NAME
'AGND_PVPP_GHJ'
 '@BASEBOARD_FAB2_LIB.BASEBOARD_FAB2(SCH_1):AGND_PVPP_GHJ':
 C_SIGNAL='@baseboard_fab2_lib.baseboard_fab2(sch_1):agnd_pvpp_ghj';
NODE_NAME     R4G25 2
 '@BASEBOARD_FAB2_LIB.BASEBOARD_FAB2(SCH_1):PAGE233_I157@MSTR_DISCRETE.RES(CHIPS)':
 'B': CDS_PINID='B';
NODE_NAME     C4G7 2
 '@BASEBOARD_FAB2_LIB.BASEBOARD_FAB2(SCH_1):PAGE233_I183@MSTR_DISCRETE.CAP(CHIPS)':
 'B': CDS_PINID='B';
NODE_NAME     C6U6 2
 '@BASEBOARD_FAB2_LIB.BASEBOARD_FAB2(SCH_1):PAGE233_I187@MSTR_DISCRETE.CAP(CHIPS)':
 'B': CDS_PINID='B';
NODE_NAME     C4G8 2
 '@BASEBOARD_FAB2_LIB.BASEBOARD_FAB2(SCH_1):PAGE233_I194@MSTR_DISCRETE.CAP(CHIPS)':
 'B': CDS_PINID='B';
NODE_NAME     EU4G1 5
 '@BASEBOARD_FAB2_LIB.BASEBOARD_FAB2(SCH_1):PAGE233_I225@MSTR_VREG.NCP3232L(CHIPS)':
 'AGND': CDS_PINID='AGND';
NODE_NAME     EU4G1 6
 '@BASEBOARD_FAB2_LIB.BASEBOARD_FAB2(SCH_1):PAGE233_I225@MSTR_VREG.NCP3232L(CHIPS)':
 'OTS': CDS_PINID='OTS';
NODE_NAME     R4G9 2
 '@BASEBOARD_FAB2_LIB.BASEBOARD_FAB2(SCH_1):PAGE233_I283@MSTR_DISCRETE.RES(CHIPS)':
 'B': CDS_PINID='B';
NODE_NAME     R4G11 2
 '@BASEBOARD_FAB2_LIB.BASEBOARD_FAB2(SCH_1):PAGE233_I284@MSTR_DISCRETE.RES(CHIPS)':
 'B': CDS_PINID='B';
NET_NAME
'AGND_PVPP_KLM'
 '@BASEBOARD_FAB2_LIB.BASEBOARD_FAB2(SCH_1):AGND_PVPP_KLM':
 C_SIGNAL='@baseboard_fab2_lib.baseboard_fab2(sch_1):agnd_pvpp_klm';
NODE_NAME     R4B14 2
 '@BASEBOARD_FAB2_LIB.BASEBOARD_FAB2(SCH_1):PAGE234_I29@MSTR_DISCRETE.RES(CHIPS)':
 'B': CDS_PINID='B';
NODE_NAME     C4B5 2
 '@BASEBOARD_FAB2_LIB.BASEBOARD_FAB2(SCH_1):PAGE234_I129@MSTR_DISCRETE.CAP(CHIPS)':
 'B': CDS_PINID='B';
NODE_NAME     C6L12 2
 '@BASEBOARD_FAB2_LIB.BASEBOARD_FAB2(SCH_1):PAGE234_I144@MSTR_DISCRETE.CAP(CHIPS)':
 'B': CDS_PINID='B';
NODE_NAME     C4B6 2
 '@BASEBOARD_FAB2_LIB.BASEBOARD_FAB2(SCH_1):PAGE234_I146@MSTR_DISCRETE.CAP(CHIPS)':
 'B': CDS_PINID='B';
NODE_NAME     EU4A3 5
 '@BASEBOARD_FAB2_LIB.BASEBOARD_FAB2(SCH_1):PAGE234_I184@MSTR_VREG.NCP3232L(CHIPS)':
 'AGND': CDS_PINID='AGND';
NODE_NAME     EU4A3 6
 '@BASEBOARD_FAB2_LIB.BASEBOARD_FAB2(SCH_1):PAGE234_I184@MSTR_VREG.NCP3232L(CHIPS)':
 'OTS': CDS_PINID='OTS';
NODE_NAME     R4B4 2
 '@BASEBOARD_FAB2_LIB.BASEBOARD_FAB2(SCH_1):PAGE234_I227@MSTR_DISCRETE.RES(CHIPS)':
 'B': CDS_PINID='B';
NODE_NAME     R4B6 2
 '@BASEBOARD_FAB2_LIB.BASEBOARD_FAB2(SCH_1):PAGE234_I228@MSTR_DISCRETE.RES(CHIPS)':
 'B': CDS_PINID='B';
NET_NAME
'A_1P8_3P3_RCOMP'
 '@BASEBOARD_FAB2_LIB.BASEBOARD_FAB2(SCH_1):A_1P8_3P3_RCOMP':
 C_SIGNAL='@baseboard_fab2_lib.baseboard_fab2(sch_1):a_1p8_3p3_rcomp';
NODE_NAME     U7C1 AM4
 '@BASEBOARD_FAB2_LIB.BASEBOARD_FAB2(SCH_1):PAGE121_I34@MSTR_U_PROC.LBG_CORE_QAT_EXT_D(CHIPS)':
 'GPIO_RCOMP_1P8_3P3': CDS_PINID='GPIO_RCOMP_1P8_3P3';
NODE_NAME     R8C26 1
 '@BASEBOARD_FAB2_LIB.BASEBOARD_FAB2(SCH_1):PAGE121_I35@MSTR_DISCRETE.RES(CHIPS)':
 'A': CDS_PINID='A';
NET_NAME
'A_ADM1085_CEXT'
 '@BASEBOARD_FAB2_LIB.BASEBOARD_FAB2(SCH_1):A_ADM1085_CEXT':
 C_SIGNAL='@baseboard_fab2_lib.baseboard_fab2(sch_1):a_adm1085_cext';
NODE_NAME     C3P45 1
 '@BASEBOARD_FAB2_LIB.BASEBOARD_FAB2(SCH_1):PAGE196_I60@MSTR_DISCRETE.CAP(CHIPS)':
 'A': CDS_PINID='A';
NODE_NAME     U7D3 5
 '@BASEBOARD_FAB2_LIB.BASEBOARD_FAB2(SCH_1):PAGE196_I70@MSTR_ANALOG.ADM1085(CHIPS)':
 'CEXT': CDS_PINID='CEXT';
NET_NAME
'A_CBOT'
 '@BASEBOARD_FAB2_LIB.BASEBOARD_FAB2(SCH_1):A_CBOT':
 C_SIGNAL='@baseboard_fab2_lib.baseboard_fab2(sch_1):a_cbot';
NODE_NAME     EU9E1 37
 '@BASEBOARD_FAB2_LIB.BASEBOARD_FAB2(SCH_1):PAGE139_I72@MSTR_INTEL.SPRINGVILLE(CHIPS)':
 'CBOT': CDS_PINID='CBOT';
NODE_NAME     C9E7 2
 '@BASEBOARD_FAB2_LIB.BASEBOARD_FAB2(SCH_1):PAGE139_I76@MSTR_DISCRETE.CAP(CHIPS)':
 'B': CDS_PINID='B';
NET_NAME
'A_COMP_CKMNG'
 '@BASEBOARD_FAB2_LIB.BASEBOARD_FAB2(SCH_1):A_COMP_CKMNG':
 C_SIGNAL='@baseboard_fab2_lib.baseboard_fab2(sch_1):a_comp_ckmng';
NODE_NAME     R8F25 1
 '@BASEBOARD_FAB2_LIB.BASEBOARD_FAB2(SCH_1):PAGE101_I28@MSTR_DISCRETE.RES(CHIPS)':
 'A': CDS_PINID='A';
NODE_NAME     EU8F2 11
 '@BASEBOARD_FAB2_LIB.BASEBOARD_FAB2(SCH_1):PAGE101_I34@MSTR_CLOCK.ICS9FGP204(CHIPS)':
 'IREF': CDS_PINID='IREF';
NET_NAME
'A_CPU0_ABC_RCOMP0'
 '@BASEBOARD_FAB2_LIB.BASEBOARD_FAB2(SCH_1):A_CPU0_ABC_RCOMP0':
 C_SIGNAL='@baseboard_fab2_lib.baseboard_fab2(sch_1):a_cpu0_abc_rcomp0';
NODE_NAME     R4P8 1
 '@BASEBOARD_FAB2_LIB.BASEBOARD_FAB2(SCH_1):PAGE21_I180@MSTR_DISCRETE.RES(CHIPS)':
 'A': CDS_PINID='A';
NODE_NAME     U5D1 Y43
 '@BASEBOARD_FAB2_LIB.BASEBOARD_FAB2(SCH_1):PAGE21_I259@CHPSET_LIB.SKX_EXT_B(CHIPS)':
 'DDR012_RCOMP'<0>: CDS_PINID='DDR012_RCOMP(0)';
NET_NAME
'A_CPU0_ABC_RCOMP1'
 '@BASEBOARD_FAB2_LIB.BASEBOARD_FAB2(SCH_1):A_CPU0_ABC_RCOMP1':
 C_SIGNAL='@baseboard_fab2_lib.baseboard_fab2(sch_1):a_cpu0_abc_rcomp1';
NODE_NAME     R4P10 1
 '@BASEBOARD_FAB2_LIB.BASEBOARD_FAB2(SCH_1):PAGE21_I181@MSTR_DISCRETE.RES(CHIPS)':
 'A': CDS_PINID='A';
NODE_NAME     U5D1 AB43
 '@BASEBOARD_FAB2_LIB.BASEBOARD_FAB2(SCH_1):PAGE21_I259@CHPSET_LIB.SKX_EXT_B(CHIPS)':
 'DDR012_RCOMP'<1>: CDS_PINID='DDR012_RCOMP(1)';
NET_NAME
'A_CPU0_ABC_RCOMP2'
 '@BASEBOARD_FAB2_LIB.BASEBOARD_FAB2(SCH_1):A_CPU0_ABC_RCOMP2':
 C_SIGNAL='@baseboard_fab2_lib.baseboard_fab2(sch_1):a_cpu0_abc_rcomp2';
NODE_NAME     R4P11 1
 '@BASEBOARD_FAB2_LIB.BASEBOARD_FAB2(SCH_1):PAGE21_I182@MSTR_DISCRETE.RES(CHIPS)':
 'A': CDS_PINID='A';
NODE_NAME     U5D1 AC42
 '@BASEBOARD_FAB2_LIB.BASEBOARD_FAB2(SCH_1):PAGE21_I259@CHPSET_LIB.SKX_EXT_B(CHIPS)':
 'DDR012_RCOMP'<2>: CDS_PINID='DDR012_RCOMP(2)';
NET_NAME
'A_CPU0_DEF_RCOMP0'
 '@BASEBOARD_FAB2_LIB.BASEBOARD_FAB2(SCH_1):A_CPU0_DEF_RCOMP0':
 C_SIGNAL='@baseboard_fab2_lib.baseboard_fab2(sch_1):a_cpu0_def_rcomp0';
NODE_NAME     R5D1 1
 '@BASEBOARD_FAB2_LIB.BASEBOARD_FAB2(SCH_1):PAGE21_I177@MSTR_DISCRETE.RES(CHIPS)':
 'A': CDS_PINID='A';
NODE_NAME     U5D1 DC48
 '@BASEBOARD_FAB2_LIB.BASEBOARD_FAB2(SCH_1):PAGE21_I259@CHPSET_LIB.SKX_EXT_B(CHIPS)':
 'DDR345_RCOMP'<0>: CDS_PINID='DDR345_RCOMP(0)';
NET_NAME
'A_CPU0_DEF_RCOMP1'
 '@BASEBOARD_FAB2_LIB.BASEBOARD_FAB2(SCH_1):A_CPU0_DEF_RCOMP1':
 C_SIGNAL='@baseboard_fab2_lib.baseboard_fab2(sch_1):a_cpu0_def_rcomp1';
NODE_NAME     R5D2 1
 '@BASEBOARD_FAB2_LIB.BASEBOARD_FAB2(SCH_1):PAGE21_I178@MSTR_DISCRETE.RES(CHIPS)':
 'A': CDS_PINID='A';
NODE_NAME     U5D1 DD47
 '@BASEBOARD_FAB2_LIB.BASEBOARD_FAB2(SCH_1):PAGE21_I259@CHPSET_LIB.SKX_EXT_B(CHIPS)':
 'DDR345_RCOMP'<1>: CDS_PINID='DDR345_RCOMP(1)';
NET_NAME
'A_CPU0_DEF_RCOMP2'
 '@BASEBOARD_FAB2_LIB.BASEBOARD_FAB2(SCH_1):A_CPU0_DEF_RCOMP2':
 C_SIGNAL='@baseboard_fab2_lib.baseboard_fab2(sch_1):a_cpu0_def_rcomp2';
NODE_NAME     R6D1 1
 '@BASEBOARD_FAB2_LIB.BASEBOARD_FAB2(SCH_1):PAGE21_I179@MSTR_DISCRETE.RES(CHIPS)':
 'A': CDS_PINID='A';
NODE_NAME     U5D1 DD49
 '@BASEBOARD_FAB2_LIB.BASEBOARD_FAB2(SCH_1):PAGE21_I259@CHPSET_LIB.SKX_EXT_B(CHIPS)':
 'DDR345_RCOMP'<2>: CDS_PINID='DDR345_RCOMP(2)';
NET_NAME
'A_CPU0_MCP01_RBIAS'
 '@BASEBOARD_FAB2_LIB.BASEBOARD_FAB2(SCH_1):A_CPU0_MCP01_RBIAS':
 C_SIGNAL='@baseboard_fab2_lib.baseboard_fab2(sch_1):a_cpu0_mcp01_rbias';
NODE_NAME     R6D2 1
 '@BASEBOARD_FAB2_LIB.BASEBOARD_FAB2(SCH_1):PAGE21_I204@MSTR_DISCRETE.RES(CHIPS)':
 'A': CDS_PINID='A';
NODE_NAME     U5D1 CU32
 '@BASEBOARD_FAB2_LIB.BASEBOARD_FAB2(SCH_1):PAGE21_I259@CHPSET_LIB.SKX_EXT_B(CHIPS)':
 'MCP01_RBIAS'<0>: CDS_PINID='MCP01_RBIAS(0)';
NODE_NAME     U5D1 CT31
 '@BASEBOARD_FAB2_LIB.BASEBOARD_FAB2(SCH_1):PAGE21_I259@CHPSET_LIB.SKX_EXT_B(CHIPS)':
 'MCP01_RBIAS'<1>: CDS_PINID='MCP01_RBIAS(1)';
NET_NAME
'A_CPU0_PE012_RBIAS'
 '@BASEBOARD_FAB2_LIB.BASEBOARD_FAB2(SCH_1):A_CPU0_PE012_RBIAS':
 C_SIGNAL='@baseboard_fab2_lib.baseboard_fab2(sch_1):a_cpu0_pe012_rbias';
NODE_NAME     R4P3 1
 '@BASEBOARD_FAB2_LIB.BASEBOARD_FAB2(SCH_1):PAGE21_I186@MSTR_DISCRETE.RES(CHIPS)':
 'A': CDS_PINID='A';
NODE_NAME     U5D1 CN30
 '@BASEBOARD_FAB2_LIB.BASEBOARD_FAB2(SCH_1):PAGE21_I259@CHPSET_LIB.SKX_EXT_B(CHIPS)':
 'PE012_RBIAS'<0>: CDS_PINID='PE012_RBIAS(0)';
NODE_NAME     U5D1 CL30
 '@BASEBOARD_FAB2_LIB.BASEBOARD_FAB2(SCH_1):PAGE21_I259@CHPSET_LIB.SKX_EXT_B(CHIPS)':
 'PE012_RBIAS'<1>: CDS_PINID='PE012_RBIAS(1)';
NET_NAME
'A_CPU0_PE3_RBIAS'
 '@BASEBOARD_FAB2_LIB.BASEBOARD_FAB2(SCH_1):A_CPU0_PE3_RBIAS':
 C_SIGNAL='@baseboard_fab2_lib.baseboard_fab2(sch_1):a_cpu0_pe3_rbias';
NODE_NAME     R4P2 1
 '@BASEBOARD_FAB2_LIB.BASEBOARD_FAB2(SCH_1):PAGE21_I188@MSTR_DISCRETE.RES(CHIPS)':
 'A': CDS_PINID='A';
NODE_NAME     U5D1 CP29
 '@BASEBOARD_FAB2_LIB.BASEBOARD_FAB2(SCH_1):PAGE21_I259@CHPSET_LIB.SKX_EXT_B(CHIPS)':
 'PE3_RBIAS'<0>: CDS_PINID='PE3_RBIAS(0)';
NODE_NAME     U5D1 CR30
 '@BASEBOARD_FAB2_LIB.BASEBOARD_FAB2(SCH_1):PAGE21_I259@CHPSET_LIB.SKX_EXT_B(CHIPS)':
 'PE3_RBIAS'<1>: CDS_PINID='PE3_RBIAS(1)';
NET_NAME
'A_CPU0_UPI01_RBIAS'
 '@BASEBOARD_FAB2_LIB.BASEBOARD_FAB2(SCH_1):A_CPU0_UPI01_RBIAS':
 C_SIGNAL='@baseboard_fab2_lib.baseboard_fab2(sch_1):a_cpu0_upi01_rbias';
NODE_NAME     R6D11 1
 '@BASEBOARD_FAB2_LIB.BASEBOARD_FAB2(SCH_1):PAGE21_I184@MSTR_DISCRETE.RES(CHIPS)':
 'A': CDS_PINID='A';
NODE_NAME     U5D1 AT29
 '@BASEBOARD_FAB2_LIB.BASEBOARD_FAB2(SCH_1):PAGE21_I259@CHPSET_LIB.SKX_EXT_B(CHIPS)':
 'UPI01_RBIAS'<0>: CDS_PINID='UPI01_RBIAS(0)';
NODE_NAME     U5D1 AP29
 '@BASEBOARD_FAB2_LIB.BASEBOARD_FAB2(SCH_1):PAGE21_I259@CHPSET_LIB.SKX_EXT_B(CHIPS)':
 'UPI01_RBIAS'<1>: CDS_PINID='UPI01_RBIAS(1)';
NET_NAME
'A_CPU0_UPI2_RBIAS'
 '@BASEBOARD_FAB2_LIB.BASEBOARD_FAB2(SCH_1):A_CPU0_UPI2_RBIAS':
 C_SIGNAL='@baseboard_fab2_lib.baseboard_fab2(sch_1):a_cpu0_upi2_rbias';
NODE_NAME     R4P4 1
 '@BASEBOARD_FAB2_LIB.BASEBOARD_FAB2(SCH_1):PAGE21_I189@MSTR_DISCRETE.RES(CHIPS)':
 'A': CDS_PINID='A';
NODE_NAME     U5D1 CL28
 '@BASEBOARD_FAB2_LIB.BASEBOARD_FAB2(SCH_1):PAGE21_I259@CHPSET_LIB.SKX_EXT_B(CHIPS)':
 'UPI2_RBIAS'<0>: CDS_PINID='UPI2_RBIAS(0)';
NODE_NAME     U5D1 CK29
 '@BASEBOARD_FAB2_LIB.BASEBOARD_FAB2(SCH_1):PAGE21_I259@CHPSET_LIB.SKX_EXT_B(CHIPS)':
 'UPI2_RBIAS'<1>: CDS_PINID='UPI2_RBIAS(1)';
NET_NAME
'A_CPU1_GHJ_RCOMP0'
 '@BASEBOARD_FAB2_LIB.BASEBOARD_FAB2(SCH_1):A_CPU1_GHJ_RCOMP0':
 C_SIGNAL='@baseboard_fab2_lib.baseboard_fab2(sch_1):a_cpu1_ghj_rcomp0';
NODE_NAME     R7P16 1
 '@BASEBOARD_FAB2_LIB.BASEBOARD_FAB2(SCH_1):PAGE55_I119@MSTR_DISCRETE.RES(CHIPS)':
 'A': CDS_PINID='A';
NODE_NAME     U2D1 Y43
 '@BASEBOARD_FAB2_LIB.BASEBOARD_FAB2(SCH_1):PAGE55_I172@CHPSET_LIB.SKX_EXT_B(CHIPS)':
 'DDR012_RCOMP'<0>: CDS_PINID='DDR012_RCOMP(0)';
NET_NAME
'A_CPU1_GHJ_RCOMP1'
 '@BASEBOARD_FAB2_LIB.BASEBOARD_FAB2(SCH_1):A_CPU1_GHJ_RCOMP1':
 C_SIGNAL='@baseboard_fab2_lib.baseboard_fab2(sch_1):a_cpu1_ghj_rcomp1';
NODE_NAME     R7P17 1
 '@BASEBOARD_FAB2_LIB.BASEBOARD_FAB2(SCH_1):PAGE55_I140@MSTR_DISCRETE.RES(CHIPS)':
 'A': CDS_PINID='A';
NODE_NAME     U2D1 AB43
 '@BASEBOARD_FAB2_LIB.BASEBOARD_FAB2(SCH_1):PAGE55_I172@CHPSET_LIB.SKX_EXT_B(CHIPS)':
 'DDR012_RCOMP'<1>: CDS_PINID='DDR012_RCOMP(1)';
NET_NAME
'A_CPU1_GHJ_RCOMP2'
 '@BASEBOARD_FAB2_LIB.BASEBOARD_FAB2(SCH_1):A_CPU1_GHJ_RCOMP2':
 C_SIGNAL='@baseboard_fab2_lib.baseboard_fab2(sch_1):a_cpu1_ghj_rcomp2';
NODE_NAME     R7P19 1
 '@BASEBOARD_FAB2_LIB.BASEBOARD_FAB2(SCH_1):PAGE55_I115@MSTR_DISCRETE.RES(CHIPS)':
 'A': CDS_PINID='A';
NODE_NAME     U2D1 AC42
 '@BASEBOARD_FAB2_LIB.BASEBOARD_FAB2(SCH_1):PAGE55_I172@CHPSET_LIB.SKX_EXT_B(CHIPS)':
 'DDR012_RCOMP'<2>: CDS_PINID='DDR012_RCOMP(2)';
NET_NAME
'A_CPU1_KLM_RCOMP0'
 '@BASEBOARD_FAB2_LIB.BASEBOARD_FAB2(SCH_1):A_CPU1_KLM_RCOMP0':
 C_SIGNAL='@baseboard_fab2_lib.baseboard_fab2(sch_1):a_cpu1_klm_rcomp0';
NODE_NAME     R3D1 1
 '@BASEBOARD_FAB2_LIB.BASEBOARD_FAB2(SCH_1):PAGE55_I116@MSTR_DISCRETE.RES(CHIPS)':
 'A': CDS_PINID='A';
NODE_NAME     U2D1 DC48
 '@BASEBOARD_FAB2_LIB.BASEBOARD_FAB2(SCH_1):PAGE55_I172@CHPSET_LIB.SKX_EXT_B(CHIPS)':
 'DDR345_RCOMP'<0>: CDS_PINID='DDR345_RCOMP(0)';
NET_NAME
'A_CPU1_KLM_RCOMP1'
 '@BASEBOARD_FAB2_LIB.BASEBOARD_FAB2(SCH_1):A_CPU1_KLM_RCOMP1':
 C_SIGNAL='@baseboard_fab2_lib.baseboard_fab2(sch_1):a_cpu1_klm_rcomp1';
NODE_NAME     R3D2 1
 '@BASEBOARD_FAB2_LIB.BASEBOARD_FAB2(SCH_1):PAGE55_I117@MSTR_DISCRETE.RES(CHIPS)':
 'A': CDS_PINID='A';
NODE_NAME     U2D1 DD47
 '@BASEBOARD_FAB2_LIB.BASEBOARD_FAB2(SCH_1):PAGE55_I172@CHPSET_LIB.SKX_EXT_B(CHIPS)':
 'DDR345_RCOMP'<1>: CDS_PINID='DDR345_RCOMP(1)';
NET_NAME
'A_CPU1_KLM_RCOMP2'
 '@BASEBOARD_FAB2_LIB.BASEBOARD_FAB2(SCH_1):A_CPU1_KLM_RCOMP2':
 C_SIGNAL='@baseboard_fab2_lib.baseboard_fab2(sch_1):a_cpu1_klm_rcomp2';
NODE_NAME     R3D3 1
 '@BASEBOARD_FAB2_LIB.BASEBOARD_FAB2(SCH_1):PAGE55_I118@MSTR_DISCRETE.RES(CHIPS)':
 'A': CDS_PINID='A';
NODE_NAME     U2D1 DD49
 '@BASEBOARD_FAB2_LIB.BASEBOARD_FAB2(SCH_1):PAGE55_I172@CHPSET_LIB.SKX_EXT_B(CHIPS)':
 'DDR345_RCOMP'<2>: CDS_PINID='DDR345_RCOMP(2)';
NET_NAME
'A_CPU1_MCP01_RBIAS'
 '@BASEBOARD_FAB2_LIB.BASEBOARD_FAB2(SCH_1):A_CPU1_MCP01_RBIAS':
 C_SIGNAL='@baseboard_fab2_lib.baseboard_fab2(sch_1):a_cpu1_mcp01_rbias';
NODE_NAME     R3D4 1
 '@BASEBOARD_FAB2_LIB.BASEBOARD_FAB2(SCH_1):PAGE55_I155@MSTR_DISCRETE.RES(CHIPS)':
 'A': CDS_PINID='A';
NODE_NAME     U2D1 CU32
 '@BASEBOARD_FAB2_LIB.BASEBOARD_FAB2(SCH_1):PAGE55_I172@CHPSET_LIB.SKX_EXT_B(CHIPS)':
 'MCP01_RBIAS'<0>: CDS_PINID='MCP01_RBIAS(0)';
NODE_NAME     U2D1 CT31
 '@BASEBOARD_FAB2_LIB.BASEBOARD_FAB2(SCH_1):PAGE55_I172@CHPSET_LIB.SKX_EXT_B(CHIPS)':
 'MCP01_RBIAS'<1>: CDS_PINID='MCP01_RBIAS(1)';
NET_NAME
'A_CPU1_PE012_RBIAS'
 '@BASEBOARD_FAB2_LIB.BASEBOARD_FAB2(SCH_1):A_CPU1_PE012_RBIAS':
 C_SIGNAL='@baseboard_fab2_lib.baseboard_fab2(sch_1):a_cpu1_pe012_rbias';
NODE_NAME     R7P10 1
 '@BASEBOARD_FAB2_LIB.BASEBOARD_FAB2(SCH_1):PAGE55_I124@MSTR_DISCRETE.RES(CHIPS)':
 'A': CDS_PINID='A';
NODE_NAME     U2D1 CN30
 '@BASEBOARD_FAB2_LIB.BASEBOARD_FAB2(SCH_1):PAGE55_I172@CHPSET_LIB.SKX_EXT_B(CHIPS)':
 'PE012_RBIAS'<0>: CDS_PINID='PE012_RBIAS(0)';
NODE_NAME     U2D1 CL30
 '@BASEBOARD_FAB2_LIB.BASEBOARD_FAB2(SCH_1):PAGE55_I172@CHPSET_LIB.SKX_EXT_B(CHIPS)':
 'PE012_RBIAS'<1>: CDS_PINID='PE012_RBIAS(1)';
NET_NAME
'A_CPU1_PE3_RBIAS'
 '@BASEBOARD_FAB2_LIB.BASEBOARD_FAB2(SCH_1):A_CPU1_PE3_RBIAS':
 C_SIGNAL='@baseboard_fab2_lib.baseboard_fab2(sch_1):a_cpu1_pe3_rbias';
NODE_NAME     R7P8 1
 '@BASEBOARD_FAB2_LIB.BASEBOARD_FAB2(SCH_1):PAGE55_I123@MSTR_DISCRETE.RES(CHIPS)':
 'A': CDS_PINID='A';
NODE_NAME     U2D1 CP29
 '@BASEBOARD_FAB2_LIB.BASEBOARD_FAB2(SCH_1):PAGE55_I172@CHPSET_LIB.SKX_EXT_B(CHIPS)':
 'PE3_RBIAS'<0>: CDS_PINID='PE3_RBIAS(0)';
NODE_NAME     U2D1 CR30
 '@BASEBOARD_FAB2_LIB.BASEBOARD_FAB2(SCH_1):PAGE55_I172@CHPSET_LIB.SKX_EXT_B(CHIPS)':
 'PE3_RBIAS'<1>: CDS_PINID='PE3_RBIAS(1)';
NET_NAME
'A_CPU1_UPI01_RBIAS'
 '@BASEBOARD_FAB2_LIB.BASEBOARD_FAB2(SCH_1):A_CPU1_UPI01_RBIAS':
 C_SIGNAL='@baseboard_fab2_lib.baseboard_fab2(sch_1):a_cpu1_upi01_rbias';
NODE_NAME     R3D19 1
 '@BASEBOARD_FAB2_LIB.BASEBOARD_FAB2(SCH_1):PAGE55_I125@MSTR_DISCRETE.RES(CHIPS)':
 'A': CDS_PINID='A';
NODE_NAME     U2D1 AT29
 '@BASEBOARD_FAB2_LIB.BASEBOARD_FAB2(SCH_1):PAGE55_I172@CHPSET_LIB.SKX_EXT_B(CHIPS)':
 'UPI01_RBIAS'<0>: CDS_PINID='UPI01_RBIAS(0)';
NODE_NAME     U2D1 AP29
 '@BASEBOARD_FAB2_LIB.BASEBOARD_FAB2(SCH_1):PAGE55_I172@CHPSET_LIB.SKX_EXT_B(CHIPS)':
 'UPI01_RBIAS'<1>: CDS_PINID='UPI01_RBIAS(1)';
NET_NAME
'A_CPU1_UPI2_RBIAS'
 '@BASEBOARD_FAB2_LIB.BASEBOARD_FAB2(SCH_1):A_CPU1_UPI2_RBIAS':
 C_SIGNAL='@baseboard_fab2_lib.baseboard_fab2(sch_1):a_cpu1_upi2_rbias';
NODE_NAME     R7P11 1
 '@BASEBOARD_FAB2_LIB.BASEBOARD_FAB2(SCH_1):PAGE55_I126@MSTR_DISCRETE.RES(CHIPS)':
 'A': CDS_PINID='A';
NODE_NAME     U2D1 CL28
 '@BASEBOARD_FAB2_LIB.BASEBOARD_FAB2(SCH_1):PAGE55_I172@CHPSET_LIB.SKX_EXT_B(CHIPS)':
 'UPI2_RBIAS'<0>: CDS_PINID='UPI2_RBIAS(0)';
NODE_NAME     U2D1 CK29
 '@BASEBOARD_FAB2_LIB.BASEBOARD_FAB2(SCH_1):PAGE55_I172@CHPSET_LIB.SKX_EXT_B(CHIPS)':
 'UPI2_RBIAS'<1>: CDS_PINID='UPI2_RBIAS(1)';
NET_NAME
'A_CTOP'
 '@BASEBOARD_FAB2_LIB.BASEBOARD_FAB2(SCH_1):A_CTOP':
 C_SIGNAL='@baseboard_fab2_lib.baseboard_fab2(sch_1):a_ctop';
NODE_NAME     EU9E1 40
 '@BASEBOARD_FAB2_LIB.BASEBOARD_FAB2(SCH_1):PAGE139_I72@MSTR_INTEL.SPRINGVILLE(CHIPS)':
 'CTOP': CDS_PINID='CTOP';
NODE_NAME     C9E7 1
 '@BASEBOARD_FAB2_LIB.BASEBOARD_FAB2(SCH_1):PAGE139_I76@MSTR_DISCRETE.CAP(CHIPS)':
 'A': CDS_PINID='A';
NET_NAME
'A_DACRSET'
 '@BASEBOARD_FAB2_LIB.BASEBOARD_FAB2(SCH_1):A_DACRSET':
 C_SIGNAL='@baseboard_fab2_lib.baseboard_fab2(sch_1):a_dacrset';
NODE_NAME     U25W4 K4
 '@BASEBOARD_FAB2_LIB.BASEBOARD_FAB2(SCH_1):PAGE144_I95@W_HDL.AST2520A1-GP-GP(CHIPS)':
 'DACRSET': CDS_PINID='DACRSET';
NODE_NAME     R25W58 1
 '@BASEBOARD_FAB2_LIB.BASEBOARD_FAB2(SCH_1):PAGE144_I150@W_HDL.18KR2F-GP(CHIPS)':
 '1': CDS_PINID='\1\';
NET_NAME
'A_EXTCLKN'
 '@BASEBOARD_FAB2_LIB.BASEBOARD_FAB2(SCH_1):A_EXTCLKN':
 C_SIGNAL='@baseboard_fab2_lib.baseboard_fab2(sch_1):a_extclkn';
NODE_NAME     U7C1 D66
 '@BASEBOARD_FAB2_LIB.BASEBOARD_FAB2(SCH_1):PAGE116_I220@MSTR_U_PROC.LBG_CORE_QAT_EXT_D(CHIPS)':
 'EXTCLKN': CDS_PINID='EXTCLKN';
NODE_NAME     R7B8 1
 '@BASEBOARD_FAB2_LIB.BASEBOARD_FAB2(SCH_1):PAGE116_I229@MSTR_DISCRETE.RES(CHIPS)':
 'A': CDS_PINID='A';
NET_NAME
'A_EXTCLKP'
 '@BASEBOARD_FAB2_LIB.BASEBOARD_FAB2(SCH_1):A_EXTCLKP':
 C_SIGNAL='@baseboard_fab2_lib.baseboard_fab2(sch_1):a_extclkp';
NODE_NAME     U7C1 E67
 '@BASEBOARD_FAB2_LIB.BASEBOARD_FAB2(SCH_1):PAGE116_I220@MSTR_U_PROC.LBG_CORE_QAT_EXT_D(CHIPS)':
 'EXTCLKP': CDS_PINID='EXTCLKP';
NODE_NAME     R7B7 1
 '@BASEBOARD_FAB2_LIB.BASEBOARD_FAB2(SCH_1):PAGE116_I230@MSTR_DISCRETE.RES(CHIPS)':
 'A': CDS_PINID='A';
NET_NAME
'A_HSC_C'
 '@BASEBOARD_FAB2_LIB.BASEBOARD_FAB2(SCH_1):A_HSC_C':
 C_SIGNAL='@baseboard_fab2_lib.baseboard_fab2(sch_1):a_hsc_c';
NODE_NAME     R1D51 1
 '@BASEBOARD_FAB2_LIB.BASEBOARD_FAB2(SCH_1):PAGE200_I154@MSTR_DISCRETE.RES(CHIPS)':
 'A': CDS_PINID='A';
NODE_NAME     C1E2 1
 '@BASEBOARD_FAB2_LIB.BASEBOARD_FAB2(SCH_1):PAGE200_I155@MSTR_DISCRETE.CAP(CHIPS)':
 'A': CDS_PINID='A';
NET_NAME
'A_HSC_CSOUT'
 '@BASEBOARD_FAB2_LIB.BASEBOARD_FAB2(SCH_1):A_HSC_CSOUT':
 C_SIGNAL='@baseboard_fab2_lib.baseboard_fab2(sch_1):a_hsc_csout';
NODE_NAME     EU1D2 19
 '@BASEBOARD_FAB2_LIB.BASEBOARD_FAB2(SCH_1):PAGE199_I10@MSTR_CONTROLLER.ADM1278(CHIPS)':
 'CSOUT': CDS_PINID='CSOUT';
NODE_NAME     R1D14 1
 '@BASEBOARD_FAB2_LIB.BASEBOARD_FAB2(SCH_1):PAGE200_I246@MSTR_DISCRETE.RES(CHIPS)':
 'A': CDS_PINID='A';
NODE_NAME     R1D20 1
 '@BASEBOARD_FAB2_LIB.BASEBOARD_FAB2(SCH_1):PAGE200_I253@MSTR_DISCRETE.RES(CHIPS)':
 'A': CDS_PINID='A';
NET_NAME
'A_HSC_GATE'
 '@BASEBOARD_FAB2_LIB.BASEBOARD_FAB2(SCH_1):A_HSC_GATE':
 C_SIGNAL='@baseboard_fab2_lib.baseboard_fab2(sch_1):a_hsc_gate';
NODE_NAME     EU1D2 24
 '@BASEBOARD_FAB2_LIB.BASEBOARD_FAB2(SCH_1):PAGE199_I10@MSTR_CONTROLLER.ADM1278(CHIPS)':
 'GATE': CDS_PINID='GATE';
NODE_NAME     R1E1 1
 '@BASEBOARD_FAB2_LIB.BASEBOARD_FAB2(SCH_1):PAGE200_I56@MSTR_DISCRETE.RES(CHIPS)':
 'A': CDS_PINID='A';
NODE_NAME     R9R4 1
 '@BASEBOARD_FAB2_LIB.BASEBOARD_FAB2(SCH_1):PAGE200_I58@MSTR_DISCRETE.RES(CHIPS)':
 'A': CDS_PINID='A';
NODE_NAME     R1D48 1
 '@BASEBOARD_FAB2_LIB.BASEBOARD_FAB2(SCH_1):PAGE200_I60@MSTR_DISCRETE.RES(CHIPS)':
 'A': CDS_PINID='A';
NODE_NAME     R1D51 2
 '@BASEBOARD_FAB2_LIB.BASEBOARD_FAB2(SCH_1):PAGE200_I154@MSTR_DISCRETE.RES(CHIPS)':
 'B': CDS_PINID='B';
NET_NAME
'A_HSC_GATE1_R'
 '@BASEBOARD_FAB2_LIB.BASEBOARD_FAB2(SCH_1):A_HSC_GATE1_R':
 C_SIGNAL='@baseboard_fab2_lib.baseboard_fab2(sch_1):a_hsc_gate1_r';
NODE_NAME     EU1E3 4
 '@BASEBOARD_FAB2_LIB.BASEBOARD_FAB2(SCH_1):PAGE200_I54@MSTR_DISCRETE.MOSFETN_1D3S(CHIPS)':
 'G': CDS_PINID='G';
NODE_NAME     R1E1 2
 '@BASEBOARD_FAB2_LIB.BASEBOARD_FAB2(SCH_1):PAGE200_I56@MSTR_DISCRETE.RES(CHIPS)':
 'B': CDS_PINID='B';
NET_NAME
'A_HSC_GATE2_R'
 '@BASEBOARD_FAB2_LIB.BASEBOARD_FAB2(SCH_1):A_HSC_GATE2_R':
 C_SIGNAL='@baseboard_fab2_lib.baseboard_fab2(sch_1):a_hsc_gate2_r';
NODE_NAME     EU9R1 4
 '@BASEBOARD_FAB2_LIB.BASEBOARD_FAB2(SCH_1):PAGE200_I57@MSTR_DISCRETE.MOSFETN_1D3S(CHIPS)':
 'G': CDS_PINID='G';
NODE_NAME     R9R4 2
 '@BASEBOARD_FAB2_LIB.BASEBOARD_FAB2(SCH_1):PAGE200_I58@MSTR_DISCRETE.RES(CHIPS)':
 'B': CDS_PINID='B';
NET_NAME
'A_HSC_GATE3_R'
 '@BASEBOARD_FAB2_LIB.BASEBOARD_FAB2(SCH_1):A_HSC_GATE3_R':
 C_SIGNAL='@baseboard_fab2_lib.baseboard_fab2(sch_1):a_hsc_gate3_r';
NODE_NAME     EU1E1 4
 '@BASEBOARD_FAB2_LIB.BASEBOARD_FAB2(SCH_1):PAGE200_I59@MSTR_DISCRETE.MOSFETN_1D3S(CHIPS)':
 'G': CDS_PINID='G';
NODE_NAME     R1D48 2
 '@BASEBOARD_FAB2_LIB.BASEBOARD_FAB2(SCH_1):PAGE200_I60@MSTR_DISCRETE.RES(CHIPS)':
 'B': CDS_PINID='B';
NET_NAME
'A_HSC_HIGH'
 '@BASEBOARD_FAB2_LIB.BASEBOARD_FAB2(SCH_1):A_HSC_HIGH':
 C_SIGNAL='@baseboard_fab2_lib.baseboard_fab2(sch_1):a_hsc_high';
NODE_NAME     U1D2 3
 '@BASEBOARD_FAB2_LIB.BASEBOARD_FAB2(SCH_1):PAGE200_I170@MSTR_VREG.TPS3700(CHIPS)':
 'INBN': CDS_PINID='INBN';
NODE_NAME     R1D19 1
 '@BASEBOARD_FAB2_LIB.BASEBOARD_FAB2(SCH_1):PAGE200_I175@MSTR_DISCRETE.RES(CHIPS)':
 'A': CDS_PINID='A';
NODE_NAME     R1D20 2
 '@BASEBOARD_FAB2_LIB.BASEBOARD_FAB2(SCH_1):PAGE200_I253@MSTR_DISCRETE.RES(CHIPS)':
 'B': CDS_PINID='B';
NET_NAME
'A_HSC_HIGH_EN'
 '@BASEBOARD_FAB2_LIB.BASEBOARD_FAB2(SCH_1):A_HSC_HIGH_EN':
 C_SIGNAL='@baseboard_fab2_lib.baseboard_fab2(sch_1):a_hsc_high_en';
NODE_NAME     Q1D1 5
 '@BASEBOARD_FAB2_LIB.BASEBOARD_FAB2(SCH_1):PAGE199_I82@MSTR_DISCRETE.FET_N_DUAL(CHIPS)':
 'GATE'<0>: CDS_PINID='GATE(0)';
NODE_NAME     R1D18 1
 '@BASEBOARD_FAB2_LIB.BASEBOARD_FAB2(SCH_1):PAGE199_I87@MSTR_DISCRETE.RES(CHIPS)':
 'A': CDS_PINID='A';
NODE_NAME     Q1W5 1
 '@BASEBOARD_FAB2_LIB.BASEBOARD_FAB2(SCH_1):PAGE199_I130@MSTR_DISCRETE.FET_N(CHIPS)':
 'GATE': CDS_PINID='GATE';
NODE_NAME     J1B4 1
 '@BASEBOARD_FAB2_LIB.BASEBOARD_FAB2(SCH_1):PAGE199_I131@W_HDL.CLX-CONN3A-1-GP(CHIPS)':
 '1': CDS_PINID='\1\';
NET_NAME
'A_HSC_HSN'
 '@BASEBOARD_FAB2_LIB.BASEBOARD_FAB2(SCH_1):A_HSC_HSN':
 C_SIGNAL='@baseboard_fab2_lib.baseboard_fab2(sch_1):a_hsc_hsn';
NODE_NAME     EU1D2 27
 '@BASEBOARD_FAB2_LIB.BASEBOARD_FAB2(SCH_1):PAGE199_I10@MSTR_CONTROLLER.ADM1278(CHIPS)':
 'HSN': CDS_PINID='HSN';
NODE_NAME     R1D45 2
 '@BASEBOARD_FAB2_LIB.BASEBOARD_FAB2(SCH_1):PAGE200_I43@MSTR_DISCRETE.RES(CHIPS)':
 'B': CDS_PINID='B';
NODE_NAME     R9P26 2
 '@BASEBOARD_FAB2_LIB.BASEBOARD_FAB2(SCH_1):PAGE200_I51@MSTR_DISCRETE.RES(CHIPS)':
 'B': CDS_PINID='B';
NODE_NAME     R1D47 2
 '@BASEBOARD_FAB2_LIB.BASEBOARD_FAB2(SCH_1):PAGE200_I52@MSTR_DISCRETE.RES(CHIPS)':
 'B': CDS_PINID='B';
NET_NAME
'A_HSC_HSP'
 '@BASEBOARD_FAB2_LIB.BASEBOARD_FAB2(SCH_1):A_HSC_HSP':
 C_SIGNAL='@baseboard_fab2_lib.baseboard_fab2(sch_1):a_hsc_hsp';
NODE_NAME     EU1D2 28
 '@BASEBOARD_FAB2_LIB.BASEBOARD_FAB2(SCH_1):PAGE199_I10@MSTR_CONTROLLER.ADM1278(CHIPS)':
 'HSP': CDS_PINID='HSP';
NODE_NAME     R1D44 2
 '@BASEBOARD_FAB2_LIB.BASEBOARD_FAB2(SCH_1):PAGE200_I44@MSTR_DISCRETE.RES(CHIPS)':
 'B': CDS_PINID='B';
NODE_NAME     R9P27 2
 '@BASEBOARD_FAB2_LIB.BASEBOARD_FAB2(SCH_1):PAGE200_I47@MSTR_DISCRETE.RES(CHIPS)':
 'B': CDS_PINID='B';
NODE_NAME     R1D46 2
 '@BASEBOARD_FAB2_LIB.BASEBOARD_FAB2(SCH_1):PAGE200_I48@MSTR_DISCRETE.RES(CHIPS)':
 'B': CDS_PINID='B';
NET_NAME
'A_HSC_INAP'
 '@BASEBOARD_FAB2_LIB.BASEBOARD_FAB2(SCH_1):A_HSC_INAP':
 C_SIGNAL='@baseboard_fab2_lib.baseboard_fab2(sch_1):a_hsc_inap';
NODE_NAME     U9P2 4
 '@BASEBOARD_FAB2_LIB.BASEBOARD_FAB2(SCH_1):PAGE200_I200@MSTR_VREG.TPS3700(CHIPS)':
 'INAP': CDS_PINID='INAP';
NODE_NAME     R9P12 1
 '@BASEBOARD_FAB2_LIB.BASEBOARD_FAB2(SCH_1):PAGE200_I218@MSTR_DISCRETE.RES(CHIPS)':
 'A': CDS_PINID='A';
NODE_NAME     R9P33 2
 '@BASEBOARD_FAB2_LIB.BASEBOARD_FAB2(SCH_1):PAGE200_I222@MSTR_DISCRETE.RES(CHIPS)':
 'B': CDS_PINID='B';
NET_NAME
'A_HSC_ISET'
 '@BASEBOARD_FAB2_LIB.BASEBOARD_FAB2(SCH_1):A_HSC_ISET':
 C_SIGNAL='@baseboard_fab2_lib.baseboard_fab2(sch_1):a_hsc_iset';
NODE_NAME     EU1D2 3
 '@BASEBOARD_FAB2_LIB.BASEBOARD_FAB2(SCH_1):PAGE199_I10@MSTR_CONTROLLER.ADM1278(CHIPS)':
 'ISET': CDS_PINID='ISET';
NODE_NAME     R1D37 2
 '@BASEBOARD_FAB2_LIB.BASEBOARD_FAB2(SCH_1):PAGE199_I15@MSTR_DISCRETE.RES(CHIPS)':
 'B': CDS_PINID='B';
NODE_NAME     R1D13 2
 '@BASEBOARD_FAB2_LIB.BASEBOARD_FAB2(SCH_1):PAGE199_I84@MSTR_DISCRETE.RES(CHIPS)':
 'B': CDS_PINID='B';
NODE_NAME     R1D16 1
 '@BASEBOARD_FAB2_LIB.BASEBOARD_FAB2(SCH_1):PAGE199_I85@MSTR_DISCRETE.RES(CHIPS)':
 'A': CDS_PINID='A';
NODE_NAME     C9P15 1
 '@BASEBOARD_FAB2_LIB.BASEBOARD_FAB2(SCH_1):PAGE199_I105@DEV_DISCRETE.CAP_A(CHIPS)':
 'A': CDS_PINID='A';
NET_NAME
'A_HSC_ISET_S'
 '@BASEBOARD_FAB2_LIB.BASEBOARD_FAB2(SCH_1):A_HSC_ISET_S':
 C_SIGNAL='@baseboard_fab2_lib.baseboard_fab2(sch_1):a_hsc_iset_s';
NODE_NAME     Q1D1 3
 '@BASEBOARD_FAB2_LIB.BASEBOARD_FAB2(SCH_1):PAGE199_I82@MSTR_DISCRETE.FET_N_DUAL(CHIPS)':
 'DRAIN'<0>: CDS_PINID='DRAIN(0)';
NODE_NAME     R1D13 1
 '@BASEBOARD_FAB2_LIB.BASEBOARD_FAB2(SCH_1):PAGE199_I84@MSTR_DISCRETE.RES(CHIPS)':
 'A': CDS_PINID='A';
NET_NAME
'A_HSC_ISET_S2'
 '@BASEBOARD_FAB2_LIB.BASEBOARD_FAB2(SCH_1):A_HSC_ISET_S2':
 C_SIGNAL='@baseboard_fab2_lib.baseboard_fab2(sch_1):a_hsc_iset_s2';
NODE_NAME     R1D16 2
 '@BASEBOARD_FAB2_LIB.BASEBOARD_FAB2(SCH_1):PAGE199_I85@MSTR_DISCRETE.RES(CHIPS)':
 'B': CDS_PINID='B';
NODE_NAME     Q1D1 6
 '@BASEBOARD_FAB2_LIB.BASEBOARD_FAB2(SCH_1):PAGE199_I86@MSTR_DISCRETE.FET_N_DUAL(CHIPS)':
 'DRAIN'<0>: CDS_PINID='DRAIN(0)';
NET_NAME
'A_HSC_ISTART'
 '@BASEBOARD_FAB2_LIB.BASEBOARD_FAB2(SCH_1):A_HSC_ISTART':
 C_SIGNAL='@baseboard_fab2_lib.baseboard_fab2(sch_1):a_hsc_istart';
NODE_NAME     EU1D2 4
 '@BASEBOARD_FAB2_LIB.BASEBOARD_FAB2(SCH_1):PAGE199_I10@MSTR_CONTROLLER.ADM1278(CHIPS)':
 'ISTART': CDS_PINID='ISTART';
NODE_NAME     R1D32 2
 '@BASEBOARD_FAB2_LIB.BASEBOARD_FAB2(SCH_1):PAGE199_I17@MSTR_DISCRETE.RES(CHIPS)':
 'B': CDS_PINID='B';
NODE_NAME     R1D34 1
 '@BASEBOARD_FAB2_LIB.BASEBOARD_FAB2(SCH_1):PAGE199_I102@MSTR_DISCRETE.RES(CHIPS)':
 'A': CDS_PINID='A';
NET_NAME
'A_HSC_LOW'
 '@BASEBOARD_FAB2_LIB.BASEBOARD_FAB2(SCH_1):A_HSC_LOW':
 C_SIGNAL='@baseboard_fab2_lib.baseboard_fab2(sch_1):a_hsc_low';
NODE_NAME     U1D2 4
 '@BASEBOARD_FAB2_LIB.BASEBOARD_FAB2(SCH_1):PAGE200_I170@MSTR_VREG.TPS3700(CHIPS)':
 'INAP': CDS_PINID='INAP';
NODE_NAME     R1D12 1
 '@BASEBOARD_FAB2_LIB.BASEBOARD_FAB2(SCH_1):PAGE200_I174@MSTR_DISCRETE.RES(CHIPS)':
 'A': CDS_PINID='A';
NODE_NAME     R1D14 2
 '@BASEBOARD_FAB2_LIB.BASEBOARD_FAB2(SCH_1):PAGE200_I246@MSTR_DISCRETE.RES(CHIPS)':
 'B': CDS_PINID='B';
NET_NAME
'A_HSC_LOW_DRAIN'
 '@BASEBOARD_FAB2_LIB.BASEBOARD_FAB2(SCH_1):A_HSC_LOW_DRAIN':
 C_SIGNAL='@baseboard_fab2_lib.baseboard_fab2(sch_1):a_hsc_low_drain';
NODE_NAME     Q9P1 6
 '@BASEBOARD_FAB2_LIB.BASEBOARD_FAB2(SCH_1):PAGE200_I196@MSTR_DISCRETE.FET_N_DUAL(CHIPS)':
 'DRAIN'<0>: CDS_PINID='DRAIN(0)';
NODE_NAME     R9P15 1
 '@BASEBOARD_FAB2_LIB.BASEBOARD_FAB2(SCH_1):PAGE200_I243@MSTR_DISCRETE.RES(CHIPS)':
 'A': CDS_PINID='A';
NET_NAME
'A_HSC_LOW_EN'
 '@BASEBOARD_FAB2_LIB.BASEBOARD_FAB2(SCH_1):A_HSC_LOW_EN':
 C_SIGNAL='@baseboard_fab2_lib.baseboard_fab2(sch_1):a_hsc_low_en';
NODE_NAME     Q1D1 2
 '@BASEBOARD_FAB2_LIB.BASEBOARD_FAB2(SCH_1):PAGE199_I86@MSTR_DISCRETE.FET_N_DUAL(CHIPS)':
 'GATE'<0>: CDS_PINID='GATE(0)';
NODE_NAME     R1D11 1
 '@BASEBOARD_FAB2_LIB.BASEBOARD_FAB2(SCH_1):PAGE199_I88@MSTR_DISCRETE.RES(CHIPS)':
 'A': CDS_PINID='A';
NODE_NAME     J1B4 3
 '@BASEBOARD_FAB2_LIB.BASEBOARD_FAB2(SCH_1):PAGE199_I131@W_HDL.CLX-CONN3A-1-GP(CHIPS)':
 '3': CDS_PINID='\3\';
NET_NAME
'A_HSC_LOW_GATE'
 '@BASEBOARD_FAB2_LIB.BASEBOARD_FAB2(SCH_1):A_HSC_LOW_GATE':
 C_SIGNAL='@baseboard_fab2_lib.baseboard_fab2(sch_1):a_hsc_low_gate';
NODE_NAME     U1D2 6
 '@BASEBOARD_FAB2_LIB.BASEBOARD_FAB2(SCH_1):PAGE200_I170@MSTR_VREG.TPS3700(CHIPS)':
 'OUTA': CDS_PINID='OUTA';
NODE_NAME     Q9P1 2
 '@BASEBOARD_FAB2_LIB.BASEBOARD_FAB2(SCH_1):PAGE200_I196@MSTR_DISCRETE.FET_N_DUAL(CHIPS)':
 'GATE'<0>: CDS_PINID='GATE(0)';
NODE_NAME     R1D10 2
 '@BASEBOARD_FAB2_LIB.BASEBOARD_FAB2(SCH_1):PAGE200_I244@MSTR_DISCRETE.RES(CHIPS)':
 'B': CDS_PINID='B';
NODE_NAME     Q1W5 3
 '@BASEBOARD_FAB2_LIB.BASEBOARD_FAB2(SCH_1):PAGE199_I130@MSTR_DISCRETE.FET_N(CHIPS)':
 'DRN': CDS_PINID='DRN';
NET_NAME
'A_HSC_MON'
 '@BASEBOARD_FAB2_LIB.BASEBOARD_FAB2(SCH_1):A_HSC_MON':
 C_SIGNAL='@baseboard_fab2_lib.baseboard_fab2(sch_1):a_hsc_mon';
NODE_NAME     EU1D2 26
 '@BASEBOARD_FAB2_LIB.BASEBOARD_FAB2(SCH_1):PAGE199_I10@MSTR_CONTROLLER.ADM1278(CHIPS)':
 'MON': CDS_PINID='MON';
NODE_NAME     C9P17 1
 '@BASEBOARD_FAB2_LIB.BASEBOARD_FAB2(SCH_1):PAGE200_I36@DEV_DISCRETE.CAP_A(CHIPS)':
 'A': CDS_PINID='A';
NODE_NAME     C1D22 1
 '@BASEBOARD_FAB2_LIB.BASEBOARD_FAB2(SCH_1):PAGE200_I42@DEV_DISCRETE.CAP_A(CHIPS)':
 'A': CDS_PINID='A';
NODE_NAME     R1D45 1
 '@BASEBOARD_FAB2_LIB.BASEBOARD_FAB2(SCH_1):PAGE200_I43@MSTR_DISCRETE.RES(CHIPS)':
 'A': CDS_PINID='A';
NET_NAME
'A_HSC_MOP'
 '@BASEBOARD_FAB2_LIB.BASEBOARD_FAB2(SCH_1):A_HSC_MOP':
 C_SIGNAL='@baseboard_fab2_lib.baseboard_fab2(sch_1):a_hsc_mop';
NODE_NAME     EU1D2 29
 '@BASEBOARD_FAB2_LIB.BASEBOARD_FAB2(SCH_1):PAGE199_I10@MSTR_CONTROLLER.ADM1278(CHIPS)':
 'MOP': CDS_PINID='MOP';
NODE_NAME     C9P16 1
 '@BASEBOARD_FAB2_LIB.BASEBOARD_FAB2(SCH_1):PAGE200_I40@DEV_DISCRETE.CAP_A(CHIPS)':
 'A': CDS_PINID='A';
NODE_NAME     C1D22 2
 '@BASEBOARD_FAB2_LIB.BASEBOARD_FAB2(SCH_1):PAGE200_I42@DEV_DISCRETE.CAP_A(CHIPS)':
 'B': CDS_PINID='B';
NODE_NAME     R1D44 1
 '@BASEBOARD_FAB2_LIB.BASEBOARD_FAB2(SCH_1):PAGE200_I44@MSTR_DISCRETE.RES(CHIPS)':
 'A': CDS_PINID='A';
NET_NAME
'A_HSC_OCP_SEL'
 '@BASEBOARD_FAB2_LIB.BASEBOARD_FAB2(SCH_1):A_HSC_OCP_SEL':
 C_SIGNAL='@baseboard_fab2_lib.baseboard_fab2(sch_1):a_hsc_ocp_sel';
NODE_NAME     R1D15 2
 '@BASEBOARD_FAB2_LIB.BASEBOARD_FAB2(SCH_1):PAGE199_I92@MSTR_DISCRETE.RES(CHIPS)':
 'B': CDS_PINID='B';
NODE_NAME     J1B4 2
 '@BASEBOARD_FAB2_LIB.BASEBOARD_FAB2(SCH_1):PAGE199_I131@W_HDL.CLX-CONN3A-1-GP(CHIPS)':
 '2': CDS_PINID='\2\';
NET_NAME
'A_HSC_OV'
 '@BASEBOARD_FAB2_LIB.BASEBOARD_FAB2(SCH_1):A_HSC_OV':
 C_SIGNAL='@baseboard_fab2_lib.baseboard_fab2(sch_1):a_hsc_ov';
NODE_NAME     C1D27 1
 '@BASEBOARD_FAB2_LIB.BASEBOARD_FAB2(SCH_1):PAGE199_I7@DEV_DISCRETE.CAP_A(CHIPS)':
 'A': CDS_PINID='A';
NODE_NAME     R1D43 1
 '@BASEBOARD_FAB2_LIB.BASEBOARD_FAB2(SCH_1):PAGE199_I9@MSTR_DISCRETE.RES(CHIPS)':
 'A': CDS_PINID='A';
NODE_NAME     EU1D2 32
 '@BASEBOARD_FAB2_LIB.BASEBOARD_FAB2(SCH_1):PAGE199_I10@MSTR_CONTROLLER.ADM1278(CHIPS)':
 'OV': CDS_PINID='OV';
NODE_NAME     R9P28 2
 '@BASEBOARD_FAB2_LIB.BASEBOARD_FAB2(SCH_1):PAGE199_I138@MSTR_DISCRETE.RES(CHIPS)':
 'B': CDS_PINID='B';
NET_NAME
'A_HSC_PSET'
 '@BASEBOARD_FAB2_LIB.BASEBOARD_FAB2(SCH_1):A_HSC_PSET':
 C_SIGNAL='@baseboard_fab2_lib.baseboard_fab2(sch_1):a_hsc_pset';
NODE_NAME     EU1D2 1
 '@BASEBOARD_FAB2_LIB.BASEBOARD_FAB2(SCH_1):PAGE199_I10@MSTR_CONTROLLER.ADM1278(CHIPS)':
 'PSET': CDS_PINID='PSET';
NODE_NAME     R1D39 2
 '@BASEBOARD_FAB2_LIB.BASEBOARD_FAB2(SCH_1):PAGE199_I16@MSTR_DISCRETE.RES(CHIPS)':
 'B': CDS_PINID='B';
NODE_NAME     R1D40 1
 '@BASEBOARD_FAB2_LIB.BASEBOARD_FAB2(SCH_1):PAGE199_I100@MSTR_DISCRETE.RES(CHIPS)':
 'A': CDS_PINID='A';
NODE_NAME     C1D21 1
 '@BASEBOARD_FAB2_LIB.BASEBOARD_FAB2(SCH_1):PAGE199_I121@DEV_DISCRETE.CAP_A(CHIPS)':
 'A': CDS_PINID='A';
NET_NAME
'A_HSC_PWGIN'
 '@BASEBOARD_FAB2_LIB.BASEBOARD_FAB2(SCH_1):A_HSC_PWGIN':
 C_SIGNAL='@baseboard_fab2_lib.baseboard_fab2(sch_1):a_hsc_pwgin';
NODE_NAME     EU1D2 21
 '@BASEBOARD_FAB2_LIB.BASEBOARD_FAB2(SCH_1):PAGE199_I10@MSTR_CONTROLLER.ADM1278(CHIPS)':
 'PWGIN': CDS_PINID='PWGIN';
NODE_NAME     R9P23 2
 '@BASEBOARD_FAB2_LIB.BASEBOARD_FAB2(SCH_1):PAGE199_I54@MSTR_DISCRETE.RES(CHIPS)':
 'B': CDS_PINID='B';
NODE_NAME     R9P24 1
 '@BASEBOARD_FAB2_LIB.BASEBOARD_FAB2(SCH_1):PAGE199_I55@MSTR_DISCRETE.RES(CHIPS)':
 'A': CDS_PINID='A';
NET_NAME
'A_HSC_TEMP'
 '@BASEBOARD_FAB2_LIB.BASEBOARD_FAB2(SCH_1):A_HSC_TEMP':
 C_SIGNAL='@baseboard_fab2_lib.baseboard_fab2(sch_1):a_hsc_temp';
NODE_NAME     EU1D2 25
 '@BASEBOARD_FAB2_LIB.BASEBOARD_FAB2(SCH_1):PAGE199_I10@MSTR_CONTROLLER.ADM1278(CHIPS)':
 'TEMP': CDS_PINID='TEMP';
NODE_NAME     C1W16 1
 '@BASEBOARD_FAB2_LIB.BASEBOARD_FAB2(SCH_1):PAGE199_I132@MSTR_DISCRETE.CAP(CHIPS)':
 'A': CDS_PINID='A';
NODE_NAME     R1W20 1
 '@BASEBOARD_FAB2_LIB.BASEBOARD_FAB2(SCH_1):PAGE199_I134@MSTR_DISCRETE.RES(CHIPS)':
 'A': CDS_PINID='A';
NET_NAME
'A_HSC_TIMER'
 '@BASEBOARD_FAB2_LIB.BASEBOARD_FAB2(SCH_1):A_HSC_TIMER':
 C_SIGNAL='@baseboard_fab2_lib.baseboard_fab2(sch_1):a_hsc_timer';
NODE_NAME     EU1D2 5
 '@BASEBOARD_FAB2_LIB.BASEBOARD_FAB2(SCH_1):PAGE199_I10@MSTR_CONTROLLER.ADM1278(CHIPS)':
 'TIMER': CDS_PINID='TIMER';
NODE_NAME     C9P14 1
 '@BASEBOARD_FAB2_LIB.BASEBOARD_FAB2(SCH_1):PAGE199_I24@MSTR_DISCRETE.CAP(CHIPS)':
 'A': CDS_PINID='A';
NODE_NAME     R9P21 1
 '@BASEBOARD_FAB2_LIB.BASEBOARD_FAB2(SCH_1):PAGE200_I71@MSTR_DISCRETE.RES(CHIPS)':
 'A': CDS_PINID='A';
NET_NAME
'A_HSC_TIMER_R'
 '@BASEBOARD_FAB2_LIB.BASEBOARD_FAB2(SCH_1):A_HSC_TIMER_R':
 C_SIGNAL='@baseboard_fab2_lib.baseboard_fab2(sch_1):a_hsc_timer_r';
NODE_NAME     R9P19 1
 '@BASEBOARD_FAB2_LIB.BASEBOARD_FAB2(SCH_1):PAGE200_I70@MSTR_DISCRETE.RES(CHIPS)':
 'A': CDS_PINID='A';
NODE_NAME     R9P21 2
 '@BASEBOARD_FAB2_LIB.BASEBOARD_FAB2(SCH_1):PAGE200_I71@MSTR_DISCRETE.RES(CHIPS)':
 'B': CDS_PINID='B';
NODE_NAME     U9P2 3
 '@BASEBOARD_FAB2_LIB.BASEBOARD_FAB2(SCH_1):PAGE200_I200@MSTR_VREG.TPS3700(CHIPS)':
 'INBN': CDS_PINID='INBN';
NET_NAME
'A_HSC_UV'
 '@BASEBOARD_FAB2_LIB.BASEBOARD_FAB2(SCH_1):A_HSC_UV':
 C_SIGNAL='@baseboard_fab2_lib.baseboard_fab2(sch_1):a_hsc_uv';
NODE_NAME     EU1D2 31
 '@BASEBOARD_FAB2_LIB.BASEBOARD_FAB2(SCH_1):PAGE199_I10@MSTR_CONTROLLER.ADM1278(CHIPS)':
 'UV': CDS_PINID='UV';
NODE_NAME     R9P29 2
 '@BASEBOARD_FAB2_LIB.BASEBOARD_FAB2(SCH_1):PAGE199_I12@MSTR_DISCRETE.RES(CHIPS)':
 'B': CDS_PINID='B';
NODE_NAME     R1D42 1
 '@BASEBOARD_FAB2_LIB.BASEBOARD_FAB2(SCH_1):PAGE199_I13@MSTR_DISCRETE.RES(CHIPS)':
 'A': CDS_PINID='A';
NODE_NAME     C1D26 1
 '@BASEBOARD_FAB2_LIB.BASEBOARD_FAB2(SCH_1):PAGE199_I107@DEV_DISCRETE.CAP_A(CHIPS)':
 'A': CDS_PINID='A';
NET_NAME
'A_HSC_VCAP'
 '@BASEBOARD_FAB2_LIB.BASEBOARD_FAB2(SCH_1):A_HSC_VCAP':
 C_SIGNAL='@baseboard_fab2_lib.baseboard_fab2(sch_1):a_hsc_vcap';
NODE_NAME     EU1D2 2
 '@BASEBOARD_FAB2_LIB.BASEBOARD_FAB2(SCH_1):PAGE199_I10@MSTR_CONTROLLER.ADM1278(CHIPS)':
 'VCAP': CDS_PINID='VCAP';
NODE_NAME     R1D37 1
 '@BASEBOARD_FAB2_LIB.BASEBOARD_FAB2(SCH_1):PAGE199_I15@MSTR_DISCRETE.RES(CHIPS)':
 'A': CDS_PINID='A';
NODE_NAME     R1D39 1
 '@BASEBOARD_FAB2_LIB.BASEBOARD_FAB2(SCH_1):PAGE199_I16@MSTR_DISCRETE.RES(CHIPS)':
 'A': CDS_PINID='A';
NODE_NAME     R1D32 1
 '@BASEBOARD_FAB2_LIB.BASEBOARD_FAB2(SCH_1):PAGE199_I17@MSTR_DISCRETE.RES(CHIPS)':
 'A': CDS_PINID='A';
NODE_NAME     R1D27 1
 '@BASEBOARD_FAB2_LIB.BASEBOARD_FAB2(SCH_1):PAGE199_I38@MSTR_DISCRETE.RES(CHIPS)':
 'A': CDS_PINID='A';
NODE_NAME     C1D19 1
 '@BASEBOARD_FAB2_LIB.BASEBOARD_FAB2(SCH_1):PAGE199_I119@MSTR_DISCRETE.CAP(CHIPS)':
 'A': CDS_PINID='A';
NODE_NAME     R1D29 1
 '@BASEBOARD_FAB2_LIB.BASEBOARD_FAB2(SCH_1):PAGE199_I137@MSTR_DISCRETE.RES(CHIPS)':
 'A': CDS_PINID='A';
NET_NAME
'A_HSC_VOUT'
 '@BASEBOARD_FAB2_LIB.BASEBOARD_FAB2(SCH_1):A_HSC_VOUT':
 C_SIGNAL='@baseboard_fab2_lib.baseboard_fab2(sch_1):a_hsc_vout';
NODE_NAME     EU1D2 20
 '@BASEBOARD_FAB2_LIB.BASEBOARD_FAB2(SCH_1):PAGE199_I10@MSTR_CONTROLLER.ADM1278(CHIPS)':
 'VOUT': CDS_PINID='VOUT';
NODE_NAME     R1D36 2
 '@BASEBOARD_FAB2_LIB.BASEBOARD_FAB2(SCH_1):PAGE199_I65@MSTR_DISCRETE.RES(CHIPS)':
 'B': CDS_PINID='B';
NODE_NAME     C9P12 1
 '@BASEBOARD_FAB2_LIB.BASEBOARD_FAB2(SCH_1):PAGE199_I67@DEV_DISCRETE.CAP_A(CHIPS)':
 'A': CDS_PINID='A';
NET_NAME
'A_KR0_RBIAS'
 '@BASEBOARD_FAB2_LIB.BASEBOARD_FAB2(SCH_1):A_KR0_RBIAS':
 C_SIGNAL='@baseboard_fab2_lib.baseboard_fab2(sch_1):a_kr0_rbias';
NODE_NAME     U7C1 BB29
 '@BASEBOARD_FAB2_LIB.BASEBOARD_FAB2(SCH_1):PAGE118_I73@MSTR_U_PROC.LBG_CORE_QAT_EXT_D(CHIPS)':
 'LAN_RBIAS_0': CDS_PINID='LAN_RBIAS_0';
NODE_NAME     R2N4 2
 '@BASEBOARD_FAB2_LIB.BASEBOARD_FAB2(SCH_1):PAGE118_I96@MSTR_DISCRETE.RES(CHIPS)':
 'B': CDS_PINID='B';
NET_NAME
'A_KR1_RBIAS'
 '@BASEBOARD_FAB2_LIB.BASEBOARD_FAB2(SCH_1):A_KR1_RBIAS':
 C_SIGNAL='@baseboard_fab2_lib.baseboard_fab2(sch_1):a_kr1_rbias';
NODE_NAME     U7C1 BD42
 '@BASEBOARD_FAB2_LIB.BASEBOARD_FAB2(SCH_1):PAGE118_I73@MSTR_U_PROC.LBG_CORE_QAT_EXT_D(CHIPS)':
 'LAN_RBIAS_1': CDS_PINID='LAN_RBIAS_1';
NODE_NAME     R2M6 1
 '@BASEBOARD_FAB2_LIB.BASEBOARD_FAB2(SCH_1):PAGE118_I99@MSTR_DISCRETE.RES(CHIPS)':
 'A': CDS_PINID='A';
NET_NAME
'A_P12V_STBY_ADR_TRIGGER'
 '@BASEBOARD_FAB2_LIB.BASEBOARD_FAB2(SCH_1):A_P12V_STBY_ADR_TRIGGER':
 C_SIGNAL='@baseboard_fab2_lib.baseboard_fab2(sch_1):a_p12v_stby_adr_trigger';
NODE_NAME     U9P1 4
 '@BASEBOARD_FAB2_LIB.BASEBOARD_FAB2(SCH_1):PAGE200_I163@MSTR_VREG.TPS3700(CHIPS)':
 'INAP': CDS_PINID='INAP';
NODE_NAME     C9W2 1
 '@BASEBOARD_FAB2_LIB.BASEBOARD_FAB2(SCH_1):PAGE200_I236@W_HDL.SC22P50V2JN-4GP(CHIPS)':
 '1': CDS_PINID='\1\';
NODE_NAME     R9P9 1
 '@BASEBOARD_FAB2_LIB.BASEBOARD_FAB2(SCH_1):PAGE200_I251@MSTR_DISCRETE.RES(CHIPS)':
 'A': CDS_PINID='A';
NODE_NAME     R9P7 2
 '@BASEBOARD_FAB2_LIB.BASEBOARD_FAB2(SCH_1):PAGE200_I252@MSTR_DISCRETE.RES(CHIPS)':
 'B': CDS_PINID='B';
NET_NAME
'A_P12V_STBY_FPH_GATE'
 '@BASEBOARD_FAB2_LIB.BASEBOARD_FAB2(SCH_1):A_P12V_STBY_FPH_GATE':
 C_SIGNAL='@baseboard_fab2_lib.baseboard_fab2(sch_1):a_p12v_stby_fph_gate';
NODE_NAME     U9P1 1
 '@BASEBOARD_FAB2_LIB.BASEBOARD_FAB2(SCH_1):PAGE200_I163@MSTR_VREG.TPS3700(CHIPS)':
 'OUTB': CDS_PINID='OUTB';
NODE_NAME     R9P10 2
 '@BASEBOARD_FAB2_LIB.BASEBOARD_FAB2(SCH_1):PAGE200_I192@MSTR_DISCRETE.RES(CHIPS)':
 'B': CDS_PINID='B';
NODE_NAME     Q9P1 5
 '@BASEBOARD_FAB2_LIB.BASEBOARD_FAB2(SCH_1):PAGE200_I199@MSTR_DISCRETE.FET_N_DUAL(CHIPS)':
 'GATE'<0>: CDS_PINID='GATE(0)';
NET_NAME
'A_P12V_STBY_FP_TRIGGER'
 '@BASEBOARD_FAB2_LIB.BASEBOARD_FAB2(SCH_1):A_P12V_STBY_FP_TRIGGER':
 C_SIGNAL='@baseboard_fab2_lib.baseboard_fab2(sch_1):a_p12v_stby_fp_trigger';
NODE_NAME     R9P11 1
 '@BASEBOARD_FAB2_LIB.BASEBOARD_FAB2(SCH_1):PAGE200_I108@MSTR_DISCRETE.RES(CHIPS)':
 'A': CDS_PINID='A';
NODE_NAME     U9P1 3
 '@BASEBOARD_FAB2_LIB.BASEBOARD_FAB2(SCH_1):PAGE200_I163@MSTR_VREG.TPS3700(CHIPS)':
 'INBN': CDS_PINID='INBN';
NODE_NAME     C9W1 1
 '@BASEBOARD_FAB2_LIB.BASEBOARD_FAB2(SCH_1):PAGE200_I235@W_HDL.SC22P50V2JN-4GP(CHIPS)':
 '1': CDS_PINID='\1\';
NODE_NAME     R9P13 2
 '@BASEBOARD_FAB2_LIB.BASEBOARD_FAB2(SCH_1):PAGE200_I249@W_HDL.270KR2F-GP(CHIPS)':
 '2': CDS_PINID='\2\';
NODE_NAME     R6W3 2
 '@BASEBOARD_FAB2_LIB.BASEBOARD_FAB2(SCH_1):PAGE200_I250@W_HDL.232KR2F-2-GP(CHIPS)':
 '2': CDS_PINID='\2\';
NET_NAME
'A_P12V_STBY_SCALED'
 '@BASEBOARD_FAB2_LIB.BASEBOARD_FAB2(SCH_1):A_P12V_STBY_SCALED':
 C_SIGNAL='@baseboard_fab2_lib.baseboard_fab2(sch_1):a_p12v_stby_scaled';
NODE_NAME     C9G17 1
 '@BASEBOARD_FAB2_LIB.BASEBOARD_FAB2(SCH_1):PAGE169_I80@MSTR_DISCRETE.CAP(CHIPS)':
 'A': CDS_PINID='A';
NODE_NAME     R1U32 2
 '@BASEBOARD_FAB2_LIB.BASEBOARD_FAB2(SCH_1):PAGE169_I82@MSTR_DISCRETE.RES(CHIPS)':
 'B': CDS_PINID='B';
NODE_NAME     U25W4 E2
 '@BASEBOARD_FAB2_LIB.BASEBOARD_FAB2(SCH_1):PAGE147_I106@W_HDL.AST2520A1-GP-GP(CHIPS)':
 'ADC2_GPIW2': CDS_PINID='ADC2_GPIW2';
NODE_NAME     R1U33 1
 '@BASEBOARD_FAB2_LIB.BASEBOARD_FAB2(SCH_1):PAGE169_I171@W_HDL.649R2F-GP(CHIPS)':
 '1': CDS_PINID='\1\';
NET_NAME
'A_P1V05_STBY_PCH_SENSOR'
 '@BASEBOARD_FAB2_LIB.BASEBOARD_FAB2(SCH_1):A_P1V05_STBY_PCH_SENSOR':
 C_SIGNAL='@baseboard_fab2_lib.baseboard_fab2(sch_1):a_p1v05_stby_pch_sensor';
NODE_NAME     C1U21 1
 '@BASEBOARD_FAB2_LIB.BASEBOARD_FAB2(SCH_1):PAGE169_I56@MSTR_DISCRETE.CAP(CHIPS)':
 'A': CDS_PINID='A';
NODE_NAME     FB1U3 1
 '@BASEBOARD_FAB2_LIB.BASEBOARD_FAB2(SCH_1):PAGE169_I57@MSTR_DISCRETE.FERRITE(CHIPS)':
 'A': CDS_PINID='A';
NODE_NAME     U25W4 E1
 '@BASEBOARD_FAB2_LIB.BASEBOARD_FAB2(SCH_1):PAGE147_I106@W_HDL.AST2520A1-GP-GP(CHIPS)':
 'ADC3_GPIW3': CDS_PINID='ADC3_GPIW3';
NET_NAME
'A_P3V3_SCALED'
 '@BASEBOARD_FAB2_LIB.BASEBOARD_FAB2(SCH_1):A_P3V3_SCALED':
 C_SIGNAL='@baseboard_fab2_lib.baseboard_fab2(sch_1):a_p3v3_scaled';
NODE_NAME     C9G14 1
 '@BASEBOARD_FAB2_LIB.BASEBOARD_FAB2(SCH_1):PAGE169_I146@MSTR_DISCRETE.CAP(CHIPS)':
 'A': CDS_PINID='A';
NODE_NAME     R1U26 2
 '@BASEBOARD_FAB2_LIB.BASEBOARD_FAB2(SCH_1):PAGE169_I148@MSTR_DISCRETE.RES(CHIPS)':
 'B': CDS_PINID='B';
NODE_NAME     U25W4 F4
 '@BASEBOARD_FAB2_LIB.BASEBOARD_FAB2(SCH_1):PAGE147_I106@W_HDL.AST2520A1-GP-GP(CHIPS)':
 'ADC0_GPIW0': CDS_PINID='ADC0_GPIW0';
NODE_NAME     R1U27 1
 '@BASEBOARD_FAB2_LIB.BASEBOARD_FAB2(SCH_1):PAGE169_I173@MSTR_DISCRETE.RES(CHIPS)':
 'A': CDS_PINID='A';
NET_NAME
'A_P3V3_STBY_SCALED'
 '@BASEBOARD_FAB2_LIB.BASEBOARD_FAB2(SCH_1):A_P3V3_STBY_SCALED':
 C_SIGNAL='@baseboard_fab2_lib.baseboard_fab2(sch_1):a_p3v3_stby_scaled';
NODE_NAME     C9G20 1
 '@BASEBOARD_FAB2_LIB.BASEBOARD_FAB2(SCH_1):PAGE169_I86@MSTR_DISCRETE.CAP(CHIPS)':
 'A': CDS_PINID='A';
NODE_NAME     R1U39 2
 '@BASEBOARD_FAB2_LIB.BASEBOARD_FAB2(SCH_1):PAGE169_I88@MSTR_DISCRETE.RES(CHIPS)':
 'B': CDS_PINID='B';
NODE_NAME     U25W4 E3
 '@BASEBOARD_FAB2_LIB.BASEBOARD_FAB2(SCH_1):PAGE147_I106@W_HDL.AST2520A1-GP-GP(CHIPS)':
 'ADC5_GPIW5': CDS_PINID='ADC5_GPIW5';
NODE_NAME     R1U38 1
 '@BASEBOARD_FAB2_LIB.BASEBOARD_FAB2(SCH_1):PAGE169_I172@MSTR_DISCRETE.RES(CHIPS)':
 'A': CDS_PINID='A';
NET_NAME
'A_P3V_BAT_R'
 '@BASEBOARD_FAB2_LIB.BASEBOARD_FAB2(SCH_1):A_P3V_BAT_R':
 C_SIGNAL='@baseboard_fab2_lib.baseboard_fab2(sch_1):a_p3v_bat_r';
NODE_NAME     R1U50 1
 '@BASEBOARD_FAB2_LIB.BASEBOARD_FAB2(SCH_1):PAGE169_I126@MSTR_DISCRETE.RES(CHIPS)':
 'A': CDS_PINID='A';
NODE_NAME     R2U43 2
 '@BASEBOARD_FAB2_LIB.BASEBOARD_FAB2(SCH_1):PAGE196_I46@MSTR_DISCRETE.RES(CHIPS)':
 'B': CDS_PINID='B';
NODE_NAME     CR2U1 2
 '@BASEBOARD_FAB2_LIB.BASEBOARD_FAB2(SCH_1):PAGE196_I53@MSTR_DISCRETE.DIODE2A_DUAL(CHIPS)':
 'A2': CDS_PINID='A2';
NET_NAME
'A_P3V_BAT_SCALED'
 '@BASEBOARD_FAB2_LIB.BASEBOARD_FAB2(SCH_1):A_P3V_BAT_SCALED':
 C_SIGNAL='@baseboard_fab2_lib.baseboard_fab2(sch_1):a_p3v_bat_scaled';
NODE_NAME     R9G26 1
 '@BASEBOARD_FAB2_LIB.BASEBOARD_FAB2(SCH_1):PAGE169_I106@MSTR_DISCRETE.RES(CHIPS)':
 'A': CDS_PINID='A';
NODE_NAME     C9G22 1
 '@BASEBOARD_FAB2_LIB.BASEBOARD_FAB2(SCH_1):PAGE169_I108@MSTR_DISCRETE.CAP(CHIPS)':
 'A': CDS_PINID='A';
NODE_NAME     Q9G1 4
 '@BASEBOARD_FAB2_LIB.BASEBOARD_FAB2(SCH_1):PAGE169_I157@MSTR_DISCRETE.FET_N_DUAL(CHIPS)':
 'SOURCE'<0>: CDS_PINID='SOURCE(0)';
NODE_NAME     U25W4 G4
 '@BASEBOARD_FAB2_LIB.BASEBOARD_FAB2(SCH_1):PAGE147_I106@W_HDL.AST2520A1-GP-GP(CHIPS)':
 'ADC7_GPIW7': CDS_PINID='ADC7_GPIW7';
NET_NAME
'A_P5V_SCALED'
 '@BASEBOARD_FAB2_LIB.BASEBOARD_FAB2(SCH_1):A_P5V_SCALED':
 C_SIGNAL='@baseboard_fab2_lib.baseboard_fab2(sch_1):a_p5v_scaled';
NODE_NAME     C9G15 1
 '@BASEBOARD_FAB2_LIB.BASEBOARD_FAB2(SCH_1):PAGE169_I139@MSTR_DISCRETE.CAP(CHIPS)':
 'A': CDS_PINID='A';
NODE_NAME     R1U29 2
 '@BASEBOARD_FAB2_LIB.BASEBOARD_FAB2(SCH_1):PAGE169_I141@MSTR_DISCRETE.RES(CHIPS)':
 'B': CDS_PINID='B';
NODE_NAME     U25W4 F5
 '@BASEBOARD_FAB2_LIB.BASEBOARD_FAB2(SCH_1):PAGE147_I106@W_HDL.AST2520A1-GP-GP(CHIPS)':
 'ADC1_GPIW1': CDS_PINID='ADC1_GPIW1';
NODE_NAME     R1U28 1
 '@BASEBOARD_FAB2_LIB.BASEBOARD_FAB2(SCH_1):PAGE169_I169@W_HDL.1K82R2F-1-GP(CHIPS)':
 '1': CDS_PINID='\1\';
NET_NAME
'A_P5V_STBY_SCALED'
 '@BASEBOARD_FAB2_LIB.BASEBOARD_FAB2(SCH_1):A_P5V_STBY_SCALED':
 C_SIGNAL='@baseboard_fab2_lib.baseboard_fab2(sch_1):a_p5v_stby_scaled';
NODE_NAME     C9G21 1
 '@BASEBOARD_FAB2_LIB.BASEBOARD_FAB2(SCH_1):PAGE169_I68@MSTR_DISCRETE.CAP(CHIPS)':
 'A': CDS_PINID='A';
NODE_NAME     R1U47 2
 '@BASEBOARD_FAB2_LIB.BASEBOARD_FAB2(SCH_1):PAGE169_I115@MSTR_DISCRETE.RES(CHIPS)':
 'B': CDS_PINID='B';
NODE_NAME     U25W4 G5
 '@BASEBOARD_FAB2_LIB.BASEBOARD_FAB2(SCH_1):PAGE147_I106@W_HDL.AST2520A1-GP-GP(CHIPS)':
 'ADC6_GPIW6': CDS_PINID='ADC6_GPIW6';
NODE_NAME     R1U44 1
 '@BASEBOARD_FAB2_LIB.BASEBOARD_FAB2(SCH_1):PAGE169_I170@W_HDL.1K82R2F-1-GP(CHIPS)':
 '1': CDS_PINID='\1\';
NET_NAME
'A_PCH_XCLK_BIASREF'
 '@BASEBOARD_FAB2_LIB.BASEBOARD_FAB2(SCH_1):A_PCH_XCLK_BIASREF':
 C_SIGNAL='@baseboard_fab2_lib.baseboard_fab2(sch_1):a_pch_xclk_biasref';
NODE_NAME     U7C1 G44
 '@BASEBOARD_FAB2_LIB.BASEBOARD_FAB2(SCH_1):PAGE114_I40@MSTR_U_PROC.LBG_CORE_QAT_EXT_D(CHIPS)':
 'XCLK_BIASREF': CDS_PINID='XCLK_BIASREF';
NODE_NAME     R3N1 1
 '@BASEBOARD_FAB2_LIB.BASEBOARD_FAB2(SCH_1):PAGE114_I149@MSTR_DISCRETE.RES(CHIPS)':
 'A': CDS_PINID='A';
NODE_NAME     C3W1 1
 '@BASEBOARD_FAB2_LIB.BASEBOARD_FAB2(SCH_1):PAGE114_I193@MSTR_DISCRETE.CAP(CHIPS)':
 'A': CDS_PINID='A';
NET_NAME
'A_PCIEUP_RCOMP_N'
 '@BASEBOARD_FAB2_LIB.BASEBOARD_FAB2(SCH_1):A_PCIEUP_RCOMP_N':
 C_SIGNAL='@baseboard_fab2_lib.baseboard_fab2(sch_1):a_pcieup_rcomp_n';
NODE_NAME     R3M12 2
 '@BASEBOARD_FAB2_LIB.BASEBOARD_FAB2(SCH_1):PAGE116_I181@MSTR_DISCRETE.RES(CHIPS)':
 'B': CDS_PINID='B';
NODE_NAME     U7C1 AF58
 '@BASEBOARD_FAB2_LIB.BASEBOARD_FAB2(SCH_1):PAGE116_I220@MSTR_U_PROC.LBG_CORE_QAT_EXT_D(CHIPS)':
 'PCIEUP_RCOMPN': CDS_PINID='PCIEUP_RCOMPN';
NET_NAME
'A_PCIEUP_RCOMP_P'
 '@BASEBOARD_FAB2_LIB.BASEBOARD_FAB2(SCH_1):A_PCIEUP_RCOMP_P':
 C_SIGNAL='@baseboard_fab2_lib.baseboard_fab2(sch_1):a_pcieup_rcomp_p';
NODE_NAME     R3M12 1
 '@BASEBOARD_FAB2_LIB.BASEBOARD_FAB2(SCH_1):PAGE116_I181@MSTR_DISCRETE.RES(CHIPS)':
 'A': CDS_PINID='A';
NODE_NAME     U7C1 AH58
 '@BASEBOARD_FAB2_LIB.BASEBOARD_FAB2(SCH_1):PAGE116_I220@MSTR_U_PROC.LBG_CORE_QAT_EXT_D(CHIPS)':
 'PCIEUP_RCOMPP': CDS_PINID='PCIEUP_RCOMPP';
NET_NAME
'A_PCIE_RCOMP_N'
 '@BASEBOARD_FAB2_LIB.BASEBOARD_FAB2(SCH_1):A_PCIE_RCOMP_N':
 C_SIGNAL='@baseboard_fab2_lib.baseboard_fab2(sch_1):a_pcie_rcomp_n';
NODE_NAME     R3M11 2
 '@BASEBOARD_FAB2_LIB.BASEBOARD_FAB2(SCH_1):PAGE116_I108@MSTR_DISCRETE.RES(CHIPS)':
 'B': CDS_PINID='B';
NODE_NAME     U7C1 BD58
 '@BASEBOARD_FAB2_LIB.BASEBOARD_FAB2(SCH_1):PAGE116_I220@MSTR_U_PROC.LBG_CORE_QAT_EXT_D(CHIPS)':
 'PCIE_RCOMPN': CDS_PINID='PCIE_RCOMPN';
NET_NAME
'A_PCIE_RCOMP_P'
 '@BASEBOARD_FAB2_LIB.BASEBOARD_FAB2(SCH_1):A_PCIE_RCOMP_P':
 C_SIGNAL='@baseboard_fab2_lib.baseboard_fab2(sch_1):a_pcie_rcomp_p';
NODE_NAME     R3M11 1
 '@BASEBOARD_FAB2_LIB.BASEBOARD_FAB2(SCH_1):PAGE116_I108@MSTR_DISCRETE.RES(CHIPS)':
 'A': CDS_PINID='A';
NODE_NAME     U7C1 BB56
 '@BASEBOARD_FAB2_LIB.BASEBOARD_FAB2(SCH_1):PAGE116_I220@MSTR_U_PROC.LBG_CORE_QAT_EXT_D(CHIPS)':
 'PCIE_RCOMPP': CDS_PINID='PCIE_RCOMPP';
NET_NAME
'A_PG_P12V_MAIN'
 '@BASEBOARD_FAB2_LIB.BASEBOARD_FAB2(SCH_1):A_PG_P12V_MAIN':
 C_SIGNAL='@baseboard_fab2_lib.baseboard_fab2(sch_1):a_pg_p12v_main';
NODE_NAME     U8D8 4
 '@BASEBOARD_FAB2_LIB.BASEBOARD_FAB2(SCH_1):PAGE196_I104@MSTR_VREG.TPS3700(CHIPS)':
 'INAP': CDS_PINID='INAP';
NODE_NAME     R8D38 2
 '@BASEBOARD_FAB2_LIB.BASEBOARD_FAB2(SCH_1):PAGE196_I112@MSTR_DISCRETE.RES(CHIPS)':
 'B': CDS_PINID='B';
NODE_NAME     R8D40 1
 '@BASEBOARD_FAB2_LIB.BASEBOARD_FAB2(SCH_1):PAGE196_I130@MSTR_DISCRETE.RES(CHIPS)':
 'A': CDS_PINID='A';
NET_NAME
'A_PG_P5V'
 '@BASEBOARD_FAB2_LIB.BASEBOARD_FAB2(SCH_1):A_PG_P5V':
 C_SIGNAL='@baseboard_fab2_lib.baseboard_fab2(sch_1):a_pg_p5v';
NODE_NAME     U8D8 3
 '@BASEBOARD_FAB2_LIB.BASEBOARD_FAB2(SCH_1):PAGE196_I104@MSTR_VREG.TPS3700(CHIPS)':
 'INBN': CDS_PINID='INBN';
NODE_NAME     R8D39 2
 '@BASEBOARD_FAB2_LIB.BASEBOARD_FAB2(SCH_1):PAGE196_I114@MSTR_DISCRETE.RES(CHIPS)':
 'B': CDS_PINID='B';
NODE_NAME     R8D37 1
 '@BASEBOARD_FAB2_LIB.BASEBOARD_FAB2(SCH_1):PAGE196_I115@MSTR_DISCRETE.RES(CHIPS)':
 'A': CDS_PINID='A';
NET_NAME
'A_PVCCRTC_EXT_CAP'
 '@BASEBOARD_FAB2_LIB.BASEBOARD_FAB2(SCH_1):A_PVCCRTC_EXT_CAP':
 C_SIGNAL='@baseboard_fab2_lib.baseboard_fab2(sch_1):a_pvccrtc_ext_cap';
NODE_NAME     U7C1 AG22
 '@BASEBOARD_FAB2_LIB.BASEBOARD_FAB2(SCH_1):PAGE122_I63@MSTR_U_PROC.LBG_CORE_QAT_EXT_D(CHIPS)':
 'VCCRTCEXT': CDS_PINID='VCCRTCEXT';
NODE_NAME     C3N29 1
 '@BASEBOARD_FAB2_LIB.BASEBOARD_FAB2(SCH_1):PAGE130_I16@DEV_DISCRETE.CAP_A(CHIPS)':
 'A': CDS_PINID='A';
NET_NAME
'A_PVNN_STBY_PCH_SENSOR'
 '@BASEBOARD_FAB2_LIB.BASEBOARD_FAB2(SCH_1):A_PVNN_STBY_PCH_SENSOR':
 C_SIGNAL='@baseboard_fab2_lib.baseboard_fab2(sch_1):a_pvnn_stby_pch_sensor';
NODE_NAME     C9G18 1
 '@BASEBOARD_FAB2_LIB.BASEBOARD_FAB2(SCH_1):PAGE169_I153@MSTR_DISCRETE.CAP(CHIPS)':
 'A': CDS_PINID='A';
NODE_NAME     FB1U4 1
 '@BASEBOARD_FAB2_LIB.BASEBOARD_FAB2(SCH_1):PAGE169_I155@MSTR_DISCRETE.FERRITE(CHIPS)':
 'A': CDS_PINID='A';
NODE_NAME     U25W4 F3
 '@BASEBOARD_FAB2_LIB.BASEBOARD_FAB2(SCH_1):PAGE147_I106@W_HDL.AST2520A1-GP-GP(CHIPS)':
 'ADC4_GPIW4': CDS_PINID='ADC4_GPIW4';
NET_NAME
'A_RCOMP_3P3'
 '@BASEBOARD_FAB2_LIB.BASEBOARD_FAB2(SCH_1):A_RCOMP_3P3':
 C_SIGNAL='@baseboard_fab2_lib.baseboard_fab2(sch_1):a_rcomp_3p3';
NODE_NAME     U7C1 BY25
 '@BASEBOARD_FAB2_LIB.BASEBOARD_FAB2(SCH_1):PAGE120_I147@MSTR_U_PROC.LBG_CORE_QAT_EXT_D(CHIPS)':
 'GPIO_RCOMP_3P3': CDS_PINID='GPIO_RCOMP_3P3';
NODE_NAME     R8C21 1
 '@BASEBOARD_FAB2_LIB.BASEBOARD_FAB2(SCH_1):PAGE120_I275@MSTR_DISCRETE.RES(CHIPS)':
 'A': CDS_PINID='A';
NET_NAME
'A_TSENSE_P1V05_PCH_STBY_TMON'
 '@BASEBOARD_FAB2_LIB.BASEBOARD_FAB2(SCH_1):A_TSENSE_P1V05_PCH_STBY_TMON':
 C_SIGNAL='@baseboard_fab2_lib.baseboard_fab2(sch_1):a_tsense_p1v05_pch_stby_tmo~
n';
NODE_NAME     EU8A1 34
 '@BASEBOARD_FAB2_LIB.BASEBOARD_FAB2(SCH_1):PAGE235_I229@MSTR_CONTROLLER.PXE1110B(CHIPS)':
 'BTSEN': CDS_PINID='BTSEN';
NODE_NAME     EU7A2 36
 '@BASEBOARD_FAB2_LIB.BASEBOARD_FAB2(SCH_1):PAGE236_I117@MSTR_DISCRETE.IR354XX(CHIPS)':
 'TOUT_FLT': CDS_PINID='TOUT_FLT';
NODE_NAME     CT69 1
 '@BASEBOARD_FAB2_LIB.BASEBOARD_FAB2(SCH_1):PAGE236_I134@MSTR_DISCRETE.CAP(CHIPS)':
 'A': CDS_PINID='A';
NODE_NAME     C4W4 1
 '@BASEBOARD_FAB2_LIB.BASEBOARD_FAB2(SCH_1):PAGE235_I246@MSTR_DISCRETE.CAP(CHIPS)':
 'A': CDS_PINID='A';
NET_NAME
'A_TSENSE_PVCCIN_CPU0'
 '@BASEBOARD_FAB2_LIB.BASEBOARD_FAB2(SCH_1):A_TSENSE_PVCCIN_CPU0':
 C_SIGNAL='@baseboard_fab2_lib.baseboard_fab2(sch_1):a_tsense_pvccin_cpu0';
NODE_NAME     C4D17 1
 '@BASEBOARD_FAB2_LIB.BASEBOARD_FAB2(SCH_1):PAGE201_I66@MSTR_DISCRETE.CAP(CHIPS)':
 'A': CDS_PINID='A';
NODE_NAME     EU4D4 43
 '@BASEBOARD_FAB2_LIB.BASEBOARD_FAB2(SCH_1):PAGE201_I155@MSTR_CONTROLLER.PXE1610B(CHIPS)':
 'ATSEN': CDS_PINID='ATSEN';
NODE_NAME     EU4E1 36
 '@BASEBOARD_FAB2_LIB.BASEBOARD_FAB2(SCH_1):PAGE202_I63@MSTR_DISCRETE.IR354XX(CHIPS)':
 'TOUT_FLT': CDS_PINID='TOUT_FLT';
NODE_NAME     EU4D6 36
 '@BASEBOARD_FAB2_LIB.BASEBOARD_FAB2(SCH_1):PAGE202_I64@MSTR_DISCRETE.IR354XX(CHIPS)':
 'TOUT_FLT': CDS_PINID='TOUT_FLT';
NODE_NAME     EU4D3 36
 '@BASEBOARD_FAB2_LIB.BASEBOARD_FAB2(SCH_1):PAGE203_I70@MSTR_DISCRETE.IR354XX(CHIPS)':
 'TOUT_FLT': CDS_PINID='TOUT_FLT';
NODE_NAME     EU4D1 36
 '@BASEBOARD_FAB2_LIB.BASEBOARD_FAB2(SCH_1):PAGE203_I71@MSTR_DISCRETE.IR354XX(CHIPS)':
 'TOUT_FLT': CDS_PINID='TOUT_FLT';
NODE_NAME     EU4C2 36
 '@BASEBOARD_FAB2_LIB.BASEBOARD_FAB2(SCH_1):PAGE204_I71@MSTR_DISCRETE.IR354XX(CHIPS)':
 'TOUT_FLT': CDS_PINID='TOUT_FLT';
NODE_NAME     CT2 1
 '@BASEBOARD_FAB2_LIB.BASEBOARD_FAB2(SCH_1):PAGE202_I78@MSTR_DISCRETE.CAP(CHIPS)':
 'A': CDS_PINID='A';
NODE_NAME     CT34 1
 '@BASEBOARD_FAB2_LIB.BASEBOARD_FAB2(SCH_1):PAGE204_I88@MSTR_DISCRETE.CAP(CHIPS)':
 'A': CDS_PINID='A';
NODE_NAME     CT37 1
 '@BASEBOARD_FAB2_LIB.BASEBOARD_FAB2(SCH_1):PAGE203_I99@MSTR_DISCRETE.CAP(CHIPS)':
 'A': CDS_PINID='A';
NODE_NAME     CT42 1
 '@BASEBOARD_FAB2_LIB.BASEBOARD_FAB2(SCH_1):PAGE203_I108@MSTR_DISCRETE.CAP(CHIPS)':
 'A': CDS_PINID='A';
NODE_NAME     CT4 1
 '@BASEBOARD_FAB2_LIB.BASEBOARD_FAB2(SCH_1):PAGE202_I87@MSTR_DISCRETE.CAP(CHIPS)':
 'A': CDS_PINID='A';
NET_NAME
'A_TSENSE_PVCCIN_CPU1'
 '@BASEBOARD_FAB2_LIB.BASEBOARD_FAB2(SCH_1):A_TSENSE_PVCCIN_CPU1':
 C_SIGNAL='@baseboard_fab2_lib.baseboard_fab2(sch_1):a_tsense_pvccin_cpu1';
NODE_NAME     C1C10 1
 '@BASEBOARD_FAB2_LIB.BASEBOARD_FAB2(SCH_1):PAGE206_I69@MSTR_DISCRETE.CAP(CHIPS)':
 'A': CDS_PINID='A';
NODE_NAME     EU1C2 43
 '@BASEBOARD_FAB2_LIB.BASEBOARD_FAB2(SCH_1):PAGE206_I130@MSTR_CONTROLLER.PXE1610B(CHIPS)':
 'ATSEN': CDS_PINID='ATSEN';
NODE_NAME     EU1E2 36
 '@BASEBOARD_FAB2_LIB.BASEBOARD_FAB2(SCH_1):PAGE207_I20@MSTR_DISCRETE.IR354XX(CHIPS)':
 'TOUT_FLT': CDS_PINID='TOUT_FLT';
NODE_NAME     EU1D3 36
 '@BASEBOARD_FAB2_LIB.BASEBOARD_FAB2(SCH_1):PAGE208_I27@MSTR_DISCRETE.IR354XX(CHIPS)':
 'TOUT_FLT': CDS_PINID='TOUT_FLT';
NODE_NAME     EU1D1 36
 '@BASEBOARD_FAB2_LIB.BASEBOARD_FAB2(SCH_1):PAGE208_I71@MSTR_DISCRETE.IR354XX(CHIPS)':
 'TOUT_FLT': CDS_PINID='TOUT_FLT';
NODE_NAME     EU1C3 36
 '@BASEBOARD_FAB2_LIB.BASEBOARD_FAB2(SCH_1):PAGE209_I56@MSTR_DISCRETE.IR354XX(CHIPS)':
 'TOUT_FLT': CDS_PINID='TOUT_FLT';
NODE_NAME     CT15 1
 '@BASEBOARD_FAB2_LIB.BASEBOARD_FAB2(SCH_1):PAGE209_I67@MSTR_DISCRETE.CAP(CHIPS)':
 'A': CDS_PINID='A';
NODE_NAME     CTI7 1
 '@BASEBOARD_FAB2_LIB.BASEBOARD_FAB2(SCH_1):PAGE208_I82@MSTR_DISCRETE.CAP(CHIPS)':
 'A': CDS_PINID='A';
NODE_NAME     CT19 1
 '@BASEBOARD_FAB2_LIB.BASEBOARD_FAB2(SCH_1):PAGE208_I90@MSTR_DISCRETE.CAP(CHIPS)':
 'A': CDS_PINID='A';
NODE_NAME     CT22 1
 '@BASEBOARD_FAB2_LIB.BASEBOARD_FAB2(SCH_1):PAGE207_I74@MSTR_DISCRETE.CAP(CHIPS)':
 'A': CDS_PINID='A';
NODE_NAME     CT26 1
 '@BASEBOARD_FAB2_LIB.BASEBOARD_FAB2(SCH_1):PAGE207_I82@MSTR_DISCRETE.CAP(CHIPS)':
 'A': CDS_PINID='A';
NODE_NAME     EU1D4 36
 '@BASEBOARD_FAB2_LIB.BASEBOARD_FAB2(SCH_1):PAGE207_I113@MSTR_DISCRETE.IR354XX(CHIPS)':
 'TOUT_FLT': CDS_PINID='TOUT_FLT';
NET_NAME
'A_TSENSE_PVCCIO_CPU0'
 '@BASEBOARD_FAB2_LIB.BASEBOARD_FAB2(SCH_1):A_TSENSE_PVCCIO_CPU0':
 C_SIGNAL='@baseboard_fab2_lib.baseboard_fab2(sch_1):a_tsense_pvccio_cpu0';
NODE_NAME     EU3P1 35
 '@BASEBOARD_FAB2_LIB.BASEBOARD_FAB2(SCH_1):PAGE211_I93@MSTR_CONTROLLER.PXE1110B(CHIPS)':
 'ATSEN': CDS_PINID='ATSEN';
NODE_NAME     EU7C1 36
 '@BASEBOARD_FAB2_LIB.BASEBOARD_FAB2(SCH_1):PAGE212_I101@MSTR_DISCRETE.IR354XX(CHIPS)':
 'TOUT_FLT': CDS_PINID='TOUT_FLT';
NODE_NAME     CT71 1
 '@BASEBOARD_FAB2_LIB.BASEBOARD_FAB2(SCH_1):PAGE212_I109@MSTR_DISCRETE.CAP(CHIPS)':
 'A': CDS_PINID='A';
NODE_NAME     C4W1 1
 '@BASEBOARD_FAB2_LIB.BASEBOARD_FAB2(SCH_1):PAGE211_I97@MSTR_DISCRETE.CAP(CHIPS)':
 'A': CDS_PINID='A';
NET_NAME
'A_TSENSE_PVCCIO_CPU1'
 '@BASEBOARD_FAB2_LIB.BASEBOARD_FAB2(SCH_1):A_TSENSE_PVCCIO_CPU1':
 C_SIGNAL='@baseboard_fab2_lib.baseboard_fab2(sch_1):a_tsense_pvccio_cpu1';
NODE_NAME     EU4D5 35
 '@BASEBOARD_FAB2_LIB.BASEBOARD_FAB2(SCH_1):PAGE213_I96@MSTR_CONTROLLER.PXE1110B(CHIPS)':
 'ATSEN': CDS_PINID='ATSEN';
NODE_NAME     EU4E2 36
 '@BASEBOARD_FAB2_LIB.BASEBOARD_FAB2(SCH_1):PAGE214_I126@MSTR_DISCRETE.IR354XX(CHIPS)':
 'TOUT_FLT': CDS_PINID='TOUT_FLT';
NODE_NAME     CT61 1
 '@BASEBOARD_FAB2_LIB.BASEBOARD_FAB2(SCH_1):PAGE214_I134@MSTR_DISCRETE.CAP(CHIPS)':
 'A': CDS_PINID='A';
NODE_NAME     C4W2 1
 '@BASEBOARD_FAB2_LIB.BASEBOARD_FAB2(SCH_1):PAGE213_I101@MSTR_DISCRETE.CAP(CHIPS)':
 'A': CDS_PINID='A';
NET_NAME
'A_TSENSE_PVDDQ_ABC'
 '@BASEBOARD_FAB2_LIB.BASEBOARD_FAB2(SCH_1):A_TSENSE_PVDDQ_ABC':
 C_SIGNAL='@baseboard_fab2_lib.baseboard_fab2(sch_1):a_tsense_pvddq_abc';
NODE_NAME     EU7G2 36
 '@BASEBOARD_FAB2_LIB.BASEBOARD_FAB2(SCH_1):PAGE216_I102@MSTR_DISCRETE.IR354XX(CHIPS)':
 'TOUT_FLT': CDS_PINID='TOUT_FLT';
NODE_NAME     EU7G3 36
 '@BASEBOARD_FAB2_LIB.BASEBOARD_FAB2(SCH_1):PAGE216_I103@MSTR_DISCRETE.IR354XX(CHIPS)':
 'TOUT_FLT': CDS_PINID='TOUT_FLT';
NODE_NAME     CT49 1
 '@BASEBOARD_FAB2_LIB.BASEBOARD_FAB2(SCH_1):PAGE216_I118@MSTR_DISCRETE.CAP(CHIPS)':
 'A': CDS_PINID='A';
NODE_NAME     CT54 1
 '@BASEBOARD_FAB2_LIB.BASEBOARD_FAB2(SCH_1):PAGE216_I121@MSTR_DISCRETE.CAP(CHIPS)':
 'A': CDS_PINID='A';
NODE_NAME     C7G3 1
 '@BASEBOARD_FAB2_LIB.BASEBOARD_FAB2(SCH_1):PAGE215_I22@MSTR_DISCRETE.CAP(CHIPS)':
 'A': CDS_PINID='A';
NODE_NAME     EU7G1 35
 '@BASEBOARD_FAB2_LIB.BASEBOARD_FAB2(SCH_1):PAGE215_I69@MSTR_CONTROLLER.PXM1310B(CHIPS)':
 'ATSEN': CDS_PINID='ATSEN';
NET_NAME
'A_TSENSE_PVDDQ_DEF'
 '@BASEBOARD_FAB2_LIB.BASEBOARD_FAB2(SCH_1):A_TSENSE_PVDDQ_DEF':
 C_SIGNAL='@baseboard_fab2_lib.baseboard_fab2(sch_1):a_tsense_pvddq_def';
NODE_NAME     EU7A1 36
 '@BASEBOARD_FAB2_LIB.BASEBOARD_FAB2(SCH_1):PAGE219_I106@MSTR_DISCRETE.IR354XX(CHIPS)':
 'TOUT_FLT': CDS_PINID='TOUT_FLT';
NODE_NAME     EU7A4 36
 '@BASEBOARD_FAB2_LIB.BASEBOARD_FAB2(SCH_1):PAGE219_I107@MSTR_DISCRETE.IR354XX(CHIPS)':
 'TOUT_FLT': CDS_PINID='TOUT_FLT';
NODE_NAME     CT48 1
 '@BASEBOARD_FAB2_LIB.BASEBOARD_FAB2(SCH_1):PAGE219_I119@MSTR_DISCRETE.CAP(CHIPS)':
 'A': CDS_PINID='A';
NODE_NAME     CT43 1
 '@BASEBOARD_FAB2_LIB.BASEBOARD_FAB2(SCH_1):PAGE219_I124@MSTR_DISCRETE.CAP(CHIPS)':
 'A': CDS_PINID='A';
NODE_NAME     EU7A5 35
 '@BASEBOARD_FAB2_LIB.BASEBOARD_FAB2(SCH_1):PAGE218_I69@MSTR_CONTROLLER.PXM1310B(CHIPS)':
 'ATSEN': CDS_PINID='ATSEN';
NODE_NAME     C7A29 1
 '@BASEBOARD_FAB2_LIB.BASEBOARD_FAB2(SCH_1):PAGE218_I16@MSTR_DISCRETE.CAP(CHIPS)':
 'A': CDS_PINID='A';
NET_NAME
'A_TSENSE_PVDDQ_GHJ'
 '@BASEBOARD_FAB2_LIB.BASEBOARD_FAB2(SCH_1):A_TSENSE_PVDDQ_GHJ':
 C_SIGNAL='@baseboard_fab2_lib.baseboard_fab2(sch_1):a_tsense_pvddq_ghj';
NODE_NAME     EU1G1 36
 '@BASEBOARD_FAB2_LIB.BASEBOARD_FAB2(SCH_1):PAGE224_I110@MSTR_DISCRETE.IR354XX(CHIPS)':
 'TOUT_FLT': CDS_PINID='TOUT_FLT';
NODE_NAME     EU1F1 36
 '@BASEBOARD_FAB2_LIB.BASEBOARD_FAB2(SCH_1):PAGE224_I111@MSTR_DISCRETE.IR354XX(CHIPS)':
 'TOUT_FLT': CDS_PINID='TOUT_FLT';
NODE_NAME     CT28 1
 '@BASEBOARD_FAB2_LIB.BASEBOARD_FAB2(SCH_1):PAGE224_I122@MSTR_DISCRETE.CAP(CHIPS)':
 'A': CDS_PINID='A';
NODE_NAME     CT32 1
 '@BASEBOARD_FAB2_LIB.BASEBOARD_FAB2(SCH_1):PAGE224_I130@MSTR_DISCRETE.CAP(CHIPS)':
 'A': CDS_PINID='A';
NODE_NAME     EU1G2 35
 '@BASEBOARD_FAB2_LIB.BASEBOARD_FAB2(SCH_1):PAGE223_I69@MSTR_CONTROLLER.PXM1310B(CHIPS)':
 'ATSEN': CDS_PINID='ATSEN';
NODE_NAME     C1G24 1
 '@BASEBOARD_FAB2_LIB.BASEBOARD_FAB2(SCH_1):PAGE223_I27@MSTR_DISCRETE.CAP(CHIPS)':
 'A': CDS_PINID='A';
NET_NAME
'A_TSENSE_PVDDQ_KLM'
 '@BASEBOARD_FAB2_LIB.BASEBOARD_FAB2(SCH_1):A_TSENSE_PVDDQ_KLM':
 C_SIGNAL='@baseboard_fab2_lib.baseboard_fab2(sch_1):a_tsense_pvddq_klm';
NODE_NAME     EU1A2 36
 '@BASEBOARD_FAB2_LIB.BASEBOARD_FAB2(SCH_1):PAGE227_I101@MSTR_DISCRETE.IR354XX(CHIPS)':
 'TOUT_FLT': CDS_PINID='TOUT_FLT';
NODE_NAME     EU1A1 36
 '@BASEBOARD_FAB2_LIB.BASEBOARD_FAB2(SCH_1):PAGE227_I102@MSTR_DISCRETE.IR354XX(CHIPS)':
 'TOUT_FLT': CDS_PINID='TOUT_FLT';
NODE_NAME     CT8 1
 '@BASEBOARD_FAB2_LIB.BASEBOARD_FAB2(SCH_1):PAGE227_I114@MSTR_DISCRETE.CAP(CHIPS)':
 'A': CDS_PINID='A';
NODE_NAME     CT10 1
 '@BASEBOARD_FAB2_LIB.BASEBOARD_FAB2(SCH_1):PAGE227_I119@MSTR_DISCRETE.CAP(CHIPS)':
 'A': CDS_PINID='A';
NODE_NAME     EU1B1 35
 '@BASEBOARD_FAB2_LIB.BASEBOARD_FAB2(SCH_1):PAGE226_I69@MSTR_CONTROLLER.PXM1310B(CHIPS)':
 'ATSEN': CDS_PINID='ATSEN';
NODE_NAME     C1B11 1
 '@BASEBOARD_FAB2_LIB.BASEBOARD_FAB2(SCH_1):PAGE226_I23@MSTR_DISCRETE.CAP(CHIPS)':
 'A': CDS_PINID='A';
NET_NAME
'A_TSENSE_PVNN_PCH_TMON'
 '@BASEBOARD_FAB2_LIB.BASEBOARD_FAB2(SCH_1):A_TSENSE_PVNN_PCH_TMON':
 C_SIGNAL='@baseboard_fab2_lib.baseboard_fab2(sch_1):a_tsense_pvnn_pch_tmon';
NODE_NAME     EU8A1 35
 '@BASEBOARD_FAB2_LIB.BASEBOARD_FAB2(SCH_1):PAGE235_I229@MSTR_CONTROLLER.PXE1110B(CHIPS)':
 'ATSEN': CDS_PINID='ATSEN';
NODE_NAME     EU7A3 36
 '@BASEBOARD_FAB2_LIB.BASEBOARD_FAB2(SCH_1):PAGE236_I116@MSTR_DISCRETE.IR354XX(CHIPS)':
 'TOUT_FLT': CDS_PINID='TOUT_FLT';
NODE_NAME     CT64 1
 '@BASEBOARD_FAB2_LIB.BASEBOARD_FAB2(SCH_1):PAGE236_I136@MSTR_DISCRETE.CAP(CHIPS)':
 'A': CDS_PINID='A';
NODE_NAME     C4W3 1
 '@BASEBOARD_FAB2_LIB.BASEBOARD_FAB2(SCH_1):PAGE235_I244@MSTR_DISCRETE.CAP(CHIPS)':
 'A': CDS_PINID='A';
NET_NAME
'A_TSENSE_PVSA_CPU0'
 '@BASEBOARD_FAB2_LIB.BASEBOARD_FAB2(SCH_1):A_TSENSE_PVSA_CPU0':
 C_SIGNAL='@baseboard_fab2_lib.baseboard_fab2(sch_1):a_tsense_pvsa_cpu0';
NODE_NAME     C4D18 1
 '@BASEBOARD_FAB2_LIB.BASEBOARD_FAB2(SCH_1):PAGE201_I68@MSTR_DISCRETE.CAP(CHIPS)':
 'A': CDS_PINID='A';
NODE_NAME     EU4D4 42
 '@BASEBOARD_FAB2_LIB.BASEBOARD_FAB2(SCH_1):PAGE201_I155@MSTR_CONTROLLER.PXE1610B(CHIPS)':
 'BTSEN': CDS_PINID='BTSEN';
NODE_NAME     EU4C1 36
 '@BASEBOARD_FAB2_LIB.BASEBOARD_FAB2(SCH_1):PAGE205_I46@MSTR_DISCRETE.IR354XX(CHIPS)':
 'TOUT_FLT': CDS_PINID='TOUT_FLT';
NODE_NAME     CT58 1
 '@BASEBOARD_FAB2_LIB.BASEBOARD_FAB2(SCH_1):PAGE205_I65@MSTR_DISCRETE.CAP(CHIPS)':
 'A': CDS_PINID='A';
NET_NAME
'A_TSENSE_PVSA_CPU1'
 '@BASEBOARD_FAB2_LIB.BASEBOARD_FAB2(SCH_1):A_TSENSE_PVSA_CPU1':
 C_SIGNAL='@baseboard_fab2_lib.baseboard_fab2(sch_1):a_tsense_pvsa_cpu1';
NODE_NAME     C1C11 1
 '@BASEBOARD_FAB2_LIB.BASEBOARD_FAB2(SCH_1):PAGE206_I71@MSTR_DISCRETE.CAP(CHIPS)':
 'A': CDS_PINID='A';
NODE_NAME     EU1C2 42
 '@BASEBOARD_FAB2_LIB.BASEBOARD_FAB2(SCH_1):PAGE206_I130@MSTR_CONTROLLER.PXE1610B(CHIPS)':
 'BTSEN': CDS_PINID='BTSEN';
NODE_NAME     EU1C1 36
 '@BASEBOARD_FAB2_LIB.BASEBOARD_FAB2(SCH_1):PAGE210_I51@MSTR_DISCRETE.IR354XX(CHIPS)':
 'TOUT_FLT': CDS_PINID='TOUT_FLT';
NODE_NAME     CT55 1
 '@BASEBOARD_FAB2_LIB.BASEBOARD_FAB2(SCH_1):PAGE210_I60@MSTR_DISCRETE.CAP(CHIPS)':
 'A': CDS_PINID='A';
NET_NAME
'A_USB2AVRES'
 '@BASEBOARD_FAB2_LIB.BASEBOARD_FAB2(SCH_1):A_USB2AVRES':
 C_SIGNAL='@baseboard_fab2_lib.baseboard_fab2(sch_1):a_usb2avres';
NODE_NAME     R1T26 1
 '@BASEBOARD_FAB2_LIB.BASEBOARD_FAB2(SCH_1):PAGE146_I37@MSTR_DISCRETE.RES(CHIPS)':
 'A': CDS_PINID='A';
NODE_NAME     U25W4 B8
 '@BASEBOARD_FAB2_LIB.BASEBOARD_FAB2(SCH_1):PAGE146_I104@W_HDL.AST2520A1-GP-GP(CHIPS)':
 'USB2AVRES': CDS_PINID='USB2AVRES';
NODE_NAME     C1W21 1
 '@BASEBOARD_FAB2_LIB.BASEBOARD_FAB2(SCH_1):PAGE146_I160@MSTR_DISCRETE.CAP(CHIPS)':
 'A': CDS_PINID='A';
NET_NAME
'A_USB2BVRES'
 '@BASEBOARD_FAB2_LIB.BASEBOARD_FAB2(SCH_1):A_USB2BVRES':
 C_SIGNAL='@baseboard_fab2_lib.baseboard_fab2(sch_1):a_usb2bvres';
NODE_NAME     R1T25 1
 '@BASEBOARD_FAB2_LIB.BASEBOARD_FAB2(SCH_1):PAGE146_I35@MSTR_DISCRETE.RES(CHIPS)':
 'A': CDS_PINID='A';
NODE_NAME     U25W4 B7
 '@BASEBOARD_FAB2_LIB.BASEBOARD_FAB2(SCH_1):PAGE146_I104@W_HDL.AST2520A1-GP-GP(CHIPS)':
 'USB2BVRES': CDS_PINID='USB2BVRES';
NET_NAME
'A_USB2_COMP'
 '@BASEBOARD_FAB2_LIB.BASEBOARD_FAB2(SCH_1):A_USB2_COMP':
 C_SIGNAL='@baseboard_fab2_lib.baseboard_fab2(sch_1):a_usb2_comp';
NODE_NAME     U7C1 BN70
 '@BASEBOARD_FAB2_LIB.BASEBOARD_FAB2(SCH_1):PAGE115_I74@MSTR_U_PROC.LBG_CORE_QAT_EXT_D(CHIPS)':
 'USB2_COMP': CDS_PINID='USB2_COMP';
NODE_NAME     R8B9 1
 '@BASEBOARD_FAB2_LIB.BASEBOARD_FAB2(SCH_1):PAGE115_I90@MSTR_DISCRETE.RES(CHIPS)':
 'A': CDS_PINID='A';
NET_NAME
'A_USB2_VBUS'
 '@BASEBOARD_FAB2_LIB.BASEBOARD_FAB2(SCH_1):A_USB2_VBUS':
 C_SIGNAL='@baseboard_fab2_lib.baseboard_fab2(sch_1):a_usb2_vbus';
NODE_NAME     U7C1 BR67
 '@BASEBOARD_FAB2_LIB.BASEBOARD_FAB2(SCH_1):PAGE115_I74@MSTR_U_PROC.LBG_CORE_QAT_EXT_D(CHIPS)':
 'USB2_VBUS': CDS_PINID='USB2_VBUS';
NODE_NAME     R8B32 1
 '@BASEBOARD_FAB2_LIB.BASEBOARD_FAB2(SCH_1):PAGE115_I114@MSTR_DISCRETE.RES(CHIPS)':
 'A': CDS_PINID='A';
NET_NAME
'BMC_DEBUG_EN_N'
 '@BASEBOARD_FAB2_LIB.BASEBOARD_FAB2(SCH_1):BMC_DEBUG_EN_N':
 C_SIGNAL='@baseboard_fab2_lib.baseboard_fab2(sch_1):bmc_debug_en_n';
NODE_NAME     U25W4 L19
 '@BASEBOARD_FAB2_LIB.BASEBOARD_FAB2(SCH_1):PAGE144_I95@W_HDL.AST2520A1-GP-GP(CHIPS)':
 'GPIOB1': CDS_PINID='GPIOB1';
NODE_NAME     R25W180 2
 '@BASEBOARD_FAB2_LIB.BASEBOARD_FAB2(SCH_1):PAGE268_I2@MSTR_DISCRETE.RES(CHIPS)':
 'B': CDS_PINID='B';
NODE_NAME     U25W15 2
 '@BASEBOARD_FAB2_LIB.BASEBOARD_FAB2(SCH_1):PAGE268_I12@MSTR_TTL.TTL1G07_A(CHIPS)':
 'A': CDS_PINID='A';
NET_NAME
'BMC_JTAG_SEL'
 '@BASEBOARD_FAB2_LIB.BASEBOARD_FAB2(SCH_1):BMC_JTAG_SEL':
 C_SIGNAL='@baseboard_fab2_lib.baseboard_fab2(sch_1):bmc_jtag_sel';
NODE_NAME     Q25W5 3
 '@BASEBOARD_FAB2_LIB.BASEBOARD_FAB2(SCH_1):PAGE268_I51@MSTR_DISCRETE.FET_N(CHIPS)':
 'DRN': CDS_PINID='DRN';
NODE_NAME     R25W185 2
 '@BASEBOARD_FAB2_LIB.BASEBOARD_FAB2(SCH_1):PAGE268_I54@MSTR_DISCRETE.RES(CHIPS)':
 'B': CDS_PINID='B';
NODE_NAME     U25W18 2
 '@BASEBOARD_FAB2_LIB.BASEBOARD_FAB2(SCH_1):PAGE268_I57@MSTR_TTL.TTL1G08(CHIPS)':
 'B'<0>: CDS_PINID='B(0)';
NODE_NAME     S9W1 2
 '@BASEBOARD_FAB2_LIB.BASEBOARD_FAB2(SCH_1):PAGE268_I63@W_HDL.SW-SLIDE75-GP(CHIPS)':
 '2': CDS_PINID='\2\';
NET_NAME
'BMC_JTAG_SEL_BUF'
 '@BASEBOARD_FAB2_LIB.BASEBOARD_FAB2(SCH_1):BMC_JTAG_SEL_BUF':
 C_SIGNAL='@baseboard_fab2_lib.baseboard_fab2(sch_1):bmc_jtag_sel_buf';
NODE_NAME     U25W12 1
 '@BASEBOARD_FAB2_LIB.BASEBOARD_FAB2(SCH_1):PAGE269_I33@MSTR_TTL.TTL3126(CHIPS)'(3):
 'OE'<3>: CDS_PINID='OE(3)';
NODE_NAME     U25W16 13
 '@BASEBOARD_FAB2_LIB.BASEBOARD_FAB2(SCH_1):PAGE268_I38@MSTR_TTL.TTL3126(CHIPS)'(0):
 'OE'<0>: CDS_PINID='OE(0)';
NODE_NAME     U25W16 10
 '@BASEBOARD_FAB2_LIB.BASEBOARD_FAB2(SCH_1):PAGE268_I38@MSTR_TTL.TTL3126(CHIPS)'(1):
 'OE'<1>: CDS_PINID='OE(1)';
NODE_NAME     U25W16 4
 '@BASEBOARD_FAB2_LIB.BASEBOARD_FAB2(SCH_1):PAGE268_I38@MSTR_TTL.TTL3126(CHIPS)'(2):
 'OE'<2>: CDS_PINID='OE(2)';
NODE_NAME     U25W16 1
 '@BASEBOARD_FAB2_LIB.BASEBOARD_FAB2(SCH_1):PAGE268_I38@MSTR_TTL.TTL3126(CHIPS)'(3):
 'OE'<3>: CDS_PINID='OE(3)';
NODE_NAME     U25W17 2
 '@BASEBOARD_FAB2_LIB.BASEBOARD_FAB2(SCH_1):PAGE269_I61@MSTR_TTL.TTL1G08(CHIPS)':
 'B'<0>: CDS_PINID='B(0)';
NODE_NAME     U25W18 4
 '@BASEBOARD_FAB2_LIB.BASEBOARD_FAB2(SCH_1):PAGE268_I57@MSTR_TTL.TTL1G08(CHIPS)':
 'Y'<0>: CDS_PINID='Y(0)';
NODE_NAME     U25W19 1
 '@BASEBOARD_FAB2_LIB.BASEBOARD_FAB2(SCH_1):PAGE269_I76@MSTR_TTL.TTL1G126_A(CHIPS)':
 'OE': CDS_PINID='OE';
NET_NAME
'BMC_JTAG_SEL_N'
 '@BASEBOARD_FAB2_LIB.BASEBOARD_FAB2(SCH_1):BMC_JTAG_SEL_N':
 C_SIGNAL='@baseboard_fab2_lib.baseboard_fab2(sch_1):bmc_jtag_sel_n';
NODE_NAME     U25W4 P22
 '@BASEBOARD_FAB2_LIB.BASEBOARD_FAB2(SCH_1):PAGE148_I28@W_HDL.AST2520A1-GP-GP(CHIPS)':
 'GPIOY2_SIOPWREQ#': CDS_PINID='\gpioy2_siopwreq#\';
NODE_NAME     R25W174 2
 '@BASEBOARD_FAB2_LIB.BASEBOARD_FAB2(SCH_1):PAGE269_I4@MSTR_DISCRETE.RES(CHIPS)':
 'B': CDS_PINID='B';
NODE_NAME     U25W13 7
 '@BASEBOARD_FAB2_LIB.BASEBOARD_FAB2(SCH_1):PAGE269_I53@W_HDL.MAX4564EKA-GP(CHIPS)':
 'EN#': CDS_PINID='\en#\';
NODE_NAME     R7G114 1
 '@BASEBOARD_FAB2_LIB.BASEBOARD_FAB2(SCH_1):PAGE189_I76@MSTR_DISCRETE.RES(CHIPS)':
 'A': CDS_PINID='A';
NODE_NAME     Q25W5 1
 '@BASEBOARD_FAB2_LIB.BASEBOARD_FAB2(SCH_1):PAGE268_I51@MSTR_DISCRETE.FET_N(CHIPS)':
 'GATE': CDS_PINID='GATE';
NODE_NAME     R25W186 1
 '@BASEBOARD_FAB2_LIB.BASEBOARD_FAB2(SCH_1):PAGE189_I77@MSTR_DISCRETE.RES(CHIPS)':
 'A': CDS_PINID='A';
NET_NAME
'BMC_JTAG_SEL_N_MUX'
 '@BASEBOARD_FAB2_LIB.BASEBOARD_FAB2(SCH_1):BMC_JTAG_SEL_N_MUX':
 C_SIGNAL='@baseboard_fab2_lib.baseboard_fab2(sch_1):bmc_jtag_sel_n_mux';
NODE_NAME     U1L10 13
 '@BASEBOARD_FAB2_LIB.BASEBOARD_FAB2(SCH_1):PAGE189_I67@MSTR_TTL.TTL3126(CHIPS)'(0):
 'OE'<0>: CDS_PINID='OE(0)';
NODE_NAME     U1L10 10
 '@BASEBOARD_FAB2_LIB.BASEBOARD_FAB2(SCH_1):PAGE189_I67@MSTR_TTL.TTL3126(CHIPS)'(1):
 'OE'<1>: CDS_PINID='OE(1)';
NODE_NAME     U1L10 4
 '@BASEBOARD_FAB2_LIB.BASEBOARD_FAB2(SCH_1):PAGE189_I67@MSTR_TTL.TTL3126(CHIPS)'(2):
 'OE'<2>: CDS_PINID='OE(2)';
NODE_NAME     U1L10 1
 '@BASEBOARD_FAB2_LIB.BASEBOARD_FAB2(SCH_1):PAGE189_I67@MSTR_TTL.TTL3126(CHIPS)'(3):
 'OE'<3>: CDS_PINID='OE(3)';
NODE_NAME     R7G114 2
 '@BASEBOARD_FAB2_LIB.BASEBOARD_FAB2(SCH_1):PAGE189_I76@MSTR_DISCRETE.RES(CHIPS)':
 'B': CDS_PINID='B';
NET_NAME
'BMC_MIOZ'
 '@BASEBOARD_FAB2_LIB.BASEBOARD_FAB2(SCH_1):BMC_MIOZ':
 C_SIGNAL='@baseboard_fab2_lib.baseboard_fab2(sch_1):bmc_mioz';
NODE_NAME     R1T27 2
 '@BASEBOARD_FAB2_LIB.BASEBOARD_FAB2(SCH_1):PAGE143_I58@MSTR_DISCRETE.RES(CHIPS)':
 'B': CDS_PINID='B';
NODE_NAME     U25W4 W11
 '@BASEBOARD_FAB2_LIB.BASEBOARD_FAB2(SCH_1):PAGE143_I63@W_HDL.AST2520A1-GP-GP(CHIPS)':
 'MIOZ': CDS_PINID='MIOZ';
NET_NAME
'BMC_M_A0'
 '@BASEBOARD_FAB2_LIB.BASEBOARD_FAB2(SCH_1):BMC_M_A0':
 C_SIGNAL='@baseboard_fab2_lib.baseboard_fab2(sch_1):bmc_m_a0';
NODE_NAME     U25W4 V13
 '@BASEBOARD_FAB2_LIB.BASEBOARD_FAB2(SCH_1):PAGE143_I63@W_HDL.AST2520A1-GP-GP(CHIPS)':
 'MA0': CDS_PINID='MA0';
NODE_NAME     U25W5 P3
 '@BASEBOARD_FAB2_LIB.BASEBOARD_FAB2(SCH_1):PAGE151_I49@W_HDL.H5AN4G6NAFR-TFC-GP(CHIPS)':
 'A0': CDS_PINID='A0';
NODE_NAME     R25W38 1
 '@BASEBOARD_FAB2_LIB.BASEBOARD_FAB2(SCH_1):PAGE151_I233@W_HDL.120R2F-GP(CHIPS)':
 '1': CDS_PINID='\1\';
NODE_NAME     R25W12 2
 '@BASEBOARD_FAB2_LIB.BASEBOARD_FAB2(SCH_1):PAGE151_I256@W_HDL.120R2F-GP(CHIPS)':
 '2': CDS_PINID='\2\';
NET_NAME
'BMC_M_A1'
 '@BASEBOARD_FAB2_LIB.BASEBOARD_FAB2(SCH_1):BMC_M_A1':
 C_SIGNAL='@baseboard_fab2_lib.baseboard_fab2(sch_1):bmc_m_a1';
NODE_NAME     U25W4 AB14
 '@BASEBOARD_FAB2_LIB.BASEBOARD_FAB2(SCH_1):PAGE143_I63@W_HDL.AST2520A1-GP-GP(CHIPS)':
 'MA1': CDS_PINID='MA1';
NODE_NAME     U25W5 P7
 '@BASEBOARD_FAB2_LIB.BASEBOARD_FAB2(SCH_1):PAGE151_I49@W_HDL.H5AN4G6NAFR-TFC-GP(CHIPS)':
 'A1': CDS_PINID='A1';
NODE_NAME     R25W39 1
 '@BASEBOARD_FAB2_LIB.BASEBOARD_FAB2(SCH_1):PAGE151_I234@W_HDL.120R2F-GP(CHIPS)':
 '1': CDS_PINID='\1\';
NODE_NAME     R25W13 2
 '@BASEBOARD_FAB2_LIB.BASEBOARD_FAB2(SCH_1):PAGE151_I260@W_HDL.120R2F-GP(CHIPS)':
 '2': CDS_PINID='\2\';
NET_NAME
'BMC_M_A10'
 '@BASEBOARD_FAB2_LIB.BASEBOARD_FAB2(SCH_1):BMC_M_A10':
 C_SIGNAL='@baseboard_fab2_lib.baseboard_fab2(sch_1):bmc_m_a10';
NODE_NAME     U25W4 U13
 '@BASEBOARD_FAB2_LIB.BASEBOARD_FAB2(SCH_1):PAGE143_I63@W_HDL.AST2520A1-GP-GP(CHIPS)':
 'MA10': CDS_PINID='MA10';
NODE_NAME     U25W5 M3
 '@BASEBOARD_FAB2_LIB.BASEBOARD_FAB2(SCH_1):PAGE151_I49@W_HDL.H5AN4G6NAFR-TFC-GP(CHIPS)':
 'A10/AP': CDS_PINID='\a10/ap\';
NODE_NAME     R25W48 1
 '@BASEBOARD_FAB2_LIB.BASEBOARD_FAB2(SCH_1):PAGE151_I240@W_HDL.120R2F-GP(CHIPS)':
 '1': CDS_PINID='\1\';
NODE_NAME     R25W22 2
 '@BASEBOARD_FAB2_LIB.BASEBOARD_FAB2(SCH_1):PAGE151_I270@W_HDL.120R2F-GP(CHIPS)':
 '2': CDS_PINID='\2\';
NET_NAME
'BMC_M_A11'
 '@BASEBOARD_FAB2_LIB.BASEBOARD_FAB2(SCH_1):BMC_M_A11':
 C_SIGNAL='@baseboard_fab2_lib.baseboard_fab2(sch_1):bmc_m_a11';
NODE_NAME     U25W4 AA14
 '@BASEBOARD_FAB2_LIB.BASEBOARD_FAB2(SCH_1):PAGE143_I63@W_HDL.AST2520A1-GP-GP(CHIPS)':
 'MA11': CDS_PINID='MA11';
NODE_NAME     U25W5 T2
 '@BASEBOARD_FAB2_LIB.BASEBOARD_FAB2(SCH_1):PAGE151_I49@W_HDL.H5AN4G6NAFR-TFC-GP(CHIPS)':
 'A11': CDS_PINID='A11';
NODE_NAME     R25W49 1
 '@BASEBOARD_FAB2_LIB.BASEBOARD_FAB2(SCH_1):PAGE151_I243@W_HDL.120R2F-GP(CHIPS)':
 '1': CDS_PINID='\1\';
NODE_NAME     R25W23 2
 '@BASEBOARD_FAB2_LIB.BASEBOARD_FAB2(SCH_1):PAGE151_I269@W_HDL.120R2F-GP(CHIPS)':
 '2': CDS_PINID='\2\';
NET_NAME
'BMC_M_A12'
 '@BASEBOARD_FAB2_LIB.BASEBOARD_FAB2(SCH_1):BMC_M_A12':
 C_SIGNAL='@baseboard_fab2_lib.baseboard_fab2(sch_1):bmc_m_a12';
NODE_NAME     U25W4 Y14
 '@BASEBOARD_FAB2_LIB.BASEBOARD_FAB2(SCH_1):PAGE143_I63@W_HDL.AST2520A1-GP-GP(CHIPS)':
 'MA12': CDS_PINID='MA12';
NODE_NAME     U25W5 M7
 '@BASEBOARD_FAB2_LIB.BASEBOARD_FAB2(SCH_1):PAGE151_I49@W_HDL.H5AN4G6NAFR-TFC-GP(CHIPS)':
 'A12/BC#': CDS_PINID='\a12/bc#\';
NODE_NAME     R25W50 1
 '@BASEBOARD_FAB2_LIB.BASEBOARD_FAB2(SCH_1):PAGE151_I244@W_HDL.120R2F-GP(CHIPS)':
 '1': CDS_PINID='\1\';
NODE_NAME     R25W24 2
 '@BASEBOARD_FAB2_LIB.BASEBOARD_FAB2(SCH_1):PAGE151_I268@W_HDL.120R2F-GP(CHIPS)':
 '2': CDS_PINID='\2\';
NET_NAME
'BMC_M_A13'
 '@BASEBOARD_FAB2_LIB.BASEBOARD_FAB2(SCH_1):BMC_M_A13':
 C_SIGNAL='@baseboard_fab2_lib.baseboard_fab2(sch_1):bmc_m_a13';
NODE_NAME     U25W4 AB15
 '@BASEBOARD_FAB2_LIB.BASEBOARD_FAB2(SCH_1):PAGE143_I63@W_HDL.AST2520A1-GP-GP(CHIPS)':
 'MA13': CDS_PINID='MA13';
NODE_NAME     U25W5 T8
 '@BASEBOARD_FAB2_LIB.BASEBOARD_FAB2(SCH_1):PAGE151_I49@W_HDL.H5AN4G6NAFR-TFC-GP(CHIPS)':
 'A13': CDS_PINID='A13';
NODE_NAME     R25W51 1
 '@BASEBOARD_FAB2_LIB.BASEBOARD_FAB2(SCH_1):PAGE151_I245@W_HDL.120R2F-GP(CHIPS)':
 '1': CDS_PINID='\1\';
NODE_NAME     R25W25 2
 '@BASEBOARD_FAB2_LIB.BASEBOARD_FAB2(SCH_1):PAGE151_I275@W_HDL.120R2F-GP(CHIPS)':
 '2': CDS_PINID='\2\';
NET_NAME
'BMC_M_A2'
 '@BASEBOARD_FAB2_LIB.BASEBOARD_FAB2(SCH_1):BMC_M_A2':
 C_SIGNAL='@baseboard_fab2_lib.baseboard_fab2(sch_1):bmc_m_a2';
NODE_NAME     U25W4 W14
 '@BASEBOARD_FAB2_LIB.BASEBOARD_FAB2(SCH_1):PAGE143_I63@W_HDL.AST2520A1-GP-GP(CHIPS)':
 'MA2': CDS_PINID='MA2';
NODE_NAME     U25W5 R3
 '@BASEBOARD_FAB2_LIB.BASEBOARD_FAB2(SCH_1):PAGE151_I49@W_HDL.H5AN4G6NAFR-TFC-GP(CHIPS)':
 'A2': CDS_PINID='A2';
NODE_NAME     R25W40 1
 '@BASEBOARD_FAB2_LIB.BASEBOARD_FAB2(SCH_1):PAGE151_I247@W_HDL.120R2F-GP(CHIPS)':
 '1': CDS_PINID='\1\';
NODE_NAME     R25W14 2
 '@BASEBOARD_FAB2_LIB.BASEBOARD_FAB2(SCH_1):PAGE151_I263@W_HDL.120R2F-GP(CHIPS)':
 '2': CDS_PINID='\2\';
NET_NAME
'BMC_M_A3'
 '@BASEBOARD_FAB2_LIB.BASEBOARD_FAB2(SCH_1):BMC_M_A3':
 C_SIGNAL='@baseboard_fab2_lib.baseboard_fab2(sch_1):bmc_m_a3';
NODE_NAME     U25W4 U14
 '@BASEBOARD_FAB2_LIB.BASEBOARD_FAB2(SCH_1):PAGE143_I63@W_HDL.AST2520A1-GP-GP(CHIPS)':
 'MA3': CDS_PINID='MA3';
NODE_NAME     U25W5 N7
 '@BASEBOARD_FAB2_LIB.BASEBOARD_FAB2(SCH_1):PAGE151_I49@W_HDL.H5AN4G6NAFR-TFC-GP(CHIPS)':
 'A3': CDS_PINID='A3';
NODE_NAME     R25W41 1
 '@BASEBOARD_FAB2_LIB.BASEBOARD_FAB2(SCH_1):PAGE151_I235@W_HDL.120R2F-GP(CHIPS)':
 '1': CDS_PINID='\1\';
NODE_NAME     R25W15 2
 '@BASEBOARD_FAB2_LIB.BASEBOARD_FAB2(SCH_1):PAGE151_I262@W_HDL.120R2F-GP(CHIPS)':
 '2': CDS_PINID='\2\';
NET_NAME
'BMC_M_A4'
 '@BASEBOARD_FAB2_LIB.BASEBOARD_FAB2(SCH_1):BMC_M_A4':
 C_SIGNAL='@baseboard_fab2_lib.baseboard_fab2(sch_1):bmc_m_a4';
NODE_NAME     U25W4 W15
 '@BASEBOARD_FAB2_LIB.BASEBOARD_FAB2(SCH_1):PAGE143_I63@W_HDL.AST2520A1-GP-GP(CHIPS)':
 'MA4': CDS_PINID='MA4';
NODE_NAME     U25W5 N3
 '@BASEBOARD_FAB2_LIB.BASEBOARD_FAB2(SCH_1):PAGE151_I49@W_HDL.H5AN4G6NAFR-TFC-GP(CHIPS)':
 'A4': CDS_PINID='A4';
NODE_NAME     R25W42 1
 '@BASEBOARD_FAB2_LIB.BASEBOARD_FAB2(SCH_1):PAGE151_I236@W_HDL.120R2F-GP(CHIPS)':
 '1': CDS_PINID='\1\';
NODE_NAME     R25W16 2
 '@BASEBOARD_FAB2_LIB.BASEBOARD_FAB2(SCH_1):PAGE151_I261@W_HDL.120R2F-GP(CHIPS)':
 '2': CDS_PINID='\2\';
NET_NAME
'BMC_M_A5'
 '@BASEBOARD_FAB2_LIB.BASEBOARD_FAB2(SCH_1):BMC_M_A5':
 C_SIGNAL='@baseboard_fab2_lib.baseboard_fab2(sch_1):bmc_m_a5';
NODE_NAME     U25W4 V15
 '@BASEBOARD_FAB2_LIB.BASEBOARD_FAB2(SCH_1):PAGE143_I63@W_HDL.AST2520A1-GP-GP(CHIPS)':
 'MA5': CDS_PINID='MA5';
NODE_NAME     U25W5 P8
 '@BASEBOARD_FAB2_LIB.BASEBOARD_FAB2(SCH_1):PAGE151_I49@W_HDL.H5AN4G6NAFR-TFC-GP(CHIPS)':
 'A5': CDS_PINID='A5';
NODE_NAME     R25W43 1
 '@BASEBOARD_FAB2_LIB.BASEBOARD_FAB2(SCH_1):PAGE151_I238@W_HDL.120R2F-GP(CHIPS)':
 '1': CDS_PINID='\1\';
NODE_NAME     R25W17 2
 '@BASEBOARD_FAB2_LIB.BASEBOARD_FAB2(SCH_1):PAGE151_I264@W_HDL.120R2F-GP(CHIPS)':
 '2': CDS_PINID='\2\';
NET_NAME
'BMC_M_A6'
 '@BASEBOARD_FAB2_LIB.BASEBOARD_FAB2(SCH_1):BMC_M_A6':
 C_SIGNAL='@baseboard_fab2_lib.baseboard_fab2(sch_1):bmc_m_a6';
NODE_NAME     U25W4 AB16
 '@BASEBOARD_FAB2_LIB.BASEBOARD_FAB2(SCH_1):PAGE143_I63@W_HDL.AST2520A1-GP-GP(CHIPS)':
 'MA6': CDS_PINID='MA6';
NODE_NAME     U25W5 P2
 '@BASEBOARD_FAB2_LIB.BASEBOARD_FAB2(SCH_1):PAGE151_I49@W_HDL.H5AN4G6NAFR-TFC-GP(CHIPS)':
 'A6': CDS_PINID='A6';
NODE_NAME     R25W44 1
 '@BASEBOARD_FAB2_LIB.BASEBOARD_FAB2(SCH_1):PAGE151_I237@W_HDL.120R2F-GP(CHIPS)':
 '1': CDS_PINID='\1\';
NODE_NAME     R25W18 2
 '@BASEBOARD_FAB2_LIB.BASEBOARD_FAB2(SCH_1):PAGE151_I265@W_HDL.120R2F-GP(CHIPS)':
 '2': CDS_PINID='\2\';
NET_NAME
'BMC_M_A7'
 '@BASEBOARD_FAB2_LIB.BASEBOARD_FAB2(SCH_1):BMC_M_A7':
 C_SIGNAL='@baseboard_fab2_lib.baseboard_fab2(sch_1):bmc_m_a7';
NODE_NAME     U25W4 AA16
 '@BASEBOARD_FAB2_LIB.BASEBOARD_FAB2(SCH_1):PAGE143_I63@W_HDL.AST2520A1-GP-GP(CHIPS)':
 'MA7': CDS_PINID='MA7';
NODE_NAME     U25W5 R8
 '@BASEBOARD_FAB2_LIB.BASEBOARD_FAB2(SCH_1):PAGE151_I49@W_HDL.H5AN4G6NAFR-TFC-GP(CHIPS)':
 'A7': CDS_PINID='A7';
NODE_NAME     R25W45 1
 '@BASEBOARD_FAB2_LIB.BASEBOARD_FAB2(SCH_1):PAGE151_I242@W_HDL.120R2F-GP(CHIPS)':
 '1': CDS_PINID='\1\';
NODE_NAME     R25W19 2
 '@BASEBOARD_FAB2_LIB.BASEBOARD_FAB2(SCH_1):PAGE151_I267@W_HDL.120R2F-GP(CHIPS)':
 '2': CDS_PINID='\2\';
NET_NAME
'BMC_M_A8'
 '@BASEBOARD_FAB2_LIB.BASEBOARD_FAB2(SCH_1):BMC_M_A8':
 C_SIGNAL='@baseboard_fab2_lib.baseboard_fab2(sch_1):bmc_m_a8';
NODE_NAME     U25W4 W16
 '@BASEBOARD_FAB2_LIB.BASEBOARD_FAB2(SCH_1):PAGE143_I63@W_HDL.AST2520A1-GP-GP(CHIPS)':
 'MA8': CDS_PINID='MA8';
NODE_NAME     U25W5 R2
 '@BASEBOARD_FAB2_LIB.BASEBOARD_FAB2(SCH_1):PAGE151_I49@W_HDL.H5AN4G6NAFR-TFC-GP(CHIPS)':
 'A8': CDS_PINID='A8';
NODE_NAME     R25W46 1
 '@BASEBOARD_FAB2_LIB.BASEBOARD_FAB2(SCH_1):PAGE151_I241@W_HDL.120R2F-GP(CHIPS)':
 '1': CDS_PINID='\1\';
NODE_NAME     R25W20 2
 '@BASEBOARD_FAB2_LIB.BASEBOARD_FAB2(SCH_1):PAGE151_I266@W_HDL.120R2F-GP(CHIPS)':
 '2': CDS_PINID='\2\';
NET_NAME
'BMC_M_A9'
 '@BASEBOARD_FAB2_LIB.BASEBOARD_FAB2(SCH_1):BMC_M_A9':
 C_SIGNAL='@baseboard_fab2_lib.baseboard_fab2(sch_1):bmc_m_a9';
NODE_NAME     U25W4 Y16
 '@BASEBOARD_FAB2_LIB.BASEBOARD_FAB2(SCH_1):PAGE143_I63@W_HDL.AST2520A1-GP-GP(CHIPS)':
 'MA9': CDS_PINID='MA9';
NODE_NAME     U25W5 R7
 '@BASEBOARD_FAB2_LIB.BASEBOARD_FAB2(SCH_1):PAGE151_I49@W_HDL.H5AN4G6NAFR-TFC-GP(CHIPS)':
 'A9': CDS_PINID='A9';
NODE_NAME     R25W47 1
 '@BASEBOARD_FAB2_LIB.BASEBOARD_FAB2(SCH_1):PAGE151_I239@W_HDL.120R2F-GP(CHIPS)':
 '1': CDS_PINID='\1\';
NODE_NAME     R25W21 2
 '@BASEBOARD_FAB2_LIB.BASEBOARD_FAB2(SCH_1):PAGE151_I271@W_HDL.120R2F-GP(CHIPS)':
 '2': CDS_PINID='\2\';
NET_NAME
'BMC_M_BA0'
 '@BASEBOARD_FAB2_LIB.BASEBOARD_FAB2(SCH_1):BMC_M_BA0':
 C_SIGNAL='@baseboard_fab2_lib.baseboard_fab2(sch_1):bmc_m_ba0';
NODE_NAME     U25W4 U12
 '@BASEBOARD_FAB2_LIB.BASEBOARD_FAB2(SCH_1):PAGE143_I63@W_HDL.AST2520A1-GP-GP(CHIPS)':
 'MBA0': CDS_PINID='MBA0';
NODE_NAME     U25W5 N2
 '@BASEBOARD_FAB2_LIB.BASEBOARD_FAB2(SCH_1):PAGE151_I49@W_HDL.H5AN4G6NAFR-TFC-GP(CHIPS)':
 'BA0': CDS_PINID='BA0';
NODE_NAME     R25W35 1
 '@BASEBOARD_FAB2_LIB.BASEBOARD_FAB2(SCH_1):PAGE151_I230@W_HDL.120R2F-GP(CHIPS)':
 '1': CDS_PINID='\1\';
NODE_NAME     R25W9 2
 '@BASEBOARD_FAB2_LIB.BASEBOARD_FAB2(SCH_1):PAGE151_I258@W_HDL.120R2F-GP(CHIPS)':
 '2': CDS_PINID='\2\';
NET_NAME
'BMC_M_BA1'
 '@BASEBOARD_FAB2_LIB.BASEBOARD_FAB2(SCH_1):BMC_M_BA1':
 C_SIGNAL='@baseboard_fab2_lib.baseboard_fab2(sch_1):bmc_m_ba1';
NODE_NAME     U25W4 Y13
 '@BASEBOARD_FAB2_LIB.BASEBOARD_FAB2(SCH_1):PAGE143_I63@W_HDL.AST2520A1-GP-GP(CHIPS)':
 'MBA1': CDS_PINID='MBA1';
NODE_NAME     U25W5 N8
 '@BASEBOARD_FAB2_LIB.BASEBOARD_FAB2(SCH_1):PAGE151_I49@W_HDL.H5AN4G6NAFR-TFC-GP(CHIPS)':
 'BA1': CDS_PINID='BA1';
NODE_NAME     R25W36 1
 '@BASEBOARD_FAB2_LIB.BASEBOARD_FAB2(SCH_1):PAGE151_I231@W_HDL.120R2F-GP(CHIPS)':
 '1': CDS_PINID='\1\';
NODE_NAME     R25W10 2
 '@BASEBOARD_FAB2_LIB.BASEBOARD_FAB2(SCH_1):PAGE151_I259@W_HDL.120R2F-GP(CHIPS)':
 '2': CDS_PINID='\2\';
NET_NAME
'BMC_M_BG0'
 '@BASEBOARD_FAB2_LIB.BASEBOARD_FAB2(SCH_1):BMC_M_BG0':
 C_SIGNAL='@baseboard_fab2_lib.baseboard_fab2(sch_1):bmc_m_bg0';
NODE_NAME     U25W4 W13
 '@BASEBOARD_FAB2_LIB.BASEBOARD_FAB2(SCH_1):PAGE143_I63@W_HDL.AST2520A1-GP-GP(CHIPS)':
 'MBA2_MBG0': CDS_PINID='MBA2_MBG0';
NODE_NAME     U25W5 M2
 '@BASEBOARD_FAB2_LIB.BASEBOARD_FAB2(SCH_1):PAGE151_I49@W_HDL.H5AN4G6NAFR-TFC-GP(CHIPS)':
 'BG0': CDS_PINID='BG0';
NODE_NAME     R25W37 1
 '@BASEBOARD_FAB2_LIB.BASEBOARD_FAB2(SCH_1):PAGE151_I232@W_HDL.120R2F-GP(CHIPS)':
 '1': CDS_PINID='\1\';
NODE_NAME     R25W11 2
 '@BASEBOARD_FAB2_LIB.BASEBOARD_FAB2(SCH_1):PAGE151_I257@W_HDL.120R2F-GP(CHIPS)':
 '2': CDS_PINID='\2\';
NET_NAME
'BMC_M_CAS_N'
 '@BASEBOARD_FAB2_LIB.BASEBOARD_FAB2(SCH_1):BMC_M_CAS_N':
 C_SIGNAL='@baseboard_fab2_lib.baseboard_fab2(sch_1):bmc_m_cas_n';
NODE_NAME     U25W4 AB13
 '@BASEBOARD_FAB2_LIB.BASEBOARD_FAB2(SCH_1):PAGE143_I63@W_HDL.AST2520A1-GP-GP(CHIPS)':
 'MCAS#': CDS_PINID='\mcas#\';
NODE_NAME     U25W5 M8
 '@BASEBOARD_FAB2_LIB.BASEBOARD_FAB2(SCH_1):PAGE151_I49@W_HDL.H5AN4G6NAFR-TFC-GP(CHIPS)':
 'CAS#/A15': CDS_PINID='\cas#/a15\';
NODE_NAME     R25W33 1
 '@BASEBOARD_FAB2_LIB.BASEBOARD_FAB2(SCH_1):PAGE151_I228@W_HDL.120R2F-GP(CHIPS)':
 '1': CDS_PINID='\1\';
NODE_NAME     R25W7 2
 '@BASEBOARD_FAB2_LIB.BASEBOARD_FAB2(SCH_1):PAGE151_I254@W_HDL.120R2F-GP(CHIPS)':
 '2': CDS_PINID='\2\';
NET_NAME
'BMC_M_CKE'
 '@BASEBOARD_FAB2_LIB.BASEBOARD_FAB2(SCH_1):BMC_M_CKE':
 C_SIGNAL='@baseboard_fab2_lib.baseboard_fab2(sch_1):bmc_m_cke';
NODE_NAME     U25W4 Y11
 '@BASEBOARD_FAB2_LIB.BASEBOARD_FAB2(SCH_1):PAGE143_I63@W_HDL.AST2520A1-GP-GP(CHIPS)':
 'MCKE': CDS_PINID='MCKE';
NODE_NAME     U25W5 K2
 '@BASEBOARD_FAB2_LIB.BASEBOARD_FAB2(SCH_1):PAGE151_I49@W_HDL.H5AN4G6NAFR-TFC-GP(CHIPS)':
 'CKE': CDS_PINID='CKE';
NODE_NAME     R25W27 1
 '@BASEBOARD_FAB2_LIB.BASEBOARD_FAB2(SCH_1):PAGE151_I223@W_HDL.120R2F-GP(CHIPS)':
 '1': CDS_PINID='\1\';
NODE_NAME     R25W1 2
 '@BASEBOARD_FAB2_LIB.BASEBOARD_FAB2(SCH_1):PAGE151_I248@W_HDL.120R2F-GP(CHIPS)':
 '2': CDS_PINID='\2\';
NET_NAME
'BMC_M_CLK'
 '@BASEBOARD_FAB2_LIB.BASEBOARD_FAB2(SCH_1):BMC_M_CLK':
 C_SIGNAL='@baseboard_fab2_lib.baseboard_fab2(sch_1):bmc_m_clk';
NODE_NAME     C1W20 1
 '@BASEBOARD_FAB2_LIB.BASEBOARD_FAB2(SCH_1):PAGE151_I220@MSTR_DISCRETE.CAP(CHIPS)':
 'A': CDS_PINID='A';
NODE_NAME     R1T40 2
 '@BASEBOARD_FAB2_LIB.BASEBOARD_FAB2(SCH_1):PAGE151_I278@MSTR_DISCRETE.RES(CHIPS)':
 'B': CDS_PINID='B';
NODE_NAME     R1T28 2
 '@BASEBOARD_FAB2_LIB.BASEBOARD_FAB2(SCH_1):PAGE151_I279@MSTR_DISCRETE.RES(CHIPS)':
 'B': CDS_PINID='B';
NET_NAME
'BMC_M_CLK_DN'
 '@BASEBOARD_FAB2_LIB.BASEBOARD_FAB2(SCH_1):BMC_M_CLK_DN':
 C_SIGNAL='@baseboard_fab2_lib.baseboard_fab2(sch_1):bmc_m_clk_dn';
NODE_NAME     U25W4 AB12
 '@BASEBOARD_FAB2_LIB.BASEBOARD_FAB2(SCH_1):PAGE143_I63@W_HDL.AST2520A1-GP-GP(CHIPS)':
 'MCKN': CDS_PINID='MCKN';
NODE_NAME     U25W5 K8
 '@BASEBOARD_FAB2_LIB.BASEBOARD_FAB2(SCH_1):PAGE151_I49@W_HDL.H5AN4G6NAFR-TFC-GP(CHIPS)':
 'CK_C': CDS_PINID='CK_C';
NODE_NAME     R1T28 1
 '@BASEBOARD_FAB2_LIB.BASEBOARD_FAB2(SCH_1):PAGE151_I279@MSTR_DISCRETE.RES(CHIPS)':
 'A': CDS_PINID='A';
NET_NAME
'BMC_M_CLK_DP'
 '@BASEBOARD_FAB2_LIB.BASEBOARD_FAB2(SCH_1):BMC_M_CLK_DP':
 C_SIGNAL='@baseboard_fab2_lib.baseboard_fab2(sch_1):bmc_m_clk_dp';
NODE_NAME     U25W4 AB11
 '@BASEBOARD_FAB2_LIB.BASEBOARD_FAB2(SCH_1):PAGE143_I63@W_HDL.AST2520A1-GP-GP(CHIPS)':
 'MCKP': CDS_PINID='MCKP';
NODE_NAME     U25W5 K7
 '@BASEBOARD_FAB2_LIB.BASEBOARD_FAB2(SCH_1):PAGE151_I49@W_HDL.H5AN4G6NAFR-TFC-GP(CHIPS)':
 'CK_T': CDS_PINID='CK_T';
NODE_NAME     R1T40 1
 '@BASEBOARD_FAB2_LIB.BASEBOARD_FAB2(SCH_1):PAGE151_I278@MSTR_DISCRETE.RES(CHIPS)':
 'A': CDS_PINID='A';
NET_NAME
'BMC_M_CS_N'
 '@BASEBOARD_FAB2_LIB.BASEBOARD_FAB2(SCH_1):BMC_M_CS_N':
 C_SIGNAL='@baseboard_fab2_lib.baseboard_fab2(sch_1):bmc_m_cs_n';
NODE_NAME     U25W4 AA12
 '@BASEBOARD_FAB2_LIB.BASEBOARD_FAB2(SCH_1):PAGE143_I63@W_HDL.AST2520A1-GP-GP(CHIPS)':
 'MCS#': CDS_PINID='\mcs#\';
NODE_NAME     U25W5 L7
 '@BASEBOARD_FAB2_LIB.BASEBOARD_FAB2(SCH_1):PAGE151_I49@W_HDL.H5AN4G6NAFR-TFC-GP(CHIPS)':
 'CS#': CDS_PINID='\cs#\';
NODE_NAME     R25W31 1
 '@BASEBOARD_FAB2_LIB.BASEBOARD_FAB2(SCH_1):PAGE151_I226@W_HDL.120R2F-GP(CHIPS)':
 '1': CDS_PINID='\1\';
NODE_NAME     R25W5 2
 '@BASEBOARD_FAB2_LIB.BASEBOARD_FAB2(SCH_1):PAGE151_I252@W_HDL.120R2F-GP(CHIPS)':
 '2': CDS_PINID='\2\';
NET_NAME
'BMC_M_DM0'
 '@BASEBOARD_FAB2_LIB.BASEBOARD_FAB2(SCH_1):BMC_M_DM0':
 C_SIGNAL='@baseboard_fab2_lib.baseboard_fab2(sch_1):bmc_m_dm0';
NODE_NAME     U25W4 U8
 '@BASEBOARD_FAB2_LIB.BASEBOARD_FAB2(SCH_1):PAGE143_I63@W_HDL.AST2520A1-GP-GP(CHIPS)':
 'MDM0': CDS_PINID='MDM0';
NODE_NAME     U25W5 E7
 '@BASEBOARD_FAB2_LIB.BASEBOARD_FAB2(SCH_1):PAGE151_I49@W_HDL.H5AN4G6NAFR-TFC-GP(CHIPS)':
 'DML#/DBIL#': CDS_PINID='\dml#/dbil#\';
NET_NAME
'BMC_M_DM1'
 '@BASEBOARD_FAB2_LIB.BASEBOARD_FAB2(SCH_1):BMC_M_DM1':
 C_SIGNAL='@baseboard_fab2_lib.baseboard_fab2(sch_1):bmc_m_dm1';
NODE_NAME     U25W4 AB8
 '@BASEBOARD_FAB2_LIB.BASEBOARD_FAB2(SCH_1):PAGE143_I63@W_HDL.AST2520A1-GP-GP(CHIPS)':
 'MDM1': CDS_PINID='MDM1';
NODE_NAME     U25W5 E2
 '@BASEBOARD_FAB2_LIB.BASEBOARD_FAB2(SCH_1):PAGE151_I49@W_HDL.H5AN4G6NAFR-TFC-GP(CHIPS)':
 'DMU#/DBIU#': CDS_PINID='\dmu#/dbiu#\';
NET_NAME
'BMC_M_DQ0'
 '@BASEBOARD_FAB2_LIB.BASEBOARD_FAB2(SCH_1):BMC_M_DQ0':
 C_SIGNAL='@baseboard_fab2_lib.baseboard_fab2(sch_1):bmc_m_dq0';
NODE_NAME     U25W4 U10
 '@BASEBOARD_FAB2_LIB.BASEBOARD_FAB2(SCH_1):PAGE143_I63@W_HDL.AST2520A1-GP-GP(CHIPS)':
 'MDQ0': CDS_PINID='MDQ0';
NODE_NAME     U25W5 G2
 '@BASEBOARD_FAB2_LIB.BASEBOARD_FAB2(SCH_1):PAGE151_I49@W_HDL.H5AN4G6NAFR-TFC-GP(CHIPS)':
 'DQL0': CDS_PINID='DQL0';
NET_NAME
'BMC_M_DQ1'
 '@BASEBOARD_FAB2_LIB.BASEBOARD_FAB2(SCH_1):BMC_M_DQ1':
 C_SIGNAL='@baseboard_fab2_lib.baseboard_fab2(sch_1):bmc_m_dq1';
NODE_NAME     U25W4 W10
 '@BASEBOARD_FAB2_LIB.BASEBOARD_FAB2(SCH_1):PAGE143_I63@W_HDL.AST2520A1-GP-GP(CHIPS)':
 'MDQ1': CDS_PINID='MDQ1';
NODE_NAME     U25W5 F7
 '@BASEBOARD_FAB2_LIB.BASEBOARD_FAB2(SCH_1):PAGE151_I49@W_HDL.H5AN4G6NAFR-TFC-GP(CHIPS)':
 'DQL1': CDS_PINID='DQL1';
NET_NAME
'BMC_M_DQ10'
 '@BASEBOARD_FAB2_LIB.BASEBOARD_FAB2(SCH_1):BMC_M_DQ10':
 C_SIGNAL='@baseboard_fab2_lib.baseboard_fab2(sch_1):bmc_m_dq10';
NODE_NAME     U25W4 Y7
 '@BASEBOARD_FAB2_LIB.BASEBOARD_FAB2(SCH_1):PAGE143_I63@W_HDL.AST2520A1-GP-GP(CHIPS)':
 'MDQ10': CDS_PINID='MDQ10';
NODE_NAME     U25W5 C3
 '@BASEBOARD_FAB2_LIB.BASEBOARD_FAB2(SCH_1):PAGE151_I49@W_HDL.H5AN4G6NAFR-TFC-GP(CHIPS)':
 'DQU2': CDS_PINID='DQU2';
NET_NAME
'BMC_M_DQ11'
 '@BASEBOARD_FAB2_LIB.BASEBOARD_FAB2(SCH_1):BMC_M_DQ11':
 C_SIGNAL='@baseboard_fab2_lib.baseboard_fab2(sch_1):bmc_m_dq11';
NODE_NAME     U25W4 W8
 '@BASEBOARD_FAB2_LIB.BASEBOARD_FAB2(SCH_1):PAGE143_I63@W_HDL.AST2520A1-GP-GP(CHIPS)':
 'MDQ11': CDS_PINID='MDQ11';
NODE_NAME     U25W5 C7
 '@BASEBOARD_FAB2_LIB.BASEBOARD_FAB2(SCH_1):PAGE151_I49@W_HDL.H5AN4G6NAFR-TFC-GP(CHIPS)':
 'DQU3': CDS_PINID='DQU3';
NET_NAME
'BMC_M_DQ12'
 '@BASEBOARD_FAB2_LIB.BASEBOARD_FAB2(SCH_1):BMC_M_DQ12':
 C_SIGNAL='@baseboard_fab2_lib.baseboard_fab2(sch_1):bmc_m_dq12';
NODE_NAME     U25W4 AA6
 '@BASEBOARD_FAB2_LIB.BASEBOARD_FAB2(SCH_1):PAGE143_I63@W_HDL.AST2520A1-GP-GP(CHIPS)':
 'MDQ12': CDS_PINID='MDQ12';
NODE_NAME     U25W5 C2
 '@BASEBOARD_FAB2_LIB.BASEBOARD_FAB2(SCH_1):PAGE151_I49@W_HDL.H5AN4G6NAFR-TFC-GP(CHIPS)':
 'DQU4': CDS_PINID='DQU4';
NET_NAME
'BMC_M_DQ13'
 '@BASEBOARD_FAB2_LIB.BASEBOARD_FAB2(SCH_1):BMC_M_DQ13':
 C_SIGNAL='@baseboard_fab2_lib.baseboard_fab2(sch_1):bmc_m_dq13';
NODE_NAME     U25W4 W7
 '@BASEBOARD_FAB2_LIB.BASEBOARD_FAB2(SCH_1):PAGE143_I63@W_HDL.AST2520A1-GP-GP(CHIPS)':
 'MDQ13': CDS_PINID='MDQ13';
NODE_NAME     U25W5 C8
 '@BASEBOARD_FAB2_LIB.BASEBOARD_FAB2(SCH_1):PAGE151_I49@W_HDL.H5AN4G6NAFR-TFC-GP(CHIPS)':
 'DQU5': CDS_PINID='DQU5';
NET_NAME
'BMC_M_DQ14'
 '@BASEBOARD_FAB2_LIB.BASEBOARD_FAB2(SCH_1):BMC_M_DQ14':
 C_SIGNAL='@baseboard_fab2_lib.baseboard_fab2(sch_1):bmc_m_dq14';
NODE_NAME     U25W4 V7
 '@BASEBOARD_FAB2_LIB.BASEBOARD_FAB2(SCH_1):PAGE143_I63@W_HDL.AST2520A1-GP-GP(CHIPS)':
 'MDQ14': CDS_PINID='MDQ14';
NODE_NAME     U25W5 D3
 '@BASEBOARD_FAB2_LIB.BASEBOARD_FAB2(SCH_1):PAGE151_I49@W_HDL.H5AN4G6NAFR-TFC-GP(CHIPS)':
 'DQU6': CDS_PINID='DQU6';
NET_NAME
'BMC_M_DQ15'
 '@BASEBOARD_FAB2_LIB.BASEBOARD_FAB2(SCH_1):BMC_M_DQ15':
 C_SIGNAL='@baseboard_fab2_lib.baseboard_fab2(sch_1):bmc_m_dq15';
NODE_NAME     U25W4 U7
 '@BASEBOARD_FAB2_LIB.BASEBOARD_FAB2(SCH_1):PAGE143_I63@W_HDL.AST2520A1-GP-GP(CHIPS)':
 'MDQ15': CDS_PINID='MDQ15';
NODE_NAME     U25W5 D7
 '@BASEBOARD_FAB2_LIB.BASEBOARD_FAB2(SCH_1):PAGE151_I49@W_HDL.H5AN4G6NAFR-TFC-GP(CHIPS)':
 'DQU7': CDS_PINID='DQU7';
NET_NAME
'BMC_M_DQ2'
 '@BASEBOARD_FAB2_LIB.BASEBOARD_FAB2(SCH_1):BMC_M_DQ2':
 C_SIGNAL='@baseboard_fab2_lib.baseboard_fab2(sch_1):bmc_m_dq2';
NODE_NAME     U25W4 Y10
 '@BASEBOARD_FAB2_LIB.BASEBOARD_FAB2(SCH_1):PAGE143_I63@W_HDL.AST2520A1-GP-GP(CHIPS)':
 'MDQ2': CDS_PINID='MDQ2';
NODE_NAME     U25W5 H3
 '@BASEBOARD_FAB2_LIB.BASEBOARD_FAB2(SCH_1):PAGE151_I49@W_HDL.H5AN4G6NAFR-TFC-GP(CHIPS)':
 'DQL2': CDS_PINID='DQL2';
NET_NAME
'BMC_M_DQ3'
 '@BASEBOARD_FAB2_LIB.BASEBOARD_FAB2(SCH_1):BMC_M_DQ3':
 C_SIGNAL='@baseboard_fab2_lib.baseboard_fab2(sch_1):bmc_m_dq3';
NODE_NAME     U25W4 AA10
 '@BASEBOARD_FAB2_LIB.BASEBOARD_FAB2(SCH_1):PAGE143_I63@W_HDL.AST2520A1-GP-GP(CHIPS)':
 'MDQ3': CDS_PINID='MDQ3';
NODE_NAME     U25W5 H7
 '@BASEBOARD_FAB2_LIB.BASEBOARD_FAB2(SCH_1):PAGE151_I49@W_HDL.H5AN4G6NAFR-TFC-GP(CHIPS)':
 'DQL3': CDS_PINID='DQL3';
NET_NAME
'BMC_M_DQ4'
 '@BASEBOARD_FAB2_LIB.BASEBOARD_FAB2(SCH_1):BMC_M_DQ4':
 C_SIGNAL='@baseboard_fab2_lib.baseboard_fab2(sch_1):bmc_m_dq4';
NODE_NAME     U25W4 U9
 '@BASEBOARD_FAB2_LIB.BASEBOARD_FAB2(SCH_1):PAGE143_I63@W_HDL.AST2520A1-GP-GP(CHIPS)':
 'MDQ4': CDS_PINID='MDQ4';
NODE_NAME     U25W5 H2
 '@BASEBOARD_FAB2_LIB.BASEBOARD_FAB2(SCH_1):PAGE151_I49@W_HDL.H5AN4G6NAFR-TFC-GP(CHIPS)':
 'DQL4': CDS_PINID='DQL4';
NET_NAME
'BMC_M_DQ5'
 '@BASEBOARD_FAB2_LIB.BASEBOARD_FAB2(SCH_1):BMC_M_DQ5':
 C_SIGNAL='@baseboard_fab2_lib.baseboard_fab2(sch_1):bmc_m_dq5';
NODE_NAME     U25W4 Y9
 '@BASEBOARD_FAB2_LIB.BASEBOARD_FAB2(SCH_1):PAGE143_I63@W_HDL.AST2520A1-GP-GP(CHIPS)':
 'MDQ5': CDS_PINID='MDQ5';
NODE_NAME     U25W5 H8
 '@BASEBOARD_FAB2_LIB.BASEBOARD_FAB2(SCH_1):PAGE151_I49@W_HDL.H5AN4G6NAFR-TFC-GP(CHIPS)':
 'DQL5': CDS_PINID='DQL5';
NET_NAME
'BMC_M_DQ6'
 '@BASEBOARD_FAB2_LIB.BASEBOARD_FAB2(SCH_1):BMC_M_DQ6':
 C_SIGNAL='@baseboard_fab2_lib.baseboard_fab2(sch_1):bmc_m_dq6';
NODE_NAME     U25W4 W9
 '@BASEBOARD_FAB2_LIB.BASEBOARD_FAB2(SCH_1):PAGE143_I63@W_HDL.AST2520A1-GP-GP(CHIPS)':
 'MDQ6': CDS_PINID='MDQ6';
NODE_NAME     U25W5 J3
 '@BASEBOARD_FAB2_LIB.BASEBOARD_FAB2(SCH_1):PAGE151_I49@W_HDL.H5AN4G6NAFR-TFC-GP(CHIPS)':
 'DQL6': CDS_PINID='DQL6';
NET_NAME
'BMC_M_DQ7'
 '@BASEBOARD_FAB2_LIB.BASEBOARD_FAB2(SCH_1):BMC_M_DQ7':
 C_SIGNAL='@baseboard_fab2_lib.baseboard_fab2(sch_1):bmc_m_dq7';
NODE_NAME     U25W4 V9
 '@BASEBOARD_FAB2_LIB.BASEBOARD_FAB2(SCH_1):PAGE143_I63@W_HDL.AST2520A1-GP-GP(CHIPS)':
 'MDQ7': CDS_PINID='MDQ7';
NODE_NAME     U25W5 J7
 '@BASEBOARD_FAB2_LIB.BASEBOARD_FAB2(SCH_1):PAGE151_I49@W_HDL.H5AN4G6NAFR-TFC-GP(CHIPS)':
 'DQL7': CDS_PINID='DQL7';
NET_NAME
'BMC_M_DQ8'
 '@BASEBOARD_FAB2_LIB.BASEBOARD_FAB2(SCH_1):BMC_M_DQ8':
 C_SIGNAL='@baseboard_fab2_lib.baseboard_fab2(sch_1):bmc_m_dq8';
NODE_NAME     U25W4 AA8
 '@BASEBOARD_FAB2_LIB.BASEBOARD_FAB2(SCH_1):PAGE143_I63@W_HDL.AST2520A1-GP-GP(CHIPS)':
 'MDQ8': CDS_PINID='MDQ8';
NODE_NAME     U25W5 A3
 '@BASEBOARD_FAB2_LIB.BASEBOARD_FAB2(SCH_1):PAGE151_I49@W_HDL.H5AN4G6NAFR-TFC-GP(CHIPS)':
 'DQU0': CDS_PINID='DQU0';
NET_NAME
'BMC_M_DQ9'
 '@BASEBOARD_FAB2_LIB.BASEBOARD_FAB2(SCH_1):BMC_M_DQ9':
 C_SIGNAL='@baseboard_fab2_lib.baseboard_fab2(sch_1):bmc_m_dq9';
NODE_NAME     U25W4 Y8
 '@BASEBOARD_FAB2_LIB.BASEBOARD_FAB2(SCH_1):PAGE143_I63@W_HDL.AST2520A1-GP-GP(CHIPS)':
 'MDQ9': CDS_PINID='MDQ9';
NODE_NAME     U25W5 B8
 '@BASEBOARD_FAB2_LIB.BASEBOARD_FAB2(SCH_1):PAGE151_I49@W_HDL.H5AN4G6NAFR-TFC-GP(CHIPS)':
 'DQU1': CDS_PINID='DQU1';
NET_NAME
'BMC_M_DQS0_DN'
 '@BASEBOARD_FAB2_LIB.BASEBOARD_FAB2(SCH_1):BMC_M_DQS0_DN':
 C_SIGNAL='@baseboard_fab2_lib.baseboard_fab2(sch_1):bmc_m_dqs0_dn';
NODE_NAME     U25W4 AB10
 '@BASEBOARD_FAB2_LIB.BASEBOARD_FAB2(SCH_1):PAGE143_I63@W_HDL.AST2520A1-GP-GP(CHIPS)':
 'MDQS0N': CDS_PINID='MDQS0N';
NODE_NAME     U25W5 F3
 '@BASEBOARD_FAB2_LIB.BASEBOARD_FAB2(SCH_1):PAGE151_I49@W_HDL.H5AN4G6NAFR-TFC-GP(CHIPS)':
 'DQSL_C': CDS_PINID='DQSL_C';
NET_NAME
'BMC_M_DQS0_DP'
 '@BASEBOARD_FAB2_LIB.BASEBOARD_FAB2(SCH_1):BMC_M_DQS0_DP':
 C_SIGNAL='@baseboard_fab2_lib.baseboard_fab2(sch_1):bmc_m_dqs0_dp';
NODE_NAME     U25W4 AB9
 '@BASEBOARD_FAB2_LIB.BASEBOARD_FAB2(SCH_1):PAGE143_I63@W_HDL.AST2520A1-GP-GP(CHIPS)':
 'MDQS0P': CDS_PINID='MDQS0P';
NODE_NAME     U25W5 G3
 '@BASEBOARD_FAB2_LIB.BASEBOARD_FAB2(SCH_1):PAGE151_I49@W_HDL.H5AN4G6NAFR-TFC-GP(CHIPS)':
 'DQSL_T': CDS_PINID='DQSL_T';
NET_NAME
'BMC_M_DQS1_DN'
 '@BASEBOARD_FAB2_LIB.BASEBOARD_FAB2(SCH_1):BMC_M_DQS1_DN':
 C_SIGNAL='@baseboard_fab2_lib.baseboard_fab2(sch_1):bmc_m_dqs1_dn';
NODE_NAME     U25W4 AB6
 '@BASEBOARD_FAB2_LIB.BASEBOARD_FAB2(SCH_1):PAGE143_I63@W_HDL.AST2520A1-GP-GP(CHIPS)':
 'MDQS1N': CDS_PINID='MDQS1N';
NODE_NAME     U25W5 A7
 '@BASEBOARD_FAB2_LIB.BASEBOARD_FAB2(SCH_1):PAGE151_I49@W_HDL.H5AN4G6NAFR-TFC-GP(CHIPS)':
 'DQSU_C': CDS_PINID='DQSU_C';
NET_NAME
'BMC_M_DQS1_DP'
 '@BASEBOARD_FAB2_LIB.BASEBOARD_FAB2(SCH_1):BMC_M_DQS1_DP':
 C_SIGNAL='@baseboard_fab2_lib.baseboard_fab2(sch_1):bmc_m_dqs1_dp';
NODE_NAME     U25W4 AB7
 '@BASEBOARD_FAB2_LIB.BASEBOARD_FAB2(SCH_1):PAGE143_I63@W_HDL.AST2520A1-GP-GP(CHIPS)':
 'MDQS1P': CDS_PINID='MDQS1P';
NODE_NAME     U25W5 B7
 '@BASEBOARD_FAB2_LIB.BASEBOARD_FAB2(SCH_1):PAGE151_I49@W_HDL.H5AN4G6NAFR-TFC-GP(CHIPS)':
 'DQSU_T': CDS_PINID='DQSU_T';
NET_NAME
'BMC_M_MACT_N'
 '@BASEBOARD_FAB2_LIB.BASEBOARD_FAB2(SCH_1):BMC_M_MACT_N':
 C_SIGNAL='@baseboard_fab2_lib.baseboard_fab2(sch_1):bmc_m_mact_n';
NODE_NAME     U25W4 Y15
 '@BASEBOARD_FAB2_LIB.BASEBOARD_FAB2(SCH_1):PAGE143_I63@W_HDL.AST2520A1-GP-GP(CHIPS)':
 'MA14_MACT#': CDS_PINID='\ma14_mact#\';
NODE_NAME     U25W5 L3
 '@BASEBOARD_FAB2_LIB.BASEBOARD_FAB2(SCH_1):PAGE151_I49@W_HDL.H5AN4G6NAFR-TFC-GP(CHIPS)':
 'ACT#': CDS_PINID='\act#\';
NODE_NAME     R25W52 1
 '@BASEBOARD_FAB2_LIB.BASEBOARD_FAB2(SCH_1):PAGE151_I246@W_HDL.120R2F-GP(CHIPS)':
 '1': CDS_PINID='\1\';
NODE_NAME     R25W26 2
 '@BASEBOARD_FAB2_LIB.BASEBOARD_FAB2(SCH_1):PAGE151_I274@W_HDL.120R2F-GP(CHIPS)':
 '2': CDS_PINID='\2\';
NET_NAME
'BMC_M_MALERT_N'
 '@BASEBOARD_FAB2_LIB.BASEBOARD_FAB2(SCH_1):BMC_M_MALERT_N':
 C_SIGNAL='@baseboard_fab2_lib.baseboard_fab2(sch_1):bmc_m_malert_n';
NODE_NAME     U25W4 U16
 '@BASEBOARD_FAB2_LIB.BASEBOARD_FAB2(SCH_1):PAGE146_I105@W_HDL.AST2520A1-GP-GP(CHIPS)':
 'MALERT#': CDS_PINID='\malert#\';
NODE_NAME     U25W5 P9
 '@BASEBOARD_FAB2_LIB.BASEBOARD_FAB2(SCH_1):PAGE151_I49@W_HDL.H5AN4G6NAFR-TFC-GP(CHIPS)':
 'ALERT#': CDS_PINID='\alert#\';
NODE_NAME     R25W30 1
 '@BASEBOARD_FAB2_LIB.BASEBOARD_FAB2(SCH_1):PAGE151_I222@MSTR_DISCRETE.RES(CHIPS)':
 'A': CDS_PINID='A';
NODE_NAME     R25W4 2
 '@BASEBOARD_FAB2_LIB.BASEBOARD_FAB2(SCH_1):PAGE151_I251@W_HDL.120R2F-GP(CHIPS)':
 '2': CDS_PINID='\2\';
NET_NAME
'BMC_M_ODT'
 '@BASEBOARD_FAB2_LIB.BASEBOARD_FAB2(SCH_1):BMC_M_ODT':
 C_SIGNAL='@baseboard_fab2_lib.baseboard_fab2(sch_1):bmc_m_odt';
NODE_NAME     U25W4 V11
 '@BASEBOARD_FAB2_LIB.BASEBOARD_FAB2(SCH_1):PAGE143_I63@W_HDL.AST2520A1-GP-GP(CHIPS)':
 'MODT': CDS_PINID='MODT';
NODE_NAME     U25W5 K3
 '@BASEBOARD_FAB2_LIB.BASEBOARD_FAB2(SCH_1):PAGE151_I49@W_HDL.H5AN4G6NAFR-TFC-GP(CHIPS)':
 'ODT': CDS_PINID='ODT';
NODE_NAME     R25W28 1
 '@BASEBOARD_FAB2_LIB.BASEBOARD_FAB2(SCH_1):PAGE151_I224@W_HDL.120R2F-GP(CHIPS)':
 '1': CDS_PINID='\1\';
NODE_NAME     R25W2 2
 '@BASEBOARD_FAB2_LIB.BASEBOARD_FAB2(SCH_1):PAGE151_I249@W_HDL.120R2F-GP(CHIPS)':
 '2': CDS_PINID='\2\';
NET_NAME
'BMC_M_PAR'
 '@BASEBOARD_FAB2_LIB.BASEBOARD_FAB2(SCH_1):BMC_M_PAR':
 C_SIGNAL='@baseboard_fab2_lib.baseboard_fab2(sch_1):bmc_m_par';
NODE_NAME     U25W5 T3
 '@BASEBOARD_FAB2_LIB.BASEBOARD_FAB2(SCH_1):PAGE151_I49@W_HDL.H5AN4G6NAFR-TFC-GP(CHIPS)':
 'PAR': CDS_PINID='PAR';
NODE_NAME     R25W119 2
 '@BASEBOARD_FAB2_LIB.BASEBOARD_FAB2(SCH_1):PAGE151_I210@MSTR_DISCRETE.RES(CHIPS)':
 'B': CDS_PINID='B';
NODE_NAME     R25W118 1
 '@BASEBOARD_FAB2_LIB.BASEBOARD_FAB2(SCH_1):PAGE151_I211@MSTR_DISCRETE.RES(CHIPS)':
 'A': CDS_PINID='A';
NET_NAME
'BMC_M_RAS_N'
 '@BASEBOARD_FAB2_LIB.BASEBOARD_FAB2(SCH_1):BMC_M_RAS_N':
 C_SIGNAL='@baseboard_fab2_lib.baseboard_fab2(sch_1):bmc_m_ras_n';
NODE_NAME     U25W4 W12
 '@BASEBOARD_FAB2_LIB.BASEBOARD_FAB2(SCH_1):PAGE143_I63@W_HDL.AST2520A1-GP-GP(CHIPS)':
 'MRAS#': CDS_PINID='\mras#\';
NODE_NAME     U25W5 L8
 '@BASEBOARD_FAB2_LIB.BASEBOARD_FAB2(SCH_1):PAGE151_I49@W_HDL.H5AN4G6NAFR-TFC-GP(CHIPS)':
 'RAS#/A16': CDS_PINID='\ras#/a16\';
NODE_NAME     R25W32 1
 '@BASEBOARD_FAB2_LIB.BASEBOARD_FAB2(SCH_1):PAGE151_I227@W_HDL.120R2F-GP(CHIPS)':
 '1': CDS_PINID='\1\';
NODE_NAME     R25W6 2
 '@BASEBOARD_FAB2_LIB.BASEBOARD_FAB2(SCH_1):PAGE151_I253@W_HDL.120R2F-GP(CHIPS)':
 '2': CDS_PINID='\2\';
NET_NAME
'BMC_M_RST_N'
 '@BASEBOARD_FAB2_LIB.BASEBOARD_FAB2(SCH_1):BMC_M_RST_N':
 C_SIGNAL='@baseboard_fab2_lib.baseboard_fab2(sch_1):bmc_m_rst_n';
NODE_NAME     U25W4 AB17
 '@BASEBOARD_FAB2_LIB.BASEBOARD_FAB2(SCH_1):PAGE146_I105@W_HDL.AST2520A1-GP-GP(CHIPS)':
 'MRESET#': CDS_PINID='\mreset#\';
NODE_NAME     U25W5 P1
 '@BASEBOARD_FAB2_LIB.BASEBOARD_FAB2(SCH_1):PAGE151_I49@W_HDL.H5AN4G6NAFR-TFC-GP(CHIPS)':
 'RESET#': CDS_PINID='\reset#\';
NODE_NAME     R9F34 2
 '@BASEBOARD_FAB2_LIB.BASEBOARD_FAB2(SCH_1):PAGE151_I209@MSTR_DISCRETE.RES(CHIPS)':
 'B': CDS_PINID='B';
NODE_NAME     R25W29 1
 '@BASEBOARD_FAB2_LIB.BASEBOARD_FAB2(SCH_1):PAGE151_I225@W_HDL.120R2F-GP(CHIPS)':
 '1': CDS_PINID='\1\';
NODE_NAME     R25W3 2
 '@BASEBOARD_FAB2_LIB.BASEBOARD_FAB2(SCH_1):PAGE151_I250@W_HDL.120R2F-GP(CHIPS)':
 '2': CDS_PINID='\2\';
NET_NAME
'BMC_M_VREFCA'
 '@BASEBOARD_FAB2_LIB.BASEBOARD_FAB2(SCH_1):BMC_M_VREFCA':
 C_SIGNAL='@baseboard_fab2_lib.baseboard_fab2(sch_1):bmc_m_vrefca';
NODE_NAME     U25W4 T9
 '@BASEBOARD_FAB2_LIB.BASEBOARD_FAB2(SCH_1):PAGE143_I63@W_HDL.AST2520A1-GP-GP(CHIPS)':
 'MVREF': CDS_PINID='MVREF';
NODE_NAME     U25W5 M1
 '@BASEBOARD_FAB2_LIB.BASEBOARD_FAB2(SCH_1):PAGE151_I49@W_HDL.H5AN4G6NAFR-TFC-GP(CHIPS)':
 'VREFCA': CDS_PINID='VREFCA';
NODE_NAME     R1T30 2
 '@BASEBOARD_FAB2_LIB.BASEBOARD_FAB2(SCH_1):PAGE151_I201@MSTR_DISCRETE.RES(CHIPS)':
 'B': CDS_PINID='B';
NODE_NAME     R1T29 1
 '@BASEBOARD_FAB2_LIB.BASEBOARD_FAB2(SCH_1):PAGE151_I202@MSTR_DISCRETE.RES(CHIPS)':
 'A': CDS_PINID='A';
NODE_NAME     C25W12 1
 '@BASEBOARD_FAB2_LIB.BASEBOARD_FAB2(SCH_1):PAGE151_I212@DEV_DISCRETE.CAP_A(CHIPS)':
 'A': CDS_PINID='A';
NODE_NAME     C25W10 2
 '@BASEBOARD_FAB2_LIB.BASEBOARD_FAB2(SCH_1):PAGE151_I213@DEV_DISCRETE.CAP_A(CHIPS)':
 'B': CDS_PINID='B';
NODE_NAME     C25W11 1
 '@BASEBOARD_FAB2_LIB.BASEBOARD_FAB2(SCH_1):PAGE151_I214@DEV_DISCRETE.CAP_A(CHIPS)':
 'A': CDS_PINID='A';
NODE_NAME     C25W22 1
 '@BASEBOARD_FAB2_LIB.BASEBOARD_FAB2(SCH_1):PAGE143_I67@DEV_DISCRETE.CAP_A(CHIPS)':
 'A': CDS_PINID='A';
NODE_NAME     C25W13 1
 '@BASEBOARD_FAB2_LIB.BASEBOARD_FAB2(SCH_1):PAGE151_I217@DEV_DISCRETE.CAP_A(CHIPS)':
 'A': CDS_PINID='A';
NET_NAME
'BMC_M_WE_N'
 '@BASEBOARD_FAB2_LIB.BASEBOARD_FAB2(SCH_1):BMC_M_WE_N':
 C_SIGNAL='@baseboard_fab2_lib.baseboard_fab2(sch_1):bmc_m_we_n';
NODE_NAME     U25W4 Y12
 '@BASEBOARD_FAB2_LIB.BASEBOARD_FAB2(SCH_1):PAGE143_I63@W_HDL.AST2520A1-GP-GP(CHIPS)':
 'MWE#': CDS_PINID='\mwe#\';
NODE_NAME     U25W5 L2
 '@BASEBOARD_FAB2_LIB.BASEBOARD_FAB2(SCH_1):PAGE151_I49@W_HDL.H5AN4G6NAFR-TFC-GP(CHIPS)':
 'WE#/A14': CDS_PINID='\we#/a14\';
NODE_NAME     R25W34 1
 '@BASEBOARD_FAB2_LIB.BASEBOARD_FAB2(SCH_1):PAGE151_I229@W_HDL.120R2F-GP(CHIPS)':
 '1': CDS_PINID='\1\';
NODE_NAME     R25W8 2
 '@BASEBOARD_FAB2_LIB.BASEBOARD_FAB2(SCH_1):PAGE151_I255@W_HDL.120R2F-GP(CHIPS)':
 '2': CDS_PINID='\2\';
NET_NAME
'BMC_PRDY_N'
 '@BASEBOARD_FAB2_LIB.BASEBOARD_FAB2(SCH_1):BMC_PRDY_N':
 C_SIGNAL='@baseboard_fab2_lib.baseboard_fab2(sch_1):bmc_prdy_n';
NODE_NAME     U25W4 Y19
 '@BASEBOARD_FAB2_LIB.BASEBOARD_FAB2(SCH_1):PAGE146_I105@W_HDL.AST2520A1-GP-GP(CHIPS)':
 'GPIOR3_SPI2CK': CDS_PINID='GPIOR3_SPI2CK';
NODE_NAME     U25W11 12
 '@BASEBOARD_FAB2_LIB.BASEBOARD_FAB2(SCH_1):PAGE268_I33@MSTR_DIGITAL.GTL2014(CHIPS)':
 'A1': CDS_PINID='A1';
NET_NAME
'BMC_PREQ_BUF_N'
 '@BASEBOARD_FAB2_LIB.BASEBOARD_FAB2(SCH_1):BMC_PREQ_BUF_N':
 C_SIGNAL='@baseboard_fab2_lib.baseboard_fab2(sch_1):bmc_preq_buf_n';
NODE_NAME     R25W177 2
 '@BASEBOARD_FAB2_LIB.BASEBOARD_FAB2(SCH_1):PAGE269_I18@MSTR_DISCRETE.RES(CHIPS)':
 'B': CDS_PINID='B';
NODE_NAME     U25W12 3
 '@BASEBOARD_FAB2_LIB.BASEBOARD_FAB2(SCH_1):PAGE269_I33@MSTR_TTL.TTL3126(CHIPS)'(3):
 'B'<3>: CDS_PINID='B(3)';
NODE_NAME     U25W10 13
 '@BASEBOARD_FAB2_LIB.BASEBOARD_FAB2(SCH_1):PAGE269_I49@MSTR_DIGITAL.GTL2014(CHIPS)':
 'A0': CDS_PINID='A0';
NET_NAME
'BMC_PREQ_N'
 '@BASEBOARD_FAB2_LIB.BASEBOARD_FAB2(SCH_1):BMC_PREQ_N':
 C_SIGNAL='@baseboard_fab2_lib.baseboard_fab2(sch_1):bmc_preq_n';
NODE_NAME     U25W4 Y5
 '@BASEBOARD_FAB2_LIB.BASEBOARD_FAB2(SCH_1):PAGE147_I106@W_HDL.AST2520A1-GP-GP(CHIPS)':
 'GPIOP5_TACH13': CDS_PINID='GPIOP5_TACH13';
NODE_NAME     U25W12 2
 '@BASEBOARD_FAB2_LIB.BASEBOARD_FAB2(SCH_1):PAGE269_I33@MSTR_TTL.TTL3126(CHIPS)'(3):
 'A'<3>: CDS_PINID='A(3)';
NET_NAME
'BMC_PWR_DEBUG_BUF_N'
 '@BASEBOARD_FAB2_LIB.BASEBOARD_FAB2(SCH_1):BMC_PWR_DEBUG_BUF_N':
 C_SIGNAL='@baseboard_fab2_lib.baseboard_fab2(sch_1):bmc_pwr_debug_buf_n';
NODE_NAME     R25W178 2
 '@BASEBOARD_FAB2_LIB.BASEBOARD_FAB2(SCH_1):PAGE269_I19@MSTR_DISCRETE.RES(CHIPS)':
 'B': CDS_PINID='B';
NODE_NAME     U25W10 12
 '@BASEBOARD_FAB2_LIB.BASEBOARD_FAB2(SCH_1):PAGE269_I49@MSTR_DIGITAL.GTL2014(CHIPS)':
 'A1': CDS_PINID='A1';
NODE_NAME     U25W16 11
 '@BASEBOARD_FAB2_LIB.BASEBOARD_FAB2(SCH_1):PAGE268_I38@MSTR_TTL.TTL3126(CHIPS)'(0):
 'B'<0>: CDS_PINID='B(0)';
NET_NAME
'BMC_PWR_DEBUG_N'
 '@BASEBOARD_FAB2_LIB.BASEBOARD_FAB2(SCH_1):BMC_PWR_DEBUG_N':
 C_SIGNAL='@baseboard_fab2_lib.baseboard_fab2(sch_1):bmc_pwr_debug_n';
NODE_NAME     U25W4 W6
 '@BASEBOARD_FAB2_LIB.BASEBOARD_FAB2(SCH_1):PAGE147_I106@W_HDL.AST2520A1-GP-GP(CHIPS)':
 'GPIOP6_TACH14': CDS_PINID='GPIOP6_TACH14';
NODE_NAME     U25W16 12
 '@BASEBOARD_FAB2_LIB.BASEBOARD_FAB2(SCH_1):PAGE268_I38@MSTR_TTL.TTL3126(CHIPS)'(0):
 'A'<0>: CDS_PINID='A(0)';
NET_NAME
'BMC_RSMRST_B_N'
 '@BASEBOARD_FAB2_LIB.BASEBOARD_FAB2(SCH_1):BMC_RSMRST_B_N':
 C_SIGNAL='@baseboard_fab2_lib.baseboard_fab2(sch_1):bmc_rsmrst_b_n';
NODE_NAME     U25W4 V6
 '@BASEBOARD_FAB2_LIB.BASEBOARD_FAB2(SCH_1):PAGE147_I106@W_HDL.AST2520A1-GP-GP(CHIPS)':
 'GPIOP7_TACH15': CDS_PINID='GPIOP7_TACH15';
NODE_NAME     R25W181 2
 '@BASEBOARD_FAB2_LIB.BASEBOARD_FAB2(SCH_1):PAGE147_I173@MSTR_DISCRETE.RES(CHIPS)':
 'B': CDS_PINID='B';
NET_NAME
'BMC_SELF_HW_D_RST'
 '@BASEBOARD_FAB2_LIB.BASEBOARD_FAB2(SCH_1):BMC_SELF_HW_D_RST':
 C_SIGNAL='@baseboard_fab2_lib.baseboard_fab2(sch_1):bmc_self_hw_d_rst';
NODE_NAME     R3W1 1
 '@BASEBOARD_FAB2_LIB.BASEBOARD_FAB2(SCH_1):PAGE249_I2@MSTR_DISCRETE.RES(CHIPS)':
 'A': CDS_PINID='A';
NODE_NAME     R8W1 1
 '@BASEBOARD_FAB2_LIB.BASEBOARD_FAB2(SCH_1):PAGE249_I34@MSTR_DISCRETE.RES(CHIPS)':
 'A': CDS_PINID='A';
NODE_NAME     C8W1 1
 '@BASEBOARD_FAB2_LIB.BASEBOARD_FAB2(SCH_1):PAGE249_I52@W_HDL.SC1U16V3KX-2GP(CHIPS)':
 '1': CDS_PINID='\1\';
NODE_NAME     CR3W1 1
 '@BASEBOARD_FAB2_LIB.BASEBOARD_FAB2(SCH_1):PAGE249_I55@MSTR_DISCRETE.DIODE(CHIPS)':
 'C': CDS_PINID='C';
NET_NAME
'BMC_SELF_HW_RST'
 '@BASEBOARD_FAB2_LIB.BASEBOARD_FAB2(SCH_1):BMC_SELF_HW_RST':
 C_SIGNAL='@baseboard_fab2_lib.baseboard_fab2(sch_1):bmc_self_hw_rst';
NODE_NAME     U25W4 T22
 '@BASEBOARD_FAB2_LIB.BASEBOARD_FAB2(SCH_1):PAGE146_I105@W_HDL.AST2520A1-GP-GP(CHIPS)':
 'GPIOAB2_VPOVS_WDTRST1': CDS_PINID='GPIOAB2_VPOVS_WDTRST1';
NODE_NAME     CR3W1 2
 '@BASEBOARD_FAB2_LIB.BASEBOARD_FAB2(SCH_1):PAGE249_I55@MSTR_DISCRETE.DIODE(CHIPS)':
 'A': CDS_PINID='A';
NET_NAME
'BMC_STRAP_BIT17'
 '@BASEBOARD_FAB2_LIB.BASEBOARD_FAB2(SCH_1):BMC_STRAP_BIT17':
 C_SIGNAL='@baseboard_fab2_lib.baseboard_fab2(sch_1):bmc_strap_bit17';
NODE_NAME     U25W4 U21
 '@BASEBOARD_FAB2_LIB.BASEBOARD_FAB2(SCH_1):PAGE146_I104@W_HDL.AST2520A1-GP-GP(CHIPS)':
 'GPIOZ4_VPOG6_NORA4': CDS_PINID='GPIOZ4_VPOG6_NORA4';
NODE_NAME     R25W101 2
 '@BASEBOARD_FAB2_LIB.BASEBOARD_FAB2(SCH_1):PAGE150_I241@MSTR_DISCRETE.RES(CHIPS)':
 'B': CDS_PINID='B';
NET_NAME
'BMC_STRAP_BIT18'
 '@BASEBOARD_FAB2_LIB.BASEBOARD_FAB2(SCH_1):BMC_STRAP_BIT18':
 C_SIGNAL='@baseboard_fab2_lib.baseboard_fab2(sch_1):bmc_strap_bit18';
NODE_NAME     U25W4 W22
 '@BASEBOARD_FAB2_LIB.BASEBOARD_FAB2(SCH_1):PAGE146_I104@W_HDL.AST2520A1-GP-GP(CHIPS)':
 'GPIOZ5_VPOG7_NORA5': CDS_PINID='GPIOZ5_VPOG7_NORA5';
NODE_NAME     R25W102 2
 '@BASEBOARD_FAB2_LIB.BASEBOARD_FAB2(SCH_1):PAGE150_I239@MSTR_DISCRETE.RES(CHIPS)':
 'B': CDS_PINID='B';
NET_NAME
'BMC_STRAP_BIT20'
 '@BASEBOARD_FAB2_LIB.BASEBOARD_FAB2(SCH_1):BMC_STRAP_BIT20':
 C_SIGNAL='@baseboard_fab2_lib.baseboard_fab2(sch_1):bmc_strap_bit20';
NODE_NAME     U25W4 V22
 '@BASEBOARD_FAB2_LIB.BASEBOARD_FAB2(SCH_1):PAGE146_I104@W_HDL.AST2520A1-GP-GP(CHIPS)':
 'GPIOZ6_VPOG8_NORA6': CDS_PINID='GPIOZ6_VPOG8_NORA6';
NODE_NAME     R25W103 2
 '@BASEBOARD_FAB2_LIB.BASEBOARD_FAB2(SCH_1):PAGE150_I214@MSTR_DISCRETE.RES(CHIPS)':
 'B': CDS_PINID='B';
NET_NAME
'BMC_STRAP_BIT27'
 '@BASEBOARD_FAB2_LIB.BASEBOARD_FAB2(SCH_1):BMC_STRAP_BIT27':
 C_SIGNAL='@baseboard_fab2_lib.baseboard_fab2(sch_1):bmc_strap_bit27';
NODE_NAME     U25W4 W21
 '@BASEBOARD_FAB2_LIB.BASEBOARD_FAB2(SCH_1):PAGE146_I104@W_HDL.AST2520A1-GP-GP(CHIPS)':
 'GPIOZ7_VPOG9_NORA7': CDS_PINID='GPIOZ7_VPOG9_NORA7';
NODE_NAME     R25W104 2
 '@BASEBOARD_FAB2_LIB.BASEBOARD_FAB2(SCH_1):PAGE150_I215@MSTR_DISCRETE.RES(CHIPS)':
 'B': CDS_PINID='B';
NET_NAME
'BMC_STRAP_BIT3'
 '@BASEBOARD_FAB2_LIB.BASEBOARD_FAB2(SCH_1):BMC_STRAP_BIT3':
 C_SIGNAL='@baseboard_fab2_lib.baseboard_fab2(sch_1):bmc_strap_bit3';
NODE_NAME     U25W4 R19
 '@BASEBOARD_FAB2_LIB.BASEBOARD_FAB2(SCH_1):PAGE146_I104@W_HDL.AST2520A1-GP-GP(CHIPS)':
 'GPIOS4_VPOB6': CDS_PINID='GPIOS4_VPOB6';
NODE_NAME     R25W98 2
 '@BASEBOARD_FAB2_LIB.BASEBOARD_FAB2(SCH_1):PAGE150_I209@MSTR_DISCRETE.RES(CHIPS)':
 'B': CDS_PINID='B';
NET_NAME
'BMC_STRAP_BIT5'
 '@BASEBOARD_FAB2_LIB.BASEBOARD_FAB2(SCH_1):BMC_STRAP_BIT5':
 C_SIGNAL='@baseboard_fab2_lib.baseboard_fab2(sch_1):bmc_strap_bit5';
NODE_NAME     U25W4 U20
 '@BASEBOARD_FAB2_LIB.BASEBOARD_FAB2(SCH_1):PAGE146_I104@W_HDL.AST2520A1-GP-GP(CHIPS)':
 'GPIOS6_VPOB8': CDS_PINID='GPIOS6_VPOB8';
NODE_NAME     R25W99 2
 '@BASEBOARD_FAB2_LIB.BASEBOARD_FAB2(SCH_1):PAGE150_I210@MSTR_DISCRETE.RES(CHIPS)':
 'B': CDS_PINID='B';
NET_NAME
'BMC_TCK_MUX_SEL'
 '@BASEBOARD_FAB2_LIB.BASEBOARD_FAB2(SCH_1):BMC_TCK_MUX_SEL':
 C_SIGNAL='@baseboard_fab2_lib.baseboard_fab2(sch_1):bmc_tck_mux_sel';
NODE_NAME     U25W4 T17
 '@BASEBOARD_FAB2_LIB.BASEBOARD_FAB2(SCH_1):PAGE146_I105@W_HDL.AST2520A1-GP-GP(CHIPS)':
 'GPIOR2_SPI2CS0#': CDS_PINID='\gpior2_spi2cs0#\';
NODE_NAME     R25W167 1
 '@BASEBOARD_FAB2_LIB.BASEBOARD_FAB2(SCH_1):PAGE269_I10@MSTR_DISCRETE.RES(CHIPS)':
 'A': CDS_PINID='A';
NODE_NAME     U25W13 3
 '@BASEBOARD_FAB2_LIB.BASEBOARD_FAB2(SCH_1):PAGE269_I53@W_HDL.MAX4564EKA-GP(CHIPS)':
 'IN': CDS_PINID='\in\';
NET_NAME
'BMC_TPM_HW_C_RST'
 '@BASEBOARD_FAB2_LIB.BASEBOARD_FAB2(SCH_1):BMC_TPM_HW_C_RST':
 C_SIGNAL='@baseboard_fab2_lib.baseboard_fab2(sch_1):bmc_tpm_hw_c_rst';
NODE_NAME     Q9W1 1
 '@BASEBOARD_FAB2_LIB.BASEBOARD_FAB2(SCH_1):PAGE249_I30@MSTR_DISCRETE.FET_N(CHIPS)':
 'GATE': CDS_PINID='GATE';
NODE_NAME     C8W1 2
 '@BASEBOARD_FAB2_LIB.BASEBOARD_FAB2(SCH_1):PAGE249_I52@W_HDL.SC1U16V3KX-2GP(CHIPS)':
 '2': CDS_PINID='\2\';
NODE_NAME     R3W2 1
 '@BASEBOARD_FAB2_LIB.BASEBOARD_FAB2(SCH_1):PAGE249_I56@MSTR_DISCRETE.RES(CHIPS)':
 'A': CDS_PINID='A';
NODE_NAME     C3W2 1
 '@BASEBOARD_FAB2_LIB.BASEBOARD_FAB2(SCH_1):PAGE249_I57@DEV_DISCRETE.CAP_A(CHIPS)':
 'A': CDS_PINID='A';
NET_NAME
'BMC_VGA_BLUE'
 '@BASEBOARD_FAB2_LIB.BASEBOARD_FAB2(SCH_1):BMC_VGA_BLUE':
 C_SIGNAL='@baseboard_fab2_lib.baseboard_fab2(sch_1):bmc_vga_blue';
NODE_NAME     U25W4 J2
 '@BASEBOARD_FAB2_LIB.BASEBOARD_FAB2(SCH_1):PAGE144_I95@W_HDL.AST2520A1-GP-GP(CHIPS)':
 'DACB': CDS_PINID='DACB';
NODE_NAME     R25W123 1
 '@BASEBOARD_FAB2_LIB.BASEBOARD_FAB2(SCH_1):PAGE144_I139@MSTR_DISCRETE.RES(CHIPS)':
 'A': CDS_PINID='A';
NODE_NAME     C25W72 1
 '@BASEBOARD_FAB2_LIB.BASEBOARD_FAB2(SCH_1):PAGE255_I7@MSTR_DISCRETE.CAP(CHIPS)':
 'A': CDS_PINID='A';
NODE_NAME     L25W1 1
 '@BASEBOARD_FAB2_LIB.BASEBOARD_FAB2(SCH_1):PAGE255_I76@W_HDL.IND-68NH-15-GP(CHIPS)':
 '1': CDS_PINID='\1\';
NET_NAME
'BMC_VGA_GREEN'
 '@BASEBOARD_FAB2_LIB.BASEBOARD_FAB2(SCH_1):BMC_VGA_GREEN':
 C_SIGNAL='@baseboard_fab2_lib.baseboard_fab2(sch_1):bmc_vga_green';
NODE_NAME     U25W4 J3
 '@BASEBOARD_FAB2_LIB.BASEBOARD_FAB2(SCH_1):PAGE144_I95@W_HDL.AST2520A1-GP-GP(CHIPS)':
 'DACG': CDS_PINID='DACG';
NODE_NAME     R25W124 1
 '@BASEBOARD_FAB2_LIB.BASEBOARD_FAB2(SCH_1):PAGE144_I140@MSTR_DISCRETE.RES(CHIPS)':
 'A': CDS_PINID='A';
NODE_NAME     C25W73 1
 '@BASEBOARD_FAB2_LIB.BASEBOARD_FAB2(SCH_1):PAGE255_I11@MSTR_DISCRETE.CAP(CHIPS)':
 'A': CDS_PINID='A';
NODE_NAME     L25W2 1
 '@BASEBOARD_FAB2_LIB.BASEBOARD_FAB2(SCH_1):PAGE255_I77@W_HDL.IND-68NH-15-GP(CHIPS)':
 '1': CDS_PINID='\1\';
NET_NAME
'BMC_VGA_HSYNC'
 '@BASEBOARD_FAB2_LIB.BASEBOARD_FAB2(SCH_1):BMC_VGA_HSYNC':
 C_SIGNAL='@baseboard_fab2_lib.baseboard_fab2(sch_1):bmc_vga_hsync';
NODE_NAME     U25W4 N5
 '@BASEBOARD_FAB2_LIB.BASEBOARD_FAB2(SCH_1):PAGE146_I105@W_HDL.AST2520A1-GP-GP(CHIPS)':
 'GPIOJ4_VGAHS': CDS_PINID='GPIOJ4_VGAHS';
NODE_NAME     U25W7 2
 '@BASEBOARD_FAB2_LIB.BASEBOARD_FAB2(SCH_1):PAGE255_I111@W_HDL.U74AHCT1G125G-AL5-R-GP-U(CHIPS)':
 'A': CDS_PINID='A';
NET_NAME
'BMC_VGA_RED'
 '@BASEBOARD_FAB2_LIB.BASEBOARD_FAB2(SCH_1):BMC_VGA_RED':
 C_SIGNAL='@baseboard_fab2_lib.baseboard_fab2(sch_1):bmc_vga_red';
NODE_NAME     U25W4 J4
 '@BASEBOARD_FAB2_LIB.BASEBOARD_FAB2(SCH_1):PAGE144_I95@W_HDL.AST2520A1-GP-GP(CHIPS)':
 'DACR': CDS_PINID='DACR';
NODE_NAME     R25W125 1
 '@BASEBOARD_FAB2_LIB.BASEBOARD_FAB2(SCH_1):PAGE144_I141@MSTR_DISCRETE.RES(CHIPS)':
 'A': CDS_PINID='A';
NODE_NAME     C25W74 1
 '@BASEBOARD_FAB2_LIB.BASEBOARD_FAB2(SCH_1):PAGE255_I12@MSTR_DISCRETE.CAP(CHIPS)':
 'A': CDS_PINID='A';
NODE_NAME     L25W3 1
 '@BASEBOARD_FAB2_LIB.BASEBOARD_FAB2(SCH_1):PAGE255_I78@W_HDL.IND-68NH-15-GP(CHIPS)':
 '1': CDS_PINID='\1\';
NET_NAME
'BMC_VGA_VSYNC'
 '@BASEBOARD_FAB2_LIB.BASEBOARD_FAB2(SCH_1):BMC_VGA_VSYNC':
 C_SIGNAL='@baseboard_fab2_lib.baseboard_fab2(sch_1):bmc_vga_vsync';
NODE_NAME     U25W4 R4
 '@BASEBOARD_FAB2_LIB.BASEBOARD_FAB2(SCH_1):PAGE146_I105@W_HDL.AST2520A1-GP-GP(CHIPS)':
 'GPIOJ5_VGAVS': CDS_PINID='GPIOJ5_VGAVS';
NODE_NAME     U25W8 2
 '@BASEBOARD_FAB2_LIB.BASEBOARD_FAB2(SCH_1):PAGE255_I112@W_HDL.U74AHCT1G125G-AL5-R-GP-U(CHIPS)':
 'A': CDS_PINID='A';
NET_NAME
'BMC_ZQ'
 '@BASEBOARD_FAB2_LIB.BASEBOARD_FAB2(SCH_1):BMC_ZQ':
 C_SIGNAL='@baseboard_fab2_lib.baseboard_fab2(sch_1):bmc_zq';
NODE_NAME     U25W5 F9
 '@BASEBOARD_FAB2_LIB.BASEBOARD_FAB2(SCH_1):PAGE151_I49@W_HDL.H5AN4G6NAFR-TFC-GP(CHIPS)':
 'ZQ': CDS_PINID='ZQ';
NODE_NAME     R25W117 1
 '@BASEBOARD_FAB2_LIB.BASEBOARD_FAB2(SCH_1):PAGE151_I101@MSTR_DISCRETE.RES(CHIPS)':
 'A': CDS_PINID='A';
NET_NAME
'CLK_100M_AIRMAX8_PE1_DN'
 '@BASEBOARD_FAB2_LIB.BASEBOARD_FAB2(SCH_1):CLK_100M_AIRMAX8_PE1_DN':
 C_SIGNAL='@baseboard_fab2_lib.baseboard_fab2(sch_1):clk_100m_airmax8_pe1_dn';
NODE_NAME     U7C1 K38
 '@BASEBOARD_FAB2_LIB.BASEBOARD_FAB2(SCH_1):PAGE114_I40@MSTR_U_PROC.LBG_CORE_QAT_EXT_D(CHIPS)':
 'CLKOUT_SRCN'<0>: CDS_PINID='CLKOUT_SRCN(0)';
NODE_NAME     J1F1 I4
 '@BASEBOARD_FAB2_LIB.BASEBOARD_FAB2(SCH_1):PAGE181_I134@W_HDL.DM-FCI-CONN76-8R-GP-U-01(CHIPS)':
 'PCIE_CLK_100M_DN': CDS_PINID='PCIE_CLK_100M_DN';
NET_NAME
'CLK_100M_AIRMAX8_PE1_DP'
 '@BASEBOARD_FAB2_LIB.BASEBOARD_FAB2(SCH_1):CLK_100M_AIRMAX8_PE1_DP':
 C_SIGNAL='@baseboard_fab2_lib.baseboard_fab2(sch_1):clk_100m_airmax8_pe1_dp';
NODE_NAME     U7C1 H38
 '@BASEBOARD_FAB2_LIB.BASEBOARD_FAB2(SCH_1):PAGE114_I40@MSTR_U_PROC.LBG_CORE_QAT_EXT_D(CHIPS)':
 'CLKOUT_SRCP'<0>: CDS_PINID='CLKOUT_SRCP(0)';
NODE_NAME     J1F1 H4
 '@BASEBOARD_FAB2_LIB.BASEBOARD_FAB2(SCH_1):PAGE181_I134@W_HDL.DM-FCI-CONN76-8R-GP-U-01(CHIPS)':
 'PCIE_CLK_100M_DP': CDS_PINID='PCIE_CLK_100M_DP';
NET_NAME
'CLK_100M_BMC_PE_DN'
 '@BASEBOARD_FAB2_LIB.BASEBOARD_FAB2(SCH_1):CLK_100M_BMC_PE_DN':
 C_SIGNAL='@baseboard_fab2_lib.baseboard_fab2(sch_1):clk_100m_bmc_pe_dn';
NODE_NAME     U7C1 B29
 '@BASEBOARD_FAB2_LIB.BASEBOARD_FAB2(SCH_1):PAGE114_I40@MSTR_U_PROC.LBG_CORE_QAT_EXT_D(CHIPS)':
 'CLKOUT_PLAT0N': CDS_PINID='CLKOUT_PLAT0N';
NODE_NAME     R7C2 2
 '@BASEBOARD_FAB2_LIB.BASEBOARD_FAB2(SCH_1):PAGE114_I192@MSTR_DISCRETE.RES(CHIPS)':
 'B': CDS_PINID='B';
NET_NAME
'CLK_100M_BMC_PE_DP'
 '@BASEBOARD_FAB2_LIB.BASEBOARD_FAB2(SCH_1):CLK_100M_BMC_PE_DP':
 C_SIGNAL='@baseboard_fab2_lib.baseboard_fab2(sch_1):clk_100m_bmc_pe_dp';
NODE_NAME     U7C1 D29
 '@BASEBOARD_FAB2_LIB.BASEBOARD_FAB2(SCH_1):PAGE114_I40@MSTR_U_PROC.LBG_CORE_QAT_EXT_D(CHIPS)':
 'CLKOUT_PLAT0P': CDS_PINID='CLKOUT_PLAT0P';
NODE_NAME     R7C4 2
 '@BASEBOARD_FAB2_LIB.BASEBOARD_FAB2(SCH_1):PAGE114_I191@MSTR_DISCRETE.RES(CHIPS)':
 'B': CDS_PINID='B';
NET_NAME
'CLK_100M_BMC_PE_R_DN'
 '@BASEBOARD_FAB2_LIB.BASEBOARD_FAB2(SCH_1):CLK_100M_BMC_PE_R_DN':
 C_SIGNAL='@baseboard_fab2_lib.baseboard_fab2(sch_1):clk_100m_bmc_pe_r_dn';
NODE_NAME     R25W60 1
 '@BASEBOARD_FAB2_LIB.BASEBOARD_FAB2(SCH_1):PAGE145_I34@MSTR_DISCRETE.RES(CHIPS)':
 'A': CDS_PINID='A';
NODE_NAME     U25W4 K22
 '@BASEBOARD_FAB2_LIB.BASEBOARD_FAB2(SCH_1):PAGE145_I117@W_HDL.AST2520A1-GP-GP(CHIPS)':
 'PEREFCLKN': CDS_PINID='PEREFCLKN';
NODE_NAME     R7C2 1
 '@BASEBOARD_FAB2_LIB.BASEBOARD_FAB2(SCH_1):PAGE114_I192@MSTR_DISCRETE.RES(CHIPS)':
 'A': CDS_PINID='A';
NET_NAME
'CLK_100M_BMC_PE_R_DP'
 '@BASEBOARD_FAB2_LIB.BASEBOARD_FAB2(SCH_1):CLK_100M_BMC_PE_R_DP':
 C_SIGNAL='@baseboard_fab2_lib.baseboard_fab2(sch_1):clk_100m_bmc_pe_r_dp';
NODE_NAME     R25W61 1
 '@BASEBOARD_FAB2_LIB.BASEBOARD_FAB2(SCH_1):PAGE145_I30@MSTR_DISCRETE.RES(CHIPS)':
 'A': CDS_PINID='A';
NODE_NAME     U25W4 K21
 '@BASEBOARD_FAB2_LIB.BASEBOARD_FAB2(SCH_1):PAGE145_I117@W_HDL.AST2520A1-GP-GP(CHIPS)':
 'PEREFCLKP': CDS_PINID='PEREFCLKP';
NODE_NAME     R7C4 1
 '@BASEBOARD_FAB2_LIB.BASEBOARD_FAB2(SCH_1):PAGE114_I191@MSTR_DISCRETE.RES(CHIPS)':
 'A': CDS_PINID='A';
NET_NAME
'CLK_100M_CPU0_BCLK0_DN'
 '@BASEBOARD_FAB2_LIB.BASEBOARD_FAB2(SCH_1):CLK_100M_CPU0_BCLK0_DN':
 C_SIGNAL='@baseboard_fab2_lib.baseboard_fab2(sch_1):clk_100m_cpu0_bclk0_dn';
NODE_NAME     U5D1 AU24
 '@BASEBOARD_FAB2_LIB.BASEBOARD_FAB2(SCH_1):PAGE21_I259@CHPSET_LIB.SKX_EXT_B(CHIPS)':
 'BCLK0_DN': CDS_PINID='BCLK0_DN';
NODE_NAME     R4D25 2
 '@BASEBOARD_FAB2_LIB.BASEBOARD_FAB2(SCH_1):PAGE103_I1@MSTR_DISCRETE.RES(CHIPS)':
 'B': CDS_PINID='B';
NODE_NAME     R6P15 1
 '@BASEBOARD_FAB2_LIB.BASEBOARD_FAB2(SCH_1):PAGE103_I167@MSTR_DISCRETE.RES(CHIPS)':
 'A': CDS_PINID='A';
NET_NAME
'CLK_100M_CPU0_BCLK0_DP'
 '@BASEBOARD_FAB2_LIB.BASEBOARD_FAB2(SCH_1):CLK_100M_CPU0_BCLK0_DP':
 C_SIGNAL='@baseboard_fab2_lib.baseboard_fab2(sch_1):clk_100m_cpu0_bclk0_dp';
NODE_NAME     U5D1 AW24
 '@BASEBOARD_FAB2_LIB.BASEBOARD_FAB2(SCH_1):PAGE21_I259@CHPSET_LIB.SKX_EXT_B(CHIPS)':
 'BCLK0_DP': CDS_PINID='BCLK0_DP';
NODE_NAME     R4D29 2
 '@BASEBOARD_FAB2_LIB.BASEBOARD_FAB2(SCH_1):PAGE103_I69@MSTR_DISCRETE.RES(CHIPS)':
 'B': CDS_PINID='B';
NODE_NAME     R6P17 1
 '@BASEBOARD_FAB2_LIB.BASEBOARD_FAB2(SCH_1):PAGE103_I165@MSTR_DISCRETE.RES(CHIPS)':
 'A': CDS_PINID='A';
NET_NAME
'CLK_100M_CPU0_BCLK0_R_DN'
 '@BASEBOARD_FAB2_LIB.BASEBOARD_FAB2(SCH_1):CLK_100M_CPU0_BCLK0_R_DN':
 C_SIGNAL='@baseboard_fab2_lib.baseboard_fab2(sch_1):clk_100m_cpu0_bclk0_r_dn';
NODE_NAME     EU4D2 18
 '@BASEBOARD_FAB2_LIB.BASEBOARD_FAB2(SCH_1):PAGE102_I1@MSTR_CLOCK.NB3W1200L(CHIPS)':
 'DIF_0N': CDS_PINID='DIF_0N';
NODE_NAME     R4D25 1
 '@BASEBOARD_FAB2_LIB.BASEBOARD_FAB2(SCH_1):PAGE103_I1@MSTR_DISCRETE.RES(CHIPS)':
 'A': CDS_PINID='A';
NET_NAME
'CLK_100M_CPU0_BCLK0_R_DP'
 '@BASEBOARD_FAB2_LIB.BASEBOARD_FAB2(SCH_1):CLK_100M_CPU0_BCLK0_R_DP':
 C_SIGNAL='@baseboard_fab2_lib.baseboard_fab2(sch_1):clk_100m_cpu0_bclk0_r_dp';
NODE_NAME     EU4D2 17
 '@BASEBOARD_FAB2_LIB.BASEBOARD_FAB2(SCH_1):PAGE102_I1@MSTR_CLOCK.NB3W1200L(CHIPS)':
 'DIF_0P': CDS_PINID='DIF_0P';
NODE_NAME     R4D29 1
 '@BASEBOARD_FAB2_LIB.BASEBOARD_FAB2(SCH_1):PAGE103_I69@MSTR_DISCRETE.RES(CHIPS)':
 'A': CDS_PINID='A';
NET_NAME
'CLK_100M_CPU0_BCLK1_DN'
 '@BASEBOARD_FAB2_LIB.BASEBOARD_FAB2(SCH_1):CLK_100M_CPU0_BCLK1_DN':
 C_SIGNAL='@baseboard_fab2_lib.baseboard_fab2(sch_1):clk_100m_cpu0_bclk1_dn';
NODE_NAME     U5D1 CR26
 '@BASEBOARD_FAB2_LIB.BASEBOARD_FAB2(SCH_1):PAGE21_I259@CHPSET_LIB.SKX_EXT_B(CHIPS)':
 'BCLK1_DN': CDS_PINID='BCLK1_DN';
NODE_NAME     R4D20 2
 '@BASEBOARD_FAB2_LIB.BASEBOARD_FAB2(SCH_1):PAGE103_I119@MSTR_DISCRETE.RES(CHIPS)':
 'B': CDS_PINID='B';
NODE_NAME     R4D18 1
 '@BASEBOARD_FAB2_LIB.BASEBOARD_FAB2(SCH_1):PAGE103_I163@MSTR_DISCRETE.RES(CHIPS)':
 'A': CDS_PINID='A';
NET_NAME
'CLK_100M_CPU0_BCLK1_DP'
 '@BASEBOARD_FAB2_LIB.BASEBOARD_FAB2(SCH_1):CLK_100M_CPU0_BCLK1_DP':
 C_SIGNAL='@baseboard_fab2_lib.baseboard_fab2(sch_1):clk_100m_cpu0_bclk1_dp';
NODE_NAME     U5D1 CP27
 '@BASEBOARD_FAB2_LIB.BASEBOARD_FAB2(SCH_1):PAGE21_I259@CHPSET_LIB.SKX_EXT_B(CHIPS)':
 'BCLK1_DP': CDS_PINID='BCLK1_DP';
NODE_NAME     R4D22 2
 '@BASEBOARD_FAB2_LIB.BASEBOARD_FAB2(SCH_1):PAGE103_I114@MSTR_DISCRETE.RES(CHIPS)':
 'B': CDS_PINID='B';
NODE_NAME     R4D24 1
 '@BASEBOARD_FAB2_LIB.BASEBOARD_FAB2(SCH_1):PAGE103_I161@MSTR_DISCRETE.RES(CHIPS)':
 'A': CDS_PINID='A';
NET_NAME
'CLK_100M_CPU0_BCLK1_R_DN'
 '@BASEBOARD_FAB2_LIB.BASEBOARD_FAB2(SCH_1):CLK_100M_CPU0_BCLK1_R_DN':
 C_SIGNAL='@baseboard_fab2_lib.baseboard_fab2(sch_1):clk_100m_cpu0_bclk1_r_dn';
NODE_NAME     EU4D2 22
 '@BASEBOARD_FAB2_LIB.BASEBOARD_FAB2(SCH_1):PAGE102_I1@MSTR_CLOCK.NB3W1200L(CHIPS)':
 'DIF_1N': CDS_PINID='DIF_1N';
NODE_NAME     R4D20 1
 '@BASEBOARD_FAB2_LIB.BASEBOARD_FAB2(SCH_1):PAGE103_I119@MSTR_DISCRETE.RES(CHIPS)':
 'A': CDS_PINID='A';
NET_NAME
'CLK_100M_CPU0_BCLK1_R_DP'
 '@BASEBOARD_FAB2_LIB.BASEBOARD_FAB2(SCH_1):CLK_100M_CPU0_BCLK1_R_DP':
 C_SIGNAL='@baseboard_fab2_lib.baseboard_fab2(sch_1):clk_100m_cpu0_bclk1_r_dp';
NODE_NAME     EU4D2 21
 '@BASEBOARD_FAB2_LIB.BASEBOARD_FAB2(SCH_1):PAGE102_I1@MSTR_CLOCK.NB3W1200L(CHIPS)':
 'DIF_1P': CDS_PINID='DIF_1P';
NODE_NAME     R4D22 1
 '@BASEBOARD_FAB2_LIB.BASEBOARD_FAB2(SCH_1):PAGE103_I114@MSTR_DISCRETE.RES(CHIPS)':
 'A': CDS_PINID='A';
NET_NAME
'CLK_100M_CPU0_BCLK2_DN'
 '@BASEBOARD_FAB2_LIB.BASEBOARD_FAB2(SCH_1):CLK_100M_CPU0_BCLK2_DN':
 C_SIGNAL='@baseboard_fab2_lib.baseboard_fab2(sch_1):clk_100m_cpu0_bclk2_dn';
NODE_NAME     U5D1 CT25
 '@BASEBOARD_FAB2_LIB.BASEBOARD_FAB2(SCH_1):PAGE21_I259@CHPSET_LIB.SKX_EXT_B(CHIPS)':
 'BCLK2_DN': CDS_PINID='BCLK2_DN';
NODE_NAME     R4D14 2
 '@BASEBOARD_FAB2_LIB.BASEBOARD_FAB2(SCH_1):PAGE103_I109@MSTR_DISCRETE.RES(CHIPS)':
 'B': CDS_PINID='B';
NODE_NAME     R6P12 1
 '@BASEBOARD_FAB2_LIB.BASEBOARD_FAB2(SCH_1):PAGE103_I159@MSTR_DISCRETE.RES(CHIPS)':
 'A': CDS_PINID='A';
NET_NAME
'CLK_100M_CPU0_BCLK2_DP'
 '@BASEBOARD_FAB2_LIB.BASEBOARD_FAB2(SCH_1):CLK_100M_CPU0_BCLK2_DP':
 C_SIGNAL='@baseboard_fab2_lib.baseboard_fab2(sch_1):clk_100m_cpu0_bclk2_dp';
NODE_NAME     U5D1 CU26
 '@BASEBOARD_FAB2_LIB.BASEBOARD_FAB2(SCH_1):PAGE21_I259@CHPSET_LIB.SKX_EXT_B(CHIPS)':
 'BCLK2_DP': CDS_PINID='BCLK2_DP';
NODE_NAME     R4D17 2
 '@BASEBOARD_FAB2_LIB.BASEBOARD_FAB2(SCH_1):PAGE103_I104@MSTR_DISCRETE.RES(CHIPS)':
 'B': CDS_PINID='B';
NODE_NAME     R6P13 1
 '@BASEBOARD_FAB2_LIB.BASEBOARD_FAB2(SCH_1):PAGE103_I157@MSTR_DISCRETE.RES(CHIPS)':
 'A': CDS_PINID='A';
NET_NAME
'CLK_100M_CPU0_BCLK2_R_DN'
 '@BASEBOARD_FAB2_LIB.BASEBOARD_FAB2(SCH_1):CLK_100M_CPU0_BCLK2_R_DN':
 C_SIGNAL='@baseboard_fab2_lib.baseboard_fab2(sch_1):clk_100m_cpu0_bclk2_r_dn';
NODE_NAME     EU4D2 27
 '@BASEBOARD_FAB2_LIB.BASEBOARD_FAB2(SCH_1):PAGE102_I1@MSTR_CLOCK.NB3W1200L(CHIPS)':
 'DIF_2N': CDS_PINID='DIF_2N';
NODE_NAME     R4D14 1
 '@BASEBOARD_FAB2_LIB.BASEBOARD_FAB2(SCH_1):PAGE103_I109@MSTR_DISCRETE.RES(CHIPS)':
 'A': CDS_PINID='A';
NET_NAME
'CLK_100M_CPU0_BCLK2_R_DP'
 '@BASEBOARD_FAB2_LIB.BASEBOARD_FAB2(SCH_1):CLK_100M_CPU0_BCLK2_R_DP':
 C_SIGNAL='@baseboard_fab2_lib.baseboard_fab2(sch_1):clk_100m_cpu0_bclk2_r_dp';
NODE_NAME     EU4D2 26
 '@BASEBOARD_FAB2_LIB.BASEBOARD_FAB2(SCH_1):PAGE102_I1@MSTR_CLOCK.NB3W1200L(CHIPS)':
 'DIF_2P': CDS_PINID='DIF_2P';
NODE_NAME     R4D17 1
 '@BASEBOARD_FAB2_LIB.BASEBOARD_FAB2(SCH_1):PAGE103_I104@MSTR_DISCRETE.RES(CHIPS)':
 'A': CDS_PINID='A';
NET_NAME
'CLK_100M_CPU0_PE_REFCLK_DN'
 '@BASEBOARD_FAB2_LIB.BASEBOARD_FAB2(SCH_1):CLK_100M_CPU0_PE_REFCLK_DN':
 C_SIGNAL='@baseboard_fab2_lib.baseboard_fab2(sch_1):clk_100m_cpu0_pe_refclk_dn';
NODE_NAME     U5D1 BU24
 '@BASEBOARD_FAB2_LIB.BASEBOARD_FAB2(SCH_1):PAGE29_I61@CHPSET_LIB.SKX_EXT_B(CHIPS)':
 'CD_PE_REFCLK_DN': CDS_PINID='CD_PE_REFCLK_DN';
NODE_NAME     R4D10 2
 '@BASEBOARD_FAB2_LIB.BASEBOARD_FAB2(SCH_1):PAGE103_I99@MSTR_DISCRETE.RES(CHIPS)':
 'B': CDS_PINID='B';
NODE_NAME     R6P9 1
 '@BASEBOARD_FAB2_LIB.BASEBOARD_FAB2(SCH_1):PAGE103_I155@MSTR_DISCRETE.RES(CHIPS)':
 'A': CDS_PINID='A';
NET_NAME
'CLK_100M_CPU0_PE_REFCLK_DP'
 '@BASEBOARD_FAB2_LIB.BASEBOARD_FAB2(SCH_1):CLK_100M_CPU0_PE_REFCLK_DP':
 C_SIGNAL='@baseboard_fab2_lib.baseboard_fab2(sch_1):clk_100m_cpu0_pe_refclk_dp';
NODE_NAME     U5D1 BW24
 '@BASEBOARD_FAB2_LIB.BASEBOARD_FAB2(SCH_1):PAGE29_I61@CHPSET_LIB.SKX_EXT_B(CHIPS)':
 'CD_PE_REFCLK_DP': CDS_PINID='CD_PE_REFCLK_DP';
NODE_NAME     R4D12 2
 '@BASEBOARD_FAB2_LIB.BASEBOARD_FAB2(SCH_1):PAGE103_I94@MSTR_DISCRETE.RES(CHIPS)':
 'B': CDS_PINID='B';
NODE_NAME     R6P11 1
 '@BASEBOARD_FAB2_LIB.BASEBOARD_FAB2(SCH_1):PAGE103_I153@MSTR_DISCRETE.RES(CHIPS)':
 'A': CDS_PINID='A';
NET_NAME
'CLK_100M_CPU0_PE_REFCLK_R_DN'
 '@BASEBOARD_FAB2_LIB.BASEBOARD_FAB2(SCH_1):CLK_100M_CPU0_PE_REFCLK_R_DN':
 C_SIGNAL='@baseboard_fab2_lib.baseboard_fab2(sch_1):clk_100m_cpu0_pe_refclk_r_d~
n';
NODE_NAME     EU4D2 31
 '@BASEBOARD_FAB2_LIB.BASEBOARD_FAB2(SCH_1):PAGE102_I1@MSTR_CLOCK.NB3W1200L(CHIPS)':
 'DIF_3N': CDS_PINID='DIF_3N';
NODE_NAME     R4D10 1
 '@BASEBOARD_FAB2_LIB.BASEBOARD_FAB2(SCH_1):PAGE103_I99@MSTR_DISCRETE.RES(CHIPS)':
 'A': CDS_PINID='A';
NET_NAME
'CLK_100M_CPU0_PE_REFCLK_R_DP'
 '@BASEBOARD_FAB2_LIB.BASEBOARD_FAB2(SCH_1):CLK_100M_CPU0_PE_REFCLK_R_DP':
 C_SIGNAL='@baseboard_fab2_lib.baseboard_fab2(sch_1):clk_100m_cpu0_pe_refclk_r_d~
p';
NODE_NAME     EU4D2 30
 '@BASEBOARD_FAB2_LIB.BASEBOARD_FAB2(SCH_1):PAGE102_I1@MSTR_CLOCK.NB3W1200L(CHIPS)':
 'DIF_3P': CDS_PINID='DIF_3P';
NODE_NAME     R4D12 1
 '@BASEBOARD_FAB2_LIB.BASEBOARD_FAB2(SCH_1):PAGE103_I94@MSTR_DISCRETE.RES(CHIPS)':
 'A': CDS_PINID='A';
NET_NAME
'CLK_100M_CPU0_RC_REFCLK0_DN'
 '@BASEBOARD_FAB2_LIB.BASEBOARD_FAB2(SCH_1):CLK_100M_CPU0_RC_REFCLK0_DN':
 C_SIGNAL='@baseboard_fab2_lib.baseboard_fab2(sch_1):clk_100m_cpu0_rc_refclk0_dn~
';
NODE_NAME     U5D1 AP27
 '@BASEBOARD_FAB2_LIB.BASEBOARD_FAB2(SCH_1):PAGE22_I204@CHPSET_LIB.SKX_EXT_B(CHIPS)':
 'RSVD'<195>: CDS_PINID='RSVD(195)';
NODE_NAME     R4D7 2
 '@BASEBOARD_FAB2_LIB.BASEBOARD_FAB2(SCH_1):PAGE103_I89@MSTR_DISCRETE.RES(CHIPS)':
 'B': CDS_PINID='B';
NODE_NAME     R6P2 1
 '@BASEBOARD_FAB2_LIB.BASEBOARD_FAB2(SCH_1):PAGE103_I151@MSTR_DISCRETE.RES(CHIPS)':
 'A': CDS_PINID='A';
NET_NAME
'CLK_100M_CPU0_RC_REFCLK0_DP'
 '@BASEBOARD_FAB2_LIB.BASEBOARD_FAB2(SCH_1):CLK_100M_CPU0_RC_REFCLK0_DP':
 C_SIGNAL='@baseboard_fab2_lib.baseboard_fab2(sch_1):clk_100m_cpu0_rc_refclk0_dp~
';
NODE_NAME     U5D1 AM27
 '@BASEBOARD_FAB2_LIB.BASEBOARD_FAB2(SCH_1):PAGE22_I204@CHPSET_LIB.SKX_EXT_B(CHIPS)':
 'RSVD'<206>: CDS_PINID='RSVD(206)';
NODE_NAME     R4D8 2
 '@BASEBOARD_FAB2_LIB.BASEBOARD_FAB2(SCH_1):PAGE103_I84@MSTR_DISCRETE.RES(CHIPS)':
 'B': CDS_PINID='B';
NODE_NAME     R6P1 1
 '@BASEBOARD_FAB2_LIB.BASEBOARD_FAB2(SCH_1):PAGE103_I149@MSTR_DISCRETE.RES(CHIPS)':
 'A': CDS_PINID='A';
NET_NAME
'CLK_100M_CPU0_RC_REFCLK0_R_DN'
 '@BASEBOARD_FAB2_LIB.BASEBOARD_FAB2(SCH_1):CLK_100M_CPU0_RC_REFCLK0_R_DN':
 C_SIGNAL='@baseboard_fab2_lib.baseboard_fab2(sch_1):clk_100m_cpu0_rc_refclk0_r_~
dn';
NODE_NAME     EU4D2 35
 '@BASEBOARD_FAB2_LIB.BASEBOARD_FAB2(SCH_1):PAGE102_I1@MSTR_CLOCK.NB3W1200L(CHIPS)':
 'DIF_4N': CDS_PINID='DIF_4N';
NODE_NAME     R4D7 1
 '@BASEBOARD_FAB2_LIB.BASEBOARD_FAB2(SCH_1):PAGE103_I89@MSTR_DISCRETE.RES(CHIPS)':
 'A': CDS_PINID='A';
NET_NAME
'CLK_100M_CPU0_RC_REFCLK0_R_DP'
 '@BASEBOARD_FAB2_LIB.BASEBOARD_FAB2(SCH_1):CLK_100M_CPU0_RC_REFCLK0_R_DP':
 C_SIGNAL='@baseboard_fab2_lib.baseboard_fab2(sch_1):clk_100m_cpu0_rc_refclk0_r_~
dp';
NODE_NAME     EU4D2 34
 '@BASEBOARD_FAB2_LIB.BASEBOARD_FAB2(SCH_1):PAGE102_I1@MSTR_CLOCK.NB3W1200L(CHIPS)':
 'DIF_4P': CDS_PINID='DIF_4P';
NODE_NAME     R4D8 1
 '@BASEBOARD_FAB2_LIB.BASEBOARD_FAB2(SCH_1):PAGE103_I84@MSTR_DISCRETE.RES(CHIPS)':
 'A': CDS_PINID='A';
NET_NAME
'CLK_100M_CPU0_RC_REFCLK1_DN'
 '@BASEBOARD_FAB2_LIB.BASEBOARD_FAB2(SCH_1):CLK_100M_CPU0_RC_REFCLK1_DN':
 C_SIGNAL='@baseboard_fab2_lib.baseboard_fab2(sch_1):clk_100m_cpu0_rc_refclk1_dn~
';
NODE_NAME     U5D1 BB25
 '@BASEBOARD_FAB2_LIB.BASEBOARD_FAB2(SCH_1):PAGE36_I15@CHPSET_LIB.SKX_EXT_B(CHIPS)':
 'RSVD'<165>: CDS_PINID='RSVD(165)';
NODE_NAME     R4D5 2
 '@BASEBOARD_FAB2_LIB.BASEBOARD_FAB2(SCH_1):PAGE103_I79@MSTR_DISCRETE.RES(CHIPS)':
 'B': CDS_PINID='B';
NODE_NAME     R6P4 1
 '@BASEBOARD_FAB2_LIB.BASEBOARD_FAB2(SCH_1):PAGE103_I147@MSTR_DISCRETE.RES(CHIPS)':
 'A': CDS_PINID='A';
NET_NAME
'CLK_100M_CPU0_RC_REFCLK1_DP'
 '@BASEBOARD_FAB2_LIB.BASEBOARD_FAB2(SCH_1):CLK_100M_CPU0_RC_REFCLK1_DP':
 C_SIGNAL='@baseboard_fab2_lib.baseboard_fab2(sch_1):clk_100m_cpu0_rc_refclk1_dp~
';
NODE_NAME     U5D1 BD25
 '@BASEBOARD_FAB2_LIB.BASEBOARD_FAB2(SCH_1):PAGE36_I15@CHPSET_LIB.SKX_EXT_B(CHIPS)':
 'RSVD'<153>: CDS_PINID='RSVD(153)';
NODE_NAME     R4D6 2
 '@BASEBOARD_FAB2_LIB.BASEBOARD_FAB2(SCH_1):PAGE103_I74@MSTR_DISCRETE.RES(CHIPS)':
 'B': CDS_PINID='B';
NODE_NAME     R6P3 1
 '@BASEBOARD_FAB2_LIB.BASEBOARD_FAB2(SCH_1):PAGE103_I145@MSTR_DISCRETE.RES(CHIPS)':
 'A': CDS_PINID='A';
NET_NAME
'CLK_100M_CPU0_RC_REFCLK1_R_DN'
 '@BASEBOARD_FAB2_LIB.BASEBOARD_FAB2(SCH_1):CLK_100M_CPU0_RC_REFCLK1_R_DN':
 C_SIGNAL='@baseboard_fab2_lib.baseboard_fab2(sch_1):clk_100m_cpu0_rc_refclk1_r_~
dn';
NODE_NAME     EU4D2 39
 '@BASEBOARD_FAB2_LIB.BASEBOARD_FAB2(SCH_1):PAGE102_I1@MSTR_CLOCK.NB3W1200L(CHIPS)':
 'DIF_5N': CDS_PINID='DIF_5N';
NODE_NAME     R4D5 1
 '@BASEBOARD_FAB2_LIB.BASEBOARD_FAB2(SCH_1):PAGE103_I79@MSTR_DISCRETE.RES(CHIPS)':
 'A': CDS_PINID='A';
NET_NAME
'CLK_100M_CPU0_RC_REFCLK1_R_DP'
 '@BASEBOARD_FAB2_LIB.BASEBOARD_FAB2(SCH_1):CLK_100M_CPU0_RC_REFCLK1_R_DP':
 C_SIGNAL='@baseboard_fab2_lib.baseboard_fab2(sch_1):clk_100m_cpu0_rc_refclk1_r_~
dp';
NODE_NAME     EU4D2 38
 '@BASEBOARD_FAB2_LIB.BASEBOARD_FAB2(SCH_1):PAGE102_I1@MSTR_CLOCK.NB3W1200L(CHIPS)':
 'DIF_5P': CDS_PINID='DIF_5P';
NODE_NAME     R4D6 1
 '@BASEBOARD_FAB2_LIB.BASEBOARD_FAB2(SCH_1):PAGE103_I74@MSTR_DISCRETE.RES(CHIPS)':
 'A': CDS_PINID='A';
NET_NAME
'CLK_100M_CPU1_BCLK0_DN'
 '@BASEBOARD_FAB2_LIB.BASEBOARD_FAB2(SCH_1):CLK_100M_CPU1_BCLK0_DN':
 C_SIGNAL='@baseboard_fab2_lib.baseboard_fab2(sch_1):clk_100m_cpu1_bclk0_dn';
NODE_NAME     U2D1 AU24
 '@BASEBOARD_FAB2_LIB.BASEBOARD_FAB2(SCH_1):PAGE55_I172@CHPSET_LIB.SKX_EXT_B(CHIPS)':
 'BCLK0_DN': CDS_PINID='BCLK0_DN';
NODE_NAME     R4D3 2
 '@BASEBOARD_FAB2_LIB.BASEBOARD_FAB2(SCH_1):PAGE103_I64@MSTR_DISCRETE.RES(CHIPS)':
 'B': CDS_PINID='B';
NODE_NAME     R6P6 1
 '@BASEBOARD_FAB2_LIB.BASEBOARD_FAB2(SCH_1):PAGE103_I143@MSTR_DISCRETE.RES(CHIPS)':
 'A': CDS_PINID='A';
NET_NAME
'CLK_100M_CPU1_BCLK0_DP'
 '@BASEBOARD_FAB2_LIB.BASEBOARD_FAB2(SCH_1):CLK_100M_CPU1_BCLK0_DP':
 C_SIGNAL='@baseboard_fab2_lib.baseboard_fab2(sch_1):clk_100m_cpu1_bclk0_dp';
NODE_NAME     U2D1 AW24
 '@BASEBOARD_FAB2_LIB.BASEBOARD_FAB2(SCH_1):PAGE55_I172@CHPSET_LIB.SKX_EXT_B(CHIPS)':
 'BCLK0_DP': CDS_PINID='BCLK0_DP';
NODE_NAME     R4D4 2
 '@BASEBOARD_FAB2_LIB.BASEBOARD_FAB2(SCH_1):PAGE103_I59@MSTR_DISCRETE.RES(CHIPS)':
 'B': CDS_PINID='B';
NODE_NAME     R6P5 1
 '@BASEBOARD_FAB2_LIB.BASEBOARD_FAB2(SCH_1):PAGE103_I141@MSTR_DISCRETE.RES(CHIPS)':
 'A': CDS_PINID='A';
NET_NAME
'CLK_100M_CPU1_BCLK0_R_DN'
 '@BASEBOARD_FAB2_LIB.BASEBOARD_FAB2(SCH_1):CLK_100M_CPU1_BCLK0_R_DN':
 C_SIGNAL='@baseboard_fab2_lib.baseboard_fab2(sch_1):clk_100m_cpu1_bclk0_r_dn';
NODE_NAME     EU4D2 43
 '@BASEBOARD_FAB2_LIB.BASEBOARD_FAB2(SCH_1):PAGE102_I1@MSTR_CLOCK.NB3W1200L(CHIPS)':
 'DIF_6N': CDS_PINID='DIF_6N';
NODE_NAME     R4D3 1
 '@BASEBOARD_FAB2_LIB.BASEBOARD_FAB2(SCH_1):PAGE103_I64@MSTR_DISCRETE.RES(CHIPS)':
 'A': CDS_PINID='A';
NET_NAME
'CLK_100M_CPU1_BCLK0_R_DP'
 '@BASEBOARD_FAB2_LIB.BASEBOARD_FAB2(SCH_1):CLK_100M_CPU1_BCLK0_R_DP':
 C_SIGNAL='@baseboard_fab2_lib.baseboard_fab2(sch_1):clk_100m_cpu1_bclk0_r_dp';
NODE_NAME     EU4D2 42
 '@BASEBOARD_FAB2_LIB.BASEBOARD_FAB2(SCH_1):PAGE102_I1@MSTR_CLOCK.NB3W1200L(CHIPS)':
 'DIF_6P': CDS_PINID='DIF_6P';
NODE_NAME     R4D4 1
 '@BASEBOARD_FAB2_LIB.BASEBOARD_FAB2(SCH_1):PAGE103_I59@MSTR_DISCRETE.RES(CHIPS)':
 'A': CDS_PINID='A';
NET_NAME
'CLK_100M_CPU1_BCLK1_DN'
 '@BASEBOARD_FAB2_LIB.BASEBOARD_FAB2(SCH_1):CLK_100M_CPU1_BCLK1_DN':
 C_SIGNAL='@baseboard_fab2_lib.baseboard_fab2(sch_1):clk_100m_cpu1_bclk1_dn';
NODE_NAME     U2D1 CR26
 '@BASEBOARD_FAB2_LIB.BASEBOARD_FAB2(SCH_1):PAGE55_I172@CHPSET_LIB.SKX_EXT_B(CHIPS)':
 'BCLK1_DN': CDS_PINID='BCLK1_DN';
NODE_NAME     R4D1 2
 '@BASEBOARD_FAB2_LIB.BASEBOARD_FAB2(SCH_1):PAGE103_I54@MSTR_DISCRETE.RES(CHIPS)':
 'B': CDS_PINID='B';
NODE_NAME     R6P8 1
 '@BASEBOARD_FAB2_LIB.BASEBOARD_FAB2(SCH_1):PAGE103_I139@MSTR_DISCRETE.RES(CHIPS)':
 'A': CDS_PINID='A';
NET_NAME
'CLK_100M_CPU1_BCLK1_DP'
 '@BASEBOARD_FAB2_LIB.BASEBOARD_FAB2(SCH_1):CLK_100M_CPU1_BCLK1_DP':
 C_SIGNAL='@baseboard_fab2_lib.baseboard_fab2(sch_1):clk_100m_cpu1_bclk1_dp';
NODE_NAME     U2D1 CP27
 '@BASEBOARD_FAB2_LIB.BASEBOARD_FAB2(SCH_1):PAGE55_I172@CHPSET_LIB.SKX_EXT_B(CHIPS)':
 'BCLK1_DP': CDS_PINID='BCLK1_DP';
NODE_NAME     R4D2 2
 '@BASEBOARD_FAB2_LIB.BASEBOARD_FAB2(SCH_1):PAGE103_I49@MSTR_DISCRETE.RES(CHIPS)':
 'B': CDS_PINID='B';
NODE_NAME     R6P7 1
 '@BASEBOARD_FAB2_LIB.BASEBOARD_FAB2(SCH_1):PAGE103_I137@MSTR_DISCRETE.RES(CHIPS)':
 'A': CDS_PINID='A';
NET_NAME
'CLK_100M_CPU1_BCLK1_R_DN'
 '@BASEBOARD_FAB2_LIB.BASEBOARD_FAB2(SCH_1):CLK_100M_CPU1_BCLK1_R_DN':
 C_SIGNAL='@baseboard_fab2_lib.baseboard_fab2(sch_1):clk_100m_cpu1_bclk1_r_dn';
NODE_NAME     EU4D2 47
 '@BASEBOARD_FAB2_LIB.BASEBOARD_FAB2(SCH_1):PAGE102_I1@MSTR_CLOCK.NB3W1200L(CHIPS)':
 'DIF_7N': CDS_PINID='DIF_7N';
NODE_NAME     R4D1 1
 '@BASEBOARD_FAB2_LIB.BASEBOARD_FAB2(SCH_1):PAGE103_I54@MSTR_DISCRETE.RES(CHIPS)':
 'A': CDS_PINID='A';
NET_NAME
'CLK_100M_CPU1_BCLK1_R_DP'
 '@BASEBOARD_FAB2_LIB.BASEBOARD_FAB2(SCH_1):CLK_100M_CPU1_BCLK1_R_DP':
 C_SIGNAL='@baseboard_fab2_lib.baseboard_fab2(sch_1):clk_100m_cpu1_bclk1_r_dp';
NODE_NAME     EU4D2 46
 '@BASEBOARD_FAB2_LIB.BASEBOARD_FAB2(SCH_1):PAGE102_I1@MSTR_CLOCK.NB3W1200L(CHIPS)':
 'DIF_7P': CDS_PINID='DIF_7P';
NODE_NAME     R4D2 1
 '@BASEBOARD_FAB2_LIB.BASEBOARD_FAB2(SCH_1):PAGE103_I49@MSTR_DISCRETE.RES(CHIPS)':
 'A': CDS_PINID='A';
NET_NAME
'CLK_100M_CPU1_BCLK2_DN'
 '@BASEBOARD_FAB2_LIB.BASEBOARD_FAB2(SCH_1):CLK_100M_CPU1_BCLK2_DN':
 C_SIGNAL='@baseboard_fab2_lib.baseboard_fab2(sch_1):clk_100m_cpu1_bclk2_dn';
NODE_NAME     U2D1 CT25
 '@BASEBOARD_FAB2_LIB.BASEBOARD_FAB2(SCH_1):PAGE55_I172@CHPSET_LIB.SKX_EXT_B(CHIPS)':
 'BCLK2_DN': CDS_PINID='BCLK2_DN';
NODE_NAME     R4D11 2
 '@BASEBOARD_FAB2_LIB.BASEBOARD_FAB2(SCH_1):PAGE103_I44@MSTR_DISCRETE.RES(CHIPS)':
 'B': CDS_PINID='B';
NODE_NAME     R7P2 1
 '@BASEBOARD_FAB2_LIB.BASEBOARD_FAB2(SCH_1):PAGE103_I135@MSTR_DISCRETE.RES(CHIPS)':
 'A': CDS_PINID='A';
NET_NAME
'CLK_100M_CPU1_BCLK2_DP'
 '@BASEBOARD_FAB2_LIB.BASEBOARD_FAB2(SCH_1):CLK_100M_CPU1_BCLK2_DP':
 C_SIGNAL='@baseboard_fab2_lib.baseboard_fab2(sch_1):clk_100m_cpu1_bclk2_dp';
NODE_NAME     U2D1 CU26
 '@BASEBOARD_FAB2_LIB.BASEBOARD_FAB2(SCH_1):PAGE55_I172@CHPSET_LIB.SKX_EXT_B(CHIPS)':
 'BCLK2_DP': CDS_PINID='BCLK2_DP';
NODE_NAME     R4D9 2
 '@BASEBOARD_FAB2_LIB.BASEBOARD_FAB2(SCH_1):PAGE103_I39@MSTR_DISCRETE.RES(CHIPS)':
 'B': CDS_PINID='B';
NODE_NAME     R7P1 1
 '@BASEBOARD_FAB2_LIB.BASEBOARD_FAB2(SCH_1):PAGE103_I133@MSTR_DISCRETE.RES(CHIPS)':
 'A': CDS_PINID='A';
NET_NAME
'CLK_100M_CPU1_BCLK2_R_DN'
 '@BASEBOARD_FAB2_LIB.BASEBOARD_FAB2(SCH_1):CLK_100M_CPU1_BCLK2_R_DN':
 C_SIGNAL='@baseboard_fab2_lib.baseboard_fab2(sch_1):clk_100m_cpu1_bclk2_r_dn';
NODE_NAME     EU4D2 51
 '@BASEBOARD_FAB2_LIB.BASEBOARD_FAB2(SCH_1):PAGE102_I1@MSTR_CLOCK.NB3W1200L(CHIPS)':
 'DIF_8N': CDS_PINID='DIF_8N';
NODE_NAME     R4D11 1
 '@BASEBOARD_FAB2_LIB.BASEBOARD_FAB2(SCH_1):PAGE103_I44@MSTR_DISCRETE.RES(CHIPS)':
 'A': CDS_PINID='A';
NET_NAME
'CLK_100M_CPU1_BCLK2_R_DP'
 '@BASEBOARD_FAB2_LIB.BASEBOARD_FAB2(SCH_1):CLK_100M_CPU1_BCLK2_R_DP':
 C_SIGNAL='@baseboard_fab2_lib.baseboard_fab2(sch_1):clk_100m_cpu1_bclk2_r_dp';
NODE_NAME     EU4D2 50
 '@BASEBOARD_FAB2_LIB.BASEBOARD_FAB2(SCH_1):PAGE102_I1@MSTR_CLOCK.NB3W1200L(CHIPS)':
 'DIF_8P': CDS_PINID='DIF_8P';
NODE_NAME     R4D9 1
 '@BASEBOARD_FAB2_LIB.BASEBOARD_FAB2(SCH_1):PAGE103_I39@MSTR_DISCRETE.RES(CHIPS)':
 'A': CDS_PINID='A';
NET_NAME
'CLK_100M_CPU1_PE_REFCLK_DN'
 '@BASEBOARD_FAB2_LIB.BASEBOARD_FAB2(SCH_1):CLK_100M_CPU1_PE_REFCLK_DN':
 C_SIGNAL='@baseboard_fab2_lib.baseboard_fab2(sch_1):clk_100m_cpu1_pe_refclk_dn';
NODE_NAME     U2D1 BU24
 '@BASEBOARD_FAB2_LIB.BASEBOARD_FAB2(SCH_1):PAGE63_I23@CHPSET_LIB.SKX_EXT_B(CHIPS)':
 'CD_PE_REFCLK_DN': CDS_PINID='CD_PE_REFCLK_DN';
NODE_NAME     R4D16 2
 '@BASEBOARD_FAB2_LIB.BASEBOARD_FAB2(SCH_1):PAGE103_I34@MSTR_DISCRETE.RES(CHIPS)':
 'B': CDS_PINID='B';
NODE_NAME     R7P4 1
 '@BASEBOARD_FAB2_LIB.BASEBOARD_FAB2(SCH_1):PAGE103_I131@MSTR_DISCRETE.RES(CHIPS)':
 'A': CDS_PINID='A';
NET_NAME
'CLK_100M_CPU1_PE_REFCLK_DP'
 '@BASEBOARD_FAB2_LIB.BASEBOARD_FAB2(SCH_1):CLK_100M_CPU1_PE_REFCLK_DP':
 C_SIGNAL='@baseboard_fab2_lib.baseboard_fab2(sch_1):clk_100m_cpu1_pe_refclk_dp';
NODE_NAME     U2D1 BW24
 '@BASEBOARD_FAB2_LIB.BASEBOARD_FAB2(SCH_1):PAGE63_I23@CHPSET_LIB.SKX_EXT_B(CHIPS)':
 'CD_PE_REFCLK_DP': CDS_PINID='CD_PE_REFCLK_DP';
NODE_NAME     R4D13 2
 '@BASEBOARD_FAB2_LIB.BASEBOARD_FAB2(SCH_1):PAGE103_I29@MSTR_DISCRETE.RES(CHIPS)':
 'B': CDS_PINID='B';
NODE_NAME     R7P3 1
 '@BASEBOARD_FAB2_LIB.BASEBOARD_FAB2(SCH_1):PAGE103_I129@MSTR_DISCRETE.RES(CHIPS)':
 'A': CDS_PINID='A';
NET_NAME
'CLK_100M_CPU1_PE_REFCLK_R_DN'
 '@BASEBOARD_FAB2_LIB.BASEBOARD_FAB2(SCH_1):CLK_100M_CPU1_PE_REFCLK_R_DN':
 C_SIGNAL='@baseboard_fab2_lib.baseboard_fab2(sch_1):clk_100m_cpu1_pe_refclk_r_d~
n';
NODE_NAME     EU4D2 55
 '@BASEBOARD_FAB2_LIB.BASEBOARD_FAB2(SCH_1):PAGE102_I1@MSTR_CLOCK.NB3W1200L(CHIPS)':
 'DIF_9N': CDS_PINID='DIF_9N';
NODE_NAME     R4D16 1
 '@BASEBOARD_FAB2_LIB.BASEBOARD_FAB2(SCH_1):PAGE103_I34@MSTR_DISCRETE.RES(CHIPS)':
 'A': CDS_PINID='A';
NET_NAME
'CLK_100M_CPU1_PE_REFCLK_R_DP'
 '@BASEBOARD_FAB2_LIB.BASEBOARD_FAB2(SCH_1):CLK_100M_CPU1_PE_REFCLK_R_DP':
 C_SIGNAL='@baseboard_fab2_lib.baseboard_fab2(sch_1):clk_100m_cpu1_pe_refclk_r_d~
p';
NODE_NAME     EU4D2 54
 '@BASEBOARD_FAB2_LIB.BASEBOARD_FAB2(SCH_1):PAGE102_I1@MSTR_CLOCK.NB3W1200L(CHIPS)':
 'DIF_9P': CDS_PINID='DIF_9P';
NODE_NAME     R4D13 1
 '@BASEBOARD_FAB2_LIB.BASEBOARD_FAB2(SCH_1):PAGE103_I29@MSTR_DISCRETE.RES(CHIPS)':
 'A': CDS_PINID='A';
NET_NAME
'CLK_100M_CPU1_RC_REFCLK0_DN'
 '@BASEBOARD_FAB2_LIB.BASEBOARD_FAB2(SCH_1):CLK_100M_CPU1_RC_REFCLK0_DN':
 C_SIGNAL='@baseboard_fab2_lib.baseboard_fab2(sch_1):clk_100m_cpu1_rc_refclk0_dn~
';
NODE_NAME     U2D1 AP27
 '@BASEBOARD_FAB2_LIB.BASEBOARD_FAB2(SCH_1):PAGE56_I169@CHPSET_LIB.SKX_EXT_B(CHIPS)':
 'RSVD'<195>: CDS_PINID='RSVD(195)';
NODE_NAME     R4D21 2
 '@BASEBOARD_FAB2_LIB.BASEBOARD_FAB2(SCH_1):PAGE103_I24@MSTR_DISCRETE.RES(CHIPS)':
 'B': CDS_PINID='B';
NODE_NAME     R7P7 1
 '@BASEBOARD_FAB2_LIB.BASEBOARD_FAB2(SCH_1):PAGE103_I127@MSTR_DISCRETE.RES(CHIPS)':
 'A': CDS_PINID='A';
NET_NAME
'CLK_100M_CPU1_RC_REFCLK0_DP'
 '@BASEBOARD_FAB2_LIB.BASEBOARD_FAB2(SCH_1):CLK_100M_CPU1_RC_REFCLK0_DP':
 C_SIGNAL='@baseboard_fab2_lib.baseboard_fab2(sch_1):clk_100m_cpu1_rc_refclk0_dp~
';
NODE_NAME     U2D1 AM27
 '@BASEBOARD_FAB2_LIB.BASEBOARD_FAB2(SCH_1):PAGE56_I169@CHPSET_LIB.SKX_EXT_B(CHIPS)':
 'RSVD'<206>: CDS_PINID='RSVD(206)';
NODE_NAME     R4D19 2
 '@BASEBOARD_FAB2_LIB.BASEBOARD_FAB2(SCH_1):PAGE103_I19@MSTR_DISCRETE.RES(CHIPS)':
 'B': CDS_PINID='B';
NODE_NAME     R7P6 1
 '@BASEBOARD_FAB2_LIB.BASEBOARD_FAB2(SCH_1):PAGE103_I125@MSTR_DISCRETE.RES(CHIPS)':
 'A': CDS_PINID='A';
NET_NAME
'CLK_100M_CPU1_RC_REFCLK0_R_DN'
 '@BASEBOARD_FAB2_LIB.BASEBOARD_FAB2(SCH_1):CLK_100M_CPU1_RC_REFCLK0_R_DN':
 C_SIGNAL='@baseboard_fab2_lib.baseboard_fab2(sch_1):clk_100m_cpu1_rc_refclk0_r_~
dn';
NODE_NAME     EU4D2 60
 '@BASEBOARD_FAB2_LIB.BASEBOARD_FAB2(SCH_1):PAGE102_I1@MSTR_CLOCK.NB3W1200L(CHIPS)':
 'DIF_10N': CDS_PINID='DIF_10N';
NODE_NAME     R4D21 1
 '@BASEBOARD_FAB2_LIB.BASEBOARD_FAB2(SCH_1):PAGE103_I24@MSTR_DISCRETE.RES(CHIPS)':
 'A': CDS_PINID='A';
NET_NAME
'CLK_100M_CPU1_RC_REFCLK0_R_DP'
 '@BASEBOARD_FAB2_LIB.BASEBOARD_FAB2(SCH_1):CLK_100M_CPU1_RC_REFCLK0_R_DP':
 C_SIGNAL='@baseboard_fab2_lib.baseboard_fab2(sch_1):clk_100m_cpu1_rc_refclk0_r_~
dp';
NODE_NAME     EU4D2 59
 '@BASEBOARD_FAB2_LIB.BASEBOARD_FAB2(SCH_1):PAGE102_I1@MSTR_CLOCK.NB3W1200L(CHIPS)':
 'DIF_10P': CDS_PINID='DIF_10P';
NODE_NAME     R4D19 1
 '@BASEBOARD_FAB2_LIB.BASEBOARD_FAB2(SCH_1):PAGE103_I19@MSTR_DISCRETE.RES(CHIPS)':
 'A': CDS_PINID='A';
NET_NAME
'CLK_100M_CPU1_RC_REFCLK1_DN'
 '@BASEBOARD_FAB2_LIB.BASEBOARD_FAB2(SCH_1):CLK_100M_CPU1_RC_REFCLK1_DN':
 C_SIGNAL='@baseboard_fab2_lib.baseboard_fab2(sch_1):clk_100m_cpu1_rc_refclk1_dn~
';
NODE_NAME     U2D1 BB25
 '@BASEBOARD_FAB2_LIB.BASEBOARD_FAB2(SCH_1):PAGE70_I9@CHPSET_LIB.SKX_EXT_B(CHIPS)':
 'RSVD'<165>: CDS_PINID='RSVD(165)';
NODE_NAME     R4D28 2
 '@BASEBOARD_FAB2_LIB.BASEBOARD_FAB2(SCH_1):PAGE103_I14@MSTR_DISCRETE.RES(CHIPS)':
 'B': CDS_PINID='B';
NODE_NAME     R7P12 1
 '@BASEBOARD_FAB2_LIB.BASEBOARD_FAB2(SCH_1):PAGE103_I123@MSTR_DISCRETE.RES(CHIPS)':
 'A': CDS_PINID='A';
NET_NAME
'CLK_100M_CPU1_RC_REFCLK1_DP'
 '@BASEBOARD_FAB2_LIB.BASEBOARD_FAB2(SCH_1):CLK_100M_CPU1_RC_REFCLK1_DP':
 C_SIGNAL='@baseboard_fab2_lib.baseboard_fab2(sch_1):clk_100m_cpu1_rc_refclk1_dp~
';
NODE_NAME     U2D1 BD25
 '@BASEBOARD_FAB2_LIB.BASEBOARD_FAB2(SCH_1):PAGE70_I9@CHPSET_LIB.SKX_EXT_B(CHIPS)':
 'RSVD'<153>: CDS_PINID='RSVD(153)';
NODE_NAME     R4D23 2
 '@BASEBOARD_FAB2_LIB.BASEBOARD_FAB2(SCH_1):PAGE103_I9@MSTR_DISCRETE.RES(CHIPS)':
 'B': CDS_PINID='B';
NODE_NAME     R7P9 1
 '@BASEBOARD_FAB2_LIB.BASEBOARD_FAB2(SCH_1):PAGE103_I121@MSTR_DISCRETE.RES(CHIPS)':
 'A': CDS_PINID='A';
NET_NAME
'CLK_100M_CPU1_RC_REFCLK1_R_DN'
 '@BASEBOARD_FAB2_LIB.BASEBOARD_FAB2(SCH_1):CLK_100M_CPU1_RC_REFCLK1_R_DN':
 C_SIGNAL='@baseboard_fab2_lib.baseboard_fab2(sch_1):clk_100m_cpu1_rc_refclk1_r_~
dn';
NODE_NAME     EU4D2 64
 '@BASEBOARD_FAB2_LIB.BASEBOARD_FAB2(SCH_1):PAGE102_I1@MSTR_CLOCK.NB3W1200L(CHIPS)':
 'DIF_11N': CDS_PINID='DIF_11N';
NODE_NAME     R4D28 1
 '@BASEBOARD_FAB2_LIB.BASEBOARD_FAB2(SCH_1):PAGE103_I14@MSTR_DISCRETE.RES(CHIPS)':
 'A': CDS_PINID='A';
NET_NAME
'CLK_100M_CPU1_RC_REFCLK1_R_DP'
 '@BASEBOARD_FAB2_LIB.BASEBOARD_FAB2(SCH_1):CLK_100M_CPU1_RC_REFCLK1_R_DP':
 C_SIGNAL='@baseboard_fab2_lib.baseboard_fab2(sch_1):clk_100m_cpu1_rc_refclk1_r_~
dp';
NODE_NAME     EU4D2 63
 '@BASEBOARD_FAB2_LIB.BASEBOARD_FAB2(SCH_1):PAGE102_I1@MSTR_CLOCK.NB3W1200L(CHIPS)':
 'DIF_11P': CDS_PINID='DIF_11P';
NODE_NAME     R4D23 1
 '@BASEBOARD_FAB2_LIB.BASEBOARD_FAB2(SCH_1):PAGE103_I9@MSTR_DISCRETE.RES(CHIPS)':
 'A': CDS_PINID='A';
NET_NAME
'CLK_100M_DB1200_DN'
 '@BASEBOARD_FAB2_LIB.BASEBOARD_FAB2(SCH_1):CLK_100M_DB1200_DN':
 C_SIGNAL='@baseboard_fab2_lib.baseboard_fab2(sch_1):clk_100m_db1200_dn';
NODE_NAME     EU4D2 10
 '@BASEBOARD_FAB2_LIB.BASEBOARD_FAB2(SCH_1):PAGE102_I1@MSTR_CLOCK.NB3W1200L(CHIPS)':
 'CLK_INN': CDS_PINID='CLK_INN';
NODE_NAME     U7C1 K35
 '@BASEBOARD_FAB2_LIB.BASEBOARD_FAB2(SCH_1):PAGE114_I40@MSTR_U_PROC.LBG_CORE_QAT_EXT_D(CHIPS)':
 'CLKOUT_SRCN'<1>: CDS_PINID='CLKOUT_SRCN(1)';
NET_NAME
'CLK_100M_DB1200_DP'
 '@BASEBOARD_FAB2_LIB.BASEBOARD_FAB2(SCH_1):CLK_100M_DB1200_DP':
 C_SIGNAL='@baseboard_fab2_lib.baseboard_fab2(sch_1):clk_100m_db1200_dp';
NODE_NAME     EU4D2 9
 '@BASEBOARD_FAB2_LIB.BASEBOARD_FAB2(SCH_1):PAGE102_I1@MSTR_CLOCK.NB3W1200L(CHIPS)':
 'CLK_INP': CDS_PINID='CLK_INP';
NODE_NAME     U7C1 H35
 '@BASEBOARD_FAB2_LIB.BASEBOARD_FAB2(SCH_1):PAGE114_I40@MSTR_U_PROC.LBG_CORE_QAT_EXT_D(CHIPS)':
 'CLKOUT_SRCP'<1>: CDS_PINID='CLKOUT_SRCP(1)';
NET_NAME
'CLK_100M_M2_DN'
 '@BASEBOARD_FAB2_LIB.BASEBOARD_FAB2(SCH_1):CLK_100M_M2_DN':
 C_SIGNAL='@baseboard_fab2_lib.baseboard_fab2(sch_1):clk_100m_m2_dn';
NODE_NAME     U7C1 K27
 '@BASEBOARD_FAB2_LIB.BASEBOARD_FAB2(SCH_1):PAGE114_I40@MSTR_U_PROC.LBG_CORE_QAT_EXT_D(CHIPS)':
 'CLKOUT_SRCN'<15>: CDS_PINID='CLKOUT_SRCN(15)';
NODE_NAME     J8F1 53
 '@BASEBOARD_FAB2_LIB.BASEBOARD_FAB2(SCH_1):PAGE185_I143@W_HDL.SKT-MINI67P-41-GP(CHIPS)':
 '53': CDS_PINID='\53\';
NET_NAME
'CLK_100M_M2_DP'
 '@BASEBOARD_FAB2_LIB.BASEBOARD_FAB2(SCH_1):CLK_100M_M2_DP':
 C_SIGNAL='@baseboard_fab2_lib.baseboard_fab2(sch_1):clk_100m_m2_dp';
NODE_NAME     U7C1 H27
 '@BASEBOARD_FAB2_LIB.BASEBOARD_FAB2(SCH_1):PAGE114_I40@MSTR_U_PROC.LBG_CORE_QAT_EXT_D(CHIPS)':
 'CLKOUT_SRCP'<15>: CDS_PINID='CLKOUT_SRCP(15)';
NODE_NAME     J8F1 55
 '@BASEBOARD_FAB2_LIB.BASEBOARD_FAB2(SCH_1):PAGE185_I143@W_HDL.SKT-MINI67P-41-GP(CHIPS)':
 '55': CDS_PINID='\55\';
NET_NAME
'CLK_100M_MEZZ1_DN'
 '@BASEBOARD_FAB2_LIB.BASEBOARD_FAB2(SCH_1):CLK_100M_MEZZ1_DN':
 C_SIGNAL='@baseboard_fab2_lib.baseboard_fab2(sch_1):clk_100m_mezz1_dn';
NODE_NAME     U7C1 D31
 '@BASEBOARD_FAB2_LIB.BASEBOARD_FAB2(SCH_1):PAGE114_I40@MSTR_U_PROC.LBG_CORE_QAT_EXT_D(CHIPS)':
 'CLKOUT_SRCN'<8>: CDS_PINID='CLKOUT_SRCN(8)';
NODE_NAME     J9B3 50
 '@BASEBOARD_FAB2_LIB.BASEBOARD_FAB2(SCH_1):PAGE186_I336@MSTR_SCONN.SCONN120_A28699018(CHIPS)':
 'IO50': CDS_PINID='IO50';
NET_NAME
'CLK_100M_MEZZ1_DP'
 '@BASEBOARD_FAB2_LIB.BASEBOARD_FAB2(SCH_1):CLK_100M_MEZZ1_DP':
 C_SIGNAL='@baseboard_fab2_lib.baseboard_fab2(sch_1):clk_100m_mezz1_dp';
NODE_NAME     U7C1 B31
 '@BASEBOARD_FAB2_LIB.BASEBOARD_FAB2(SCH_1):PAGE114_I40@MSTR_U_PROC.LBG_CORE_QAT_EXT_D(CHIPS)':
 'CLKOUT_SRCP'<8>: CDS_PINID='CLKOUT_SRCP(8)';
NODE_NAME     J9B3 48
 '@BASEBOARD_FAB2_LIB.BASEBOARD_FAB2(SCH_1):PAGE186_I336@MSTR_SCONN.SCONN120_A28699018(CHIPS)':
 'IO48': CDS_PINID='IO48';
NET_NAME
'CLK_100M_MEZZ2_DN'
 '@BASEBOARD_FAB2_LIB.BASEBOARD_FAB2(SCH_1):CLK_100M_MEZZ2_DN':
 C_SIGNAL='@baseboard_fab2_lib.baseboard_fab2(sch_1):clk_100m_mezz2_dn';
NODE_NAME     U7C1 J26
 '@BASEBOARD_FAB2_LIB.BASEBOARD_FAB2(SCH_1):PAGE114_I40@MSTR_U_PROC.LBG_CORE_QAT_EXT_D(CHIPS)':
 'CLKOUT_SRCN'<9>: CDS_PINID='CLKOUT_SRCN(9)';
NODE_NAME     J9B3 53
 '@BASEBOARD_FAB2_LIB.BASEBOARD_FAB2(SCH_1):PAGE186_I336@MSTR_SCONN.SCONN120_A28699018(CHIPS)':
 'IO53': CDS_PINID='IO53';
NET_NAME
'CLK_100M_MEZZ2_DP'
 '@BASEBOARD_FAB2_LIB.BASEBOARD_FAB2(SCH_1):CLK_100M_MEZZ2_DP':
 C_SIGNAL='@baseboard_fab2_lib.baseboard_fab2(sch_1):clk_100m_mezz2_dp';
NODE_NAME     U7C1 G26
 '@BASEBOARD_FAB2_LIB.BASEBOARD_FAB2(SCH_1):PAGE114_I40@MSTR_U_PROC.LBG_CORE_QAT_EXT_D(CHIPS)':
 'CLKOUT_SRCP'<9>: CDS_PINID='CLKOUT_SRCP(9)';
NODE_NAME     J9B3 51
 '@BASEBOARD_FAB2_LIB.BASEBOARD_FAB2(SCH_1):PAGE186_I336@MSTR_SCONN.SCONN120_A28699018(CHIPS)':
 'IO51': CDS_PINID='IO51';
NET_NAME
'CLK_100M_MEZZ3_DN'
 '@BASEBOARD_FAB2_LIB.BASEBOARD_FAB2(SCH_1):CLK_100M_MEZZ3_DN':
 C_SIGNAL='@baseboard_fab2_lib.baseboard_fab2(sch_1):clk_100m_mezz3_dn';
NODE_NAME     U7C1 B23
 '@BASEBOARD_FAB2_LIB.BASEBOARD_FAB2(SCH_1):PAGE114_I40@MSTR_U_PROC.LBG_CORE_QAT_EXT_D(CHIPS)':
 'CLKOUT_SRCN'<10>: CDS_PINID='CLKOUT_SRCN(10)';
NODE_NAME     J8E3 71
 '@BASEBOARD_FAB2_LIB.BASEBOARD_FAB2(SCH_1):PAGE187_I119@MSTR_SCONN.SCONN80_E67482007(CHIPS)':
 'IO71': CDS_PINID='IO71';
NET_NAME
'CLK_100M_MEZZ3_DP'
 '@BASEBOARD_FAB2_LIB.BASEBOARD_FAB2(SCH_1):CLK_100M_MEZZ3_DP':
 C_SIGNAL='@baseboard_fab2_lib.baseboard_fab2(sch_1):clk_100m_mezz3_dp';
NODE_NAME     U7C1 D23
 '@BASEBOARD_FAB2_LIB.BASEBOARD_FAB2(SCH_1):PAGE114_I40@MSTR_U_PROC.LBG_CORE_QAT_EXT_D(CHIPS)':
 'CLKOUT_SRCP'<10>: CDS_PINID='CLKOUT_SRCP(10)';
NODE_NAME     J8E3 69
 '@BASEBOARD_FAB2_LIB.BASEBOARD_FAB2(SCH_1):PAGE187_I119@MSTR_SCONN.SCONN80_E67482007(CHIPS)':
 'IO69': CDS_PINID='IO69';
NET_NAME
'CLK_100M_MEZZ4_DN'
 '@BASEBOARD_FAB2_LIB.BASEBOARD_FAB2(SCH_1):CLK_100M_MEZZ4_DN':
 C_SIGNAL='@baseboard_fab2_lib.baseboard_fab2(sch_1):clk_100m_mezz4_dn';
NODE_NAME     U7C1 B21
 '@BASEBOARD_FAB2_LIB.BASEBOARD_FAB2(SCH_1):PAGE114_I40@MSTR_U_PROC.LBG_CORE_QAT_EXT_D(CHIPS)':
 'CLKOUT_SRCN'<11>: CDS_PINID='CLKOUT_SRCN(11)';
NODE_NAME     J8E3 76
 '@BASEBOARD_FAB2_LIB.BASEBOARD_FAB2(SCH_1):PAGE187_I119@MSTR_SCONN.SCONN80_E67482007(CHIPS)':
 'IO76': CDS_PINID='IO76';
NET_NAME
'CLK_100M_MEZZ4_DP'
 '@BASEBOARD_FAB2_LIB.BASEBOARD_FAB2(SCH_1):CLK_100M_MEZZ4_DP':
 C_SIGNAL='@baseboard_fab2_lib.baseboard_fab2(sch_1):clk_100m_mezz4_dp';
NODE_NAME     U7C1 D21
 '@BASEBOARD_FAB2_LIB.BASEBOARD_FAB2(SCH_1):PAGE114_I40@MSTR_U_PROC.LBG_CORE_QAT_EXT_D(CHIPS)':
 'CLKOUT_SRCP'<11>: CDS_PINID='CLKOUT_SRCP(11)';
NODE_NAME     J8E3 74
 '@BASEBOARD_FAB2_LIB.BASEBOARD_FAB2(SCH_1):PAGE187_I119@MSTR_SCONN.SCONN80_E67482007(CHIPS)':
 'IO74': CDS_PINID='IO74';
NET_NAME
'CLK_100M_PCH_SLOTX24_S0_DN'
 '@BASEBOARD_FAB2_LIB.BASEBOARD_FAB2(SCH_1):CLK_100M_PCH_SLOTX24_S0_DN':
 C_SIGNAL='@baseboard_fab2_lib.baseboard_fab2(sch_1):clk_100m_pch_slotx24_s0_dn';
NODE_NAME     J8G1 41
 '@BASEBOARD_FAB2_LIB.BASEBOARD_FAB2(SCH_1):PAGE108_I258@MSTR_SCONN.SCONN200_H68296001(CHIPS)':
 'IO41': CDS_PINID='IO41';
NODE_NAME     U7C1 J33
 '@BASEBOARD_FAB2_LIB.BASEBOARD_FAB2(SCH_1):PAGE114_I40@MSTR_U_PROC.LBG_CORE_QAT_EXT_D(CHIPS)':
 'CLKOUT_SRCN'<2>: CDS_PINID='CLKOUT_SRCN(2)';
NET_NAME
'CLK_100M_PCH_SLOTX24_S0_DP'
 '@BASEBOARD_FAB2_LIB.BASEBOARD_FAB2(SCH_1):CLK_100M_PCH_SLOTX24_S0_DP':
 C_SIGNAL='@baseboard_fab2_lib.baseboard_fab2(sch_1):clk_100m_pch_slotx24_s0_dp';
NODE_NAME     J8G1 39
 '@BASEBOARD_FAB2_LIB.BASEBOARD_FAB2(SCH_1):PAGE108_I258@MSTR_SCONN.SCONN200_H68296001(CHIPS)':
 'IO39': CDS_PINID='IO39';
NODE_NAME     U7C1 G33
 '@BASEBOARD_FAB2_LIB.BASEBOARD_FAB2(SCH_1):PAGE114_I40@MSTR_U_PROC.LBG_CORE_QAT_EXT_D(CHIPS)':
 'CLKOUT_SRCP'<2>: CDS_PINID='CLKOUT_SRCP(2)';
NET_NAME
'CLK_100M_PCH_SLOTX24_S1_DN'
 '@BASEBOARD_FAB2_LIB.BASEBOARD_FAB2(SCH_1):CLK_100M_PCH_SLOTX24_S1_DN':
 C_SIGNAL='@baseboard_fab2_lib.baseboard_fab2(sch_1):clk_100m_pch_slotx24_s1_dn';
NODE_NAME     J8G1 44
 '@BASEBOARD_FAB2_LIB.BASEBOARD_FAB2(SCH_1):PAGE108_I258@MSTR_SCONN.SCONN200_H68296001(CHIPS)':
 'IO44': CDS_PINID='IO44';
NODE_NAME     U7C1 K42
 '@BASEBOARD_FAB2_LIB.BASEBOARD_FAB2(SCH_1):PAGE114_I40@MSTR_U_PROC.LBG_CORE_QAT_EXT_D(CHIPS)':
 'CLKOUT_SRCN'<3>: CDS_PINID='CLKOUT_SRCN(3)';
NET_NAME
'CLK_100M_PCH_SLOTX24_S1_DP'
 '@BASEBOARD_FAB2_LIB.BASEBOARD_FAB2(SCH_1):CLK_100M_PCH_SLOTX24_S1_DP':
 C_SIGNAL='@baseboard_fab2_lib.baseboard_fab2(sch_1):clk_100m_pch_slotx24_s1_dp';
NODE_NAME     J8G1 42
 '@BASEBOARD_FAB2_LIB.BASEBOARD_FAB2(SCH_1):PAGE108_I258@MSTR_SCONN.SCONN200_H68296001(CHIPS)':
 'IO42': CDS_PINID='IO42';
NODE_NAME     U7C1 H42
 '@BASEBOARD_FAB2_LIB.BASEBOARD_FAB2(SCH_1):PAGE114_I40@MSTR_U_PROC.LBG_CORE_QAT_EXT_D(CHIPS)':
 'CLKOUT_SRCP'<3>: CDS_PINID='CLKOUT_SRCP(3)';
NET_NAME
'CLK_100M_PCH_SLOTX24_S2_DN'
 '@BASEBOARD_FAB2_LIB.BASEBOARD_FAB2(SCH_1):CLK_100M_PCH_SLOTX24_S2_DN':
 C_SIGNAL='@baseboard_fab2_lib.baseboard_fab2(sch_1):clk_100m_pch_slotx24_s2_dn';
NODE_NAME     J8G1 50
 '@BASEBOARD_FAB2_LIB.BASEBOARD_FAB2(SCH_1):PAGE108_I258@MSTR_SCONN.SCONN200_H68296001(CHIPS)':
 'IO50': CDS_PINID='IO50';
NODE_NAME     U7C1 A28
 '@BASEBOARD_FAB2_LIB.BASEBOARD_FAB2(SCH_1):PAGE114_I40@MSTR_U_PROC.LBG_CORE_QAT_EXT_D(CHIPS)':
 'CLKOUT_SRCN'<4>: CDS_PINID='CLKOUT_SRCN(4)';
NET_NAME
'CLK_100M_PCH_SLOTX24_S2_DP'
 '@BASEBOARD_FAB2_LIB.BASEBOARD_FAB2(SCH_1):CLK_100M_PCH_SLOTX24_S2_DP':
 C_SIGNAL='@baseboard_fab2_lib.baseboard_fab2(sch_1):clk_100m_pch_slotx24_s2_dp';
NODE_NAME     J8G1 48
 '@BASEBOARD_FAB2_LIB.BASEBOARD_FAB2(SCH_1):PAGE108_I258@MSTR_SCONN.SCONN200_H68296001(CHIPS)':
 'IO48': CDS_PINID='IO48';
NODE_NAME     U7C1 C28
 '@BASEBOARD_FAB2_LIB.BASEBOARD_FAB2(SCH_1):PAGE114_I40@MSTR_U_PROC.LBG_CORE_QAT_EXT_D(CHIPS)':
 'CLKOUT_SRCP'<4>: CDS_PINID='CLKOUT_SRCP(4)';
NET_NAME
'CLK_100M_PCH_SLOTX24_S3_DN'
 '@BASEBOARD_FAB2_LIB.BASEBOARD_FAB2(SCH_1):CLK_100M_PCH_SLOTX24_S3_DN':
 C_SIGNAL='@baseboard_fab2_lib.baseboard_fab2(sch_1):clk_100m_pch_slotx24_s3_dn';
NODE_NAME     J8G1 47
 '@BASEBOARD_FAB2_LIB.BASEBOARD_FAB2(SCH_1):PAGE108_I258@MSTR_SCONN.SCONN200_H68296001(CHIPS)':
 'IO47': CDS_PINID='IO47';
NODE_NAME     U7C1 J40
 '@BASEBOARD_FAB2_LIB.BASEBOARD_FAB2(SCH_1):PAGE114_I40@MSTR_U_PROC.LBG_CORE_QAT_EXT_D(CHIPS)':
 'CLKOUT_SRCN'<5>: CDS_PINID='CLKOUT_SRCN(5)';
NET_NAME
'CLK_100M_PCH_SLOTX24_S3_DP'
 '@BASEBOARD_FAB2_LIB.BASEBOARD_FAB2(SCH_1):CLK_100M_PCH_SLOTX24_S3_DP':
 C_SIGNAL='@baseboard_fab2_lib.baseboard_fab2(sch_1):clk_100m_pch_slotx24_s3_dp';
NODE_NAME     J8G1 45
 '@BASEBOARD_FAB2_LIB.BASEBOARD_FAB2(SCH_1):PAGE108_I258@MSTR_SCONN.SCONN200_H68296001(CHIPS)':
 'IO45': CDS_PINID='IO45';
NODE_NAME     U7C1 G40
 '@BASEBOARD_FAB2_LIB.BASEBOARD_FAB2(SCH_1):PAGE114_I40@MSTR_U_PROC.LBG_CORE_QAT_EXT_D(CHIPS)':
 'CLKOUT_SRCP'<5>: CDS_PINID='CLKOUT_SRCP(5)';
NET_NAME
'CLK_100M_PCH_SLOTX24_S4_DN'
 '@BASEBOARD_FAB2_LIB.BASEBOARD_FAB2(SCH_1):CLK_100M_PCH_SLOTX24_S4_DN':
 C_SIGNAL='@baseboard_fab2_lib.baseboard_fab2(sch_1):clk_100m_pch_slotx24_s4_dn';
NODE_NAME     J8G1 38
 '@BASEBOARD_FAB2_LIB.BASEBOARD_FAB2(SCH_1):PAGE108_I258@MSTR_SCONN.SCONN200_H68296001(CHIPS)':
 'IO38': CDS_PINID='IO38';
NODE_NAME     U7C1 D33
 '@BASEBOARD_FAB2_LIB.BASEBOARD_FAB2(SCH_1):PAGE114_I40@MSTR_U_PROC.LBG_CORE_QAT_EXT_D(CHIPS)':
 'CLKOUT_SRCN'<6>: CDS_PINID='CLKOUT_SRCN(6)';
NET_NAME
'CLK_100M_PCH_SLOTX24_S4_DP'
 '@BASEBOARD_FAB2_LIB.BASEBOARD_FAB2(SCH_1):CLK_100M_PCH_SLOTX24_S4_DP':
 C_SIGNAL='@baseboard_fab2_lib.baseboard_fab2(sch_1):clk_100m_pch_slotx24_s4_dp';
NODE_NAME     J8G1 36
 '@BASEBOARD_FAB2_LIB.BASEBOARD_FAB2(SCH_1):PAGE108_I258@MSTR_SCONN.SCONN200_H68296001(CHIPS)':
 'IO36': CDS_PINID='IO36';
NODE_NAME     U7C1 B33
 '@BASEBOARD_FAB2_LIB.BASEBOARD_FAB2(SCH_1):PAGE114_I40@MSTR_U_PROC.LBG_CORE_QAT_EXT_D(CHIPS)':
 'CLKOUT_SRCP'<6>: CDS_PINID='CLKOUT_SRCP(6)';
NET_NAME
'CLK_100M_PCH_SLOTX24_S5_DN'
 '@BASEBOARD_FAB2_LIB.BASEBOARD_FAB2(SCH_1):CLK_100M_PCH_SLOTX24_S5_DN':
 C_SIGNAL='@baseboard_fab2_lib.baseboard_fab2(sch_1):clk_100m_pch_slotx24_s5_dn';
NODE_NAME     J8G1 35
 '@BASEBOARD_FAB2_LIB.BASEBOARD_FAB2(SCH_1):PAGE108_I258@MSTR_SCONN.SCONN200_H68296001(CHIPS)':
 'IO35': CDS_PINID='IO35';
NODE_NAME     U7C1 H31
 '@BASEBOARD_FAB2_LIB.BASEBOARD_FAB2(SCH_1):PAGE114_I40@MSTR_U_PROC.LBG_CORE_QAT_EXT_D(CHIPS)':
 'CLKOUT_SRCN'<7>: CDS_PINID='CLKOUT_SRCN(7)';
NET_NAME
'CLK_100M_PCH_SLOTX24_S5_DP'
 '@BASEBOARD_FAB2_LIB.BASEBOARD_FAB2(SCH_1):CLK_100M_PCH_SLOTX24_S5_DP':
 C_SIGNAL='@baseboard_fab2_lib.baseboard_fab2(sch_1):clk_100m_pch_slotx24_s5_dp';
NODE_NAME     J8G1 33
 '@BASEBOARD_FAB2_LIB.BASEBOARD_FAB2(SCH_1):PAGE108_I258@MSTR_SCONN.SCONN200_H68296001(CHIPS)':
 'IO33': CDS_PINID='IO33';
NODE_NAME     U7C1 K31
 '@BASEBOARD_FAB2_LIB.BASEBOARD_FAB2(SCH_1):PAGE114_I40@MSTR_U_PROC.LBG_CORE_QAT_EXT_D(CHIPS)':
 'CLKOUT_SRCP'<7>: CDS_PINID='CLKOUT_SRCP(7)';
NET_NAME
'CLK_100M_PCH_XDP_DN'
 '@BASEBOARD_FAB2_LIB.BASEBOARD_FAB2(SCH_1):CLK_100M_PCH_XDP_DN':
 C_SIGNAL='@baseboard_fab2_lib.baseboard_fab2(sch_1):clk_100m_pch_xdp_dn';
NODE_NAME     J9A3 42
 '@BASEBOARD_FAB2_LIB.BASEBOARD_FAB2(SCH_1):PAGE111_I26@MSTR_SCONN.SCONN60_C21100002(CHIPS)':
 'IO42': CDS_PINID='IO42';
NODE_NAME     U7C1 A39
 '@BASEBOARD_FAB2_LIB.BASEBOARD_FAB2(SCH_1):PAGE114_I40@MSTR_U_PROC.LBG_CORE_QAT_EXT_D(CHIPS)':
 'CLKOUT_ITPXDPN': CDS_PINID='CLKOUT_ITPXDPN';
NET_NAME
'CLK_100M_PCH_XDP_DP'
 '@BASEBOARD_FAB2_LIB.BASEBOARD_FAB2(SCH_1):CLK_100M_PCH_XDP_DP':
 C_SIGNAL='@baseboard_fab2_lib.baseboard_fab2(sch_1):clk_100m_pch_xdp_dp';
NODE_NAME     J9A3 40
 '@BASEBOARD_FAB2_LIB.BASEBOARD_FAB2(SCH_1):PAGE111_I26@MSTR_SCONN.SCONN60_C21100002(CHIPS)':
 'IO40': CDS_PINID='IO40';
NODE_NAME     U7C1 C39
 '@BASEBOARD_FAB2_LIB.BASEBOARD_FAB2(SCH_1):PAGE114_I40@MSTR_U_PROC.LBG_CORE_QAT_EXT_D(CHIPS)':
 'CLKOUT_ITPXDPP': CDS_PINID='CLKOUT_ITPXDPP';
NET_NAME
'CLK_100M_SPRV_DN'
 '@BASEBOARD_FAB2_LIB.BASEBOARD_FAB2(SCH_1):CLK_100M_SPRV_DN':
 C_SIGNAL='@baseboard_fab2_lib.baseboard_fab2(sch_1):clk_100m_sprv_dn';
NODE_NAME     U7C1 C20
 '@BASEBOARD_FAB2_LIB.BASEBOARD_FAB2(SCH_1):PAGE114_I40@MSTR_U_PROC.LBG_CORE_QAT_EXT_D(CHIPS)':
 'CLKOUT_SRCN'<14>: CDS_PINID='CLKOUT_SRCN(14)';
NODE_NAME     EU9E1 25
 '@BASEBOARD_FAB2_LIB.BASEBOARD_FAB2(SCH_1):PAGE139_I72@MSTR_INTEL.SPRINGVILLE(CHIPS)':
 'PECLKN': CDS_PINID='PECLKN';
NET_NAME
'CLK_100M_SPRV_DP'
 '@BASEBOARD_FAB2_LIB.BASEBOARD_FAB2(SCH_1):CLK_100M_SPRV_DP':
 C_SIGNAL='@baseboard_fab2_lib.baseboard_fab2(sch_1):clk_100m_sprv_dp';
NODE_NAME     U7C1 A20
 '@BASEBOARD_FAB2_LIB.BASEBOARD_FAB2(SCH_1):PAGE114_I40@MSTR_U_PROC.LBG_CORE_QAT_EXT_D(CHIPS)':
 'CLKOUT_SRCP'<14>: CDS_PINID='CLKOUT_SRCP(14)';
NODE_NAME     EU9E1 26
 '@BASEBOARD_FAB2_LIB.BASEBOARD_FAB2(SCH_1):PAGE139_I72@MSTR_INTEL.SPRINGVILLE(CHIPS)':
 'PECLKP': CDS_PINID='PECLKP';
NET_NAME
'CLK_156M_OSC_BRD_CPU0_DN'
 '@BASEBOARD_FAB2_LIB.BASEBOARD_FAB2(SCH_1):CLK_156M_OSC_BRD_CPU0_DN':
 C_SIGNAL='@baseboard_fab2_lib.baseboard_fab2(sch_1):clk_156m_osc_brd_cpu0_dn';
NODE_NAME     R6F7 1
 '@BASEBOARD_FAB2_LIB.BASEBOARD_FAB2(SCH_1):PAGE104_I67@MSTR_DISCRETE.RES(CHIPS)':
 'A': CDS_PINID='A';
NODE_NAME     Y6F1 5
 '@BASEBOARD_FAB2_LIB.BASEBOARD_FAB2(SCH_1):PAGE104_I71@MSTR_DISCRETE.OSC_C(CHIPS)':
 'OUT_N': CDS_PINID='OUT_N';
NET_NAME
'CLK_156M_OSC_BRD_CPU0_DP'
 '@BASEBOARD_FAB2_LIB.BASEBOARD_FAB2(SCH_1):CLK_156M_OSC_BRD_CPU0_DP':
 C_SIGNAL='@baseboard_fab2_lib.baseboard_fab2(sch_1):clk_156m_osc_brd_cpu0_dp';
NODE_NAME     R6F9 1
 '@BASEBOARD_FAB2_LIB.BASEBOARD_FAB2(SCH_1):PAGE104_I68@MSTR_DISCRETE.RES(CHIPS)':
 'A': CDS_PINID='A';
NODE_NAME     Y6F1 4
 '@BASEBOARD_FAB2_LIB.BASEBOARD_FAB2(SCH_1):PAGE104_I71@MSTR_DISCRETE.OSC_C(CHIPS)':
 'OUT': CDS_PINID='\out\';
NET_NAME
'CLK_156M_OSC_BRD_CPU1_DN'
 '@BASEBOARD_FAB2_LIB.BASEBOARD_FAB2(SCH_1):CLK_156M_OSC_BRD_CPU1_DN':
 C_SIGNAL='@baseboard_fab2_lib.baseboard_fab2(sch_1):clk_156m_osc_brd_cpu1_dn';
NODE_NAME     R3F2 1
 '@BASEBOARD_FAB2_LIB.BASEBOARD_FAB2(SCH_1):PAGE104_I69@MSTR_DISCRETE.RES(CHIPS)':
 'A': CDS_PINID='A';
NODE_NAME     Y3F1 5
 '@BASEBOARD_FAB2_LIB.BASEBOARD_FAB2(SCH_1):PAGE104_I72@MSTR_DISCRETE.OSC_C(CHIPS)':
 'OUT_N': CDS_PINID='OUT_N';
NET_NAME
'CLK_156M_OSC_BRD_CPU1_DP'
 '@BASEBOARD_FAB2_LIB.BASEBOARD_FAB2(SCH_1):CLK_156M_OSC_BRD_CPU1_DP':
 C_SIGNAL='@baseboard_fab2_lib.baseboard_fab2(sch_1):clk_156m_osc_brd_cpu1_dp';
NODE_NAME     R3F4 1
 '@BASEBOARD_FAB2_LIB.BASEBOARD_FAB2(SCH_1):PAGE104_I70@MSTR_DISCRETE.RES(CHIPS)':
 'A': CDS_PINID='A';
NODE_NAME     Y3F1 4
 '@BASEBOARD_FAB2_LIB.BASEBOARD_FAB2(SCH_1):PAGE104_I72@MSTR_DISCRETE.OSC_C(CHIPS)':
 'OUT': CDS_PINID='\out\';
NET_NAME
'CLK_156M_OSC_CPU0_HFI_DN'
 '@BASEBOARD_FAB2_LIB.BASEBOARD_FAB2(SCH_1):CLK_156M_OSC_CPU0_HFI_DN':
 C_SIGNAL='@baseboard_fab2_lib.baseboard_fab2(sch_1):clk_156m_osc_cpu0_hfi_dn';
NODE_NAME     U5D1 BE16
 '@BASEBOARD_FAB2_LIB.BASEBOARD_FAB2(SCH_1):PAGE29_I61@CHPSET_LIB.SKX_EXT_B(CHIPS)':
 'CD_HFI_REFCLK_DN': CDS_PINID='CD_HFI_REFCLK_DN';
NODE_NAME     R6F6 2
 '@BASEBOARD_FAB2_LIB.BASEBOARD_FAB2(SCH_1):PAGE104_I41@MSTR_DISCRETE.RES(CHIPS)':
 'B': CDS_PINID='B';
NODE_NAME     R6F7 2
 '@BASEBOARD_FAB2_LIB.BASEBOARD_FAB2(SCH_1):PAGE104_I67@MSTR_DISCRETE.RES(CHIPS)':
 'B': CDS_PINID='B';
NET_NAME
'CLK_156M_OSC_CPU0_HFI_DP'
 '@BASEBOARD_FAB2_LIB.BASEBOARD_FAB2(SCH_1):CLK_156M_OSC_CPU0_HFI_DP':
 C_SIGNAL='@baseboard_fab2_lib.baseboard_fab2(sch_1):clk_156m_osc_cpu0_hfi_dp';
NODE_NAME     U5D1 BG16
 '@BASEBOARD_FAB2_LIB.BASEBOARD_FAB2(SCH_1):PAGE29_I61@CHPSET_LIB.SKX_EXT_B(CHIPS)':
 'CD_HFI_REFCLK_DP': CDS_PINID='CD_HFI_REFCLK_DP';
NODE_NAME     R6F8 2
 '@BASEBOARD_FAB2_LIB.BASEBOARD_FAB2(SCH_1):PAGE104_I37@MSTR_DISCRETE.RES(CHIPS)':
 'B': CDS_PINID='B';
NODE_NAME     R6F9 2
 '@BASEBOARD_FAB2_LIB.BASEBOARD_FAB2(SCH_1):PAGE104_I68@MSTR_DISCRETE.RES(CHIPS)':
 'B': CDS_PINID='B';
NET_NAME
'CLK_156M_OSC_CPU1_HFI_DN'
 '@BASEBOARD_FAB2_LIB.BASEBOARD_FAB2(SCH_1):CLK_156M_OSC_CPU1_HFI_DN':
 C_SIGNAL='@baseboard_fab2_lib.baseboard_fab2(sch_1):clk_156m_osc_cpu1_hfi_dn';
NODE_NAME     U2D1 BE16
 '@BASEBOARD_FAB2_LIB.BASEBOARD_FAB2(SCH_1):PAGE63_I23@CHPSET_LIB.SKX_EXT_B(CHIPS)':
 'CD_HFI_REFCLK_DN': CDS_PINID='CD_HFI_REFCLK_DN';
NODE_NAME     R3F1 2
 '@BASEBOARD_FAB2_LIB.BASEBOARD_FAB2(SCH_1):PAGE104_I51@MSTR_DISCRETE.RES(CHIPS)':
 'B': CDS_PINID='B';
NODE_NAME     R3F2 2
 '@BASEBOARD_FAB2_LIB.BASEBOARD_FAB2(SCH_1):PAGE104_I69@MSTR_DISCRETE.RES(CHIPS)':
 'B': CDS_PINID='B';
NET_NAME
'CLK_156M_OSC_CPU1_HFI_DP'
 '@BASEBOARD_FAB2_LIB.BASEBOARD_FAB2(SCH_1):CLK_156M_OSC_CPU1_HFI_DP':
 C_SIGNAL='@baseboard_fab2_lib.baseboard_fab2(sch_1):clk_156m_osc_cpu1_hfi_dp';
NODE_NAME     U2D1 BG16
 '@BASEBOARD_FAB2_LIB.BASEBOARD_FAB2(SCH_1):PAGE63_I23@CHPSET_LIB.SKX_EXT_B(CHIPS)':
 'CD_HFI_REFCLK_DP': CDS_PINID='CD_HFI_REFCLK_DP';
NODE_NAME     R3F3 2
 '@BASEBOARD_FAB2_LIB.BASEBOARD_FAB2(SCH_1):PAGE104_I53@MSTR_DISCRETE.RES(CHIPS)':
 'B': CDS_PINID='B';
NODE_NAME     R3F4 2
 '@BASEBOARD_FAB2_LIB.BASEBOARD_FAB2(SCH_1):PAGE104_I70@MSTR_DISCRETE.RES(CHIPS)':
 'B': CDS_PINID='B';
NET_NAME
'CLK_24M_25M_BMC_CLKIN'
 '@BASEBOARD_FAB2_LIB.BASEBOARD_FAB2(SCH_1):CLK_24M_25M_BMC_CLKIN':
 C_SIGNAL='@baseboard_fab2_lib.baseboard_fab2(sch_1):clk_24m_25m_bmc_clkin';
NODE_NAME     R9F60 2
 '@BASEBOARD_FAB2_LIB.BASEBOARD_FAB2(SCH_1):PAGE145_I10@MSTR_DISCRETE.RES(CHIPS)':
 'B': CDS_PINID='B';
NODE_NAME     R9F62 2
 '@BASEBOARD_FAB2_LIB.BASEBOARD_FAB2(SCH_1):PAGE145_I11@MSTR_DISCRETE.RES(CHIPS)':
 'B': CDS_PINID='B';
NODE_NAME     U25W4 W18
 '@BASEBOARD_FAB2_LIB.BASEBOARD_FAB2(SCH_1):PAGE145_I117@W_HDL.AST2520A1-GP-GP(CHIPS)':
 'CLKIN': CDS_PINID='CLKIN';
NET_NAME
'CLK_24M_BMC_CLKIN_R'
 '@BASEBOARD_FAB2_LIB.BASEBOARD_FAB2(SCH_1):CLK_24M_BMC_CLKIN_R':
 C_SIGNAL='@baseboard_fab2_lib.baseboard_fab2(sch_1):clk_24m_bmc_clkin_r';
NODE_NAME     Y9F2 3
 '@BASEBOARD_FAB2_LIB.BASEBOARD_FAB2(SCH_1):PAGE145_I8@MSTR_DISCRETE.OSC_C(CHIPS)':
 'OUT': CDS_PINID='\out\';
NODE_NAME     R9F62 1
 '@BASEBOARD_FAB2_LIB.BASEBOARD_FAB2(SCH_1):PAGE145_I11@MSTR_DISCRETE.RES(CHIPS)':
 'A': CDS_PINID='A';
NET_NAME
'CLK_24M_BMC_LPC'
 '@BASEBOARD_FAB2_LIB.BASEBOARD_FAB2(SCH_1):CLK_24M_BMC_LPC':
 C_SIGNAL='@baseboard_fab2_lib.baseboard_fab2(sch_1):clk_24m_bmc_lpc';
NODE_NAME     R7C26 1
 '@BASEBOARD_FAB2_LIB.BASEBOARD_FAB2(SCH_1):PAGE119_I189@MSTR_DISCRETE.RES(CHIPS)':
 'A': CDS_PINID='A';
NODE_NAME     R25W66 1
 '@BASEBOARD_FAB2_LIB.BASEBOARD_FAB2(SCH_1):PAGE146_I76@MSTR_DISCRETE.RES(CHIPS)':
 'A': CDS_PINID='A';
NODE_NAME     U25W4 C22
 '@BASEBOARD_FAB2_LIB.BASEBOARD_FAB2(SCH_1):PAGE146_I105@W_HDL.AST2520A1-GP-GP(CHIPS)':
 'GPIOAC4_ESPICK_LCLK': CDS_PINID='GPIOAC4_ESPICK_LCLK';
NET_NAME
'CLK_24M_BMC_LPC_R'
 '@BASEBOARD_FAB2_LIB.BASEBOARD_FAB2(SCH_1):CLK_24M_BMC_LPC_R':
 C_SIGNAL='@baseboard_fab2_lib.baseboard_fab2(sch_1):clk_24m_bmc_lpc_r';
NODE_NAME     U7C1 R3
 '@BASEBOARD_FAB2_LIB.BASEBOARD_FAB2(SCH_1):PAGE119_I115@MSTR_U_PROC.LBG_CORE_QAT_EXT_D(CHIPS)':
 'GPP_A9_CLKOUT_LPC0_ESPI_CLK': CDS_PINID='GPP_A9_CLKOUT_LPC0_ESPI_CLK';
NODE_NAME     R7C26 2
 '@BASEBOARD_FAB2_LIB.BASEBOARD_FAB2(SCH_1):PAGE119_I189@MSTR_DISCRETE.RES(CHIPS)':
 'B': CDS_PINID='B';
NET_NAME
'CLK_25M_BMC'
 '@BASEBOARD_FAB2_LIB.BASEBOARD_FAB2(SCH_1):CLK_25M_BMC':
 C_SIGNAL='@baseboard_fab2_lib.baseboard_fab2(sch_1):clk_25m_bmc';
NODE_NAME     R8F29 2
 '@BASEBOARD_FAB2_LIB.BASEBOARD_FAB2(SCH_1):PAGE101_I20@MSTR_DISCRETE.RES(CHIPS)':
 'B': CDS_PINID='B';
NODE_NAME     R9F60 1
 '@BASEBOARD_FAB2_LIB.BASEBOARD_FAB2(SCH_1):PAGE145_I10@MSTR_DISCRETE.RES(CHIPS)':
 'A': CDS_PINID='A';
NET_NAME
'CLK_25M_BMC_R'
 '@BASEBOARD_FAB2_LIB.BASEBOARD_FAB2(SCH_1):CLK_25M_BMC_R':
 C_SIGNAL='@baseboard_fab2_lib.baseboard_fab2(sch_1):clk_25m_bmc_r';
NODE_NAME     R8F29 1
 '@BASEBOARD_FAB2_LIB.BASEBOARD_FAB2(SCH_1):PAGE101_I20@MSTR_DISCRETE.RES(CHIPS)':
 'A': CDS_PINID='A';
NODE_NAME     EU8F2 16
 '@BASEBOARD_FAB2_LIB.BASEBOARD_FAB2(SCH_1):PAGE101_I34@MSTR_CLOCK.ICS9FGP204(CHIPS)':
 '25MHZ_0': CDS_PINID='\25mhz_0\';
NET_NAME
'CLK_25M_CPLD'
 '@BASEBOARD_FAB2_LIB.BASEBOARD_FAB2(SCH_1):CLK_25M_CPLD':
 C_SIGNAL='@baseboard_fab2_lib.baseboard_fab2(sch_1):clk_25m_cpld';
NODE_NAME     R2T47 2
 '@BASEBOARD_FAB2_LIB.BASEBOARD_FAB2(SCH_1):PAGE101_I130@MSTR_DISCRETE.RES(CHIPS)':
 'B': CDS_PINID='B';
NODE_NAME     U8D7 L2
 '@BASEBOARD_FAB2_LIB.BASEBOARD_FAB2(SCH_1):PAGE190_I179@MSTR_MEMORY.LCMXO2_A(CHIPS)':
 'PL12A_PCLKT3_0': CDS_PINID='PL12A_PCLKT3_0';
NET_NAME
'CLK_25M_CPLD_R'
 '@BASEBOARD_FAB2_LIB.BASEBOARD_FAB2(SCH_1):CLK_25M_CPLD_R':
 C_SIGNAL='@baseboard_fab2_lib.baseboard_fab2(sch_1):clk_25m_cpld_r';
NODE_NAME     EU8F2 17
 '@BASEBOARD_FAB2_LIB.BASEBOARD_FAB2(SCH_1):PAGE101_I34@MSTR_CLOCK.ICS9FGP204(CHIPS)':
 '25MHZ_1': CDS_PINID='\25mhz_1\';
NODE_NAME     R2T47 1
 '@BASEBOARD_FAB2_LIB.BASEBOARD_FAB2(SCH_1):PAGE101_I130@MSTR_DISCRETE.RES(CHIPS)':
 'A': CDS_PINID='A';
NET_NAME
'CLK_322M_156M_CPU0_OSC_VRM_DN'
 '@BASEBOARD_FAB2_LIB.BASEBOARD_FAB2(SCH_1):CLK_322M_156M_CPU0_OSC_VRM_DN':
 C_SIGNAL='@baseboard_fab2_lib.baseboard_fab2(sch_1):clk_322m_156m_cpu0_osc_vrm_~
dn';
NODE_NAME     R6F6 1
 '@BASEBOARD_FAB2_LIB.BASEBOARD_FAB2(SCH_1):PAGE104_I41@MSTR_DISCRETE.RES(CHIPS)':
 'A': CDS_PINID='A';
NODE_NAME     R6F10 1
 '@BASEBOARD_FAB2_LIB.BASEBOARD_FAB2(SCH_1):PAGE104_I78@MSTR_DISCRETE.RES(CHIPS)':
 'A': CDS_PINID='A';
NODE_NAME     J6E1 F5
 '@BASEBOARD_FAB2_LIB.BASEBOARD_FAB2(SCH_1):PAGE194_I55@MSTR_SCONN.SCONN120_H61426002(CHIPS)':
 'IOF5': CDS_PINID='IOF5';
NET_NAME
'CLK_322M_156M_CPU0_OSC_VRM_DP'
 '@BASEBOARD_FAB2_LIB.BASEBOARD_FAB2(SCH_1):CLK_322M_156M_CPU0_OSC_VRM_DP':
 C_SIGNAL='@baseboard_fab2_lib.baseboard_fab2(sch_1):clk_322m_156m_cpu0_osc_vrm_~
dp';
NODE_NAME     R6F8 1
 '@BASEBOARD_FAB2_LIB.BASEBOARD_FAB2(SCH_1):PAGE104_I37@MSTR_DISCRETE.RES(CHIPS)':
 'A': CDS_PINID='A';
NODE_NAME     R6F11 1
 '@BASEBOARD_FAB2_LIB.BASEBOARD_FAB2(SCH_1):PAGE104_I79@MSTR_DISCRETE.RES(CHIPS)':
 'A': CDS_PINID='A';
NODE_NAME     J6E1 E5
 '@BASEBOARD_FAB2_LIB.BASEBOARD_FAB2(SCH_1):PAGE194_I55@MSTR_SCONN.SCONN120_H61426002(CHIPS)':
 'IOE5': CDS_PINID='IOE5';
NET_NAME
'CLK_322M_156M_CPU1_OSC_VRM_DN'
 '@BASEBOARD_FAB2_LIB.BASEBOARD_FAB2(SCH_1):CLK_322M_156M_CPU1_OSC_VRM_DN':
 C_SIGNAL='@baseboard_fab2_lib.baseboard_fab2(sch_1):clk_322m_156m_cpu1_osc_vrm_~
dn';
NODE_NAME     R3F1 1
 '@BASEBOARD_FAB2_LIB.BASEBOARD_FAB2(SCH_1):PAGE104_I51@MSTR_DISCRETE.RES(CHIPS)':
 'A': CDS_PINID='A';
NODE_NAME     R3F5 1
 '@BASEBOARD_FAB2_LIB.BASEBOARD_FAB2(SCH_1):PAGE104_I84@MSTR_DISCRETE.RES(CHIPS)':
 'A': CDS_PINID='A';
NODE_NAME     J4E1 F5
 '@BASEBOARD_FAB2_LIB.BASEBOARD_FAB2(SCH_1):PAGE193_I45@MSTR_SCONN.SCONN120_H61426002(CHIPS)':
 'IOF5': CDS_PINID='IOF5';
NET_NAME
'CLK_322M_156M_CPU1_OSC_VRM_DP'
 '@BASEBOARD_FAB2_LIB.BASEBOARD_FAB2(SCH_1):CLK_322M_156M_CPU1_OSC_VRM_DP':
 C_SIGNAL='@baseboard_fab2_lib.baseboard_fab2(sch_1):clk_322m_156m_cpu1_osc_vrm_~
dp';
NODE_NAME     R3F3 1
 '@BASEBOARD_FAB2_LIB.BASEBOARD_FAB2(SCH_1):PAGE104_I53@MSTR_DISCRETE.RES(CHIPS)':
 'A': CDS_PINID='A';
NODE_NAME     R3F6 1
 '@BASEBOARD_FAB2_LIB.BASEBOARD_FAB2(SCH_1):PAGE104_I88@MSTR_DISCRETE.RES(CHIPS)':
 'A': CDS_PINID='A';
NODE_NAME     J4E1 E5
 '@BASEBOARD_FAB2_LIB.BASEBOARD_FAB2(SCH_1):PAGE193_I45@MSTR_SCONN.SCONN120_H61426002(CHIPS)':
 'IOE5': CDS_PINID='IOE5';
NET_NAME
'CLK_322M_OSC_CPU0_RC_DN'
 '@BASEBOARD_FAB2_LIB.BASEBOARD_FAB2(SCH_1):CLK_322M_OSC_CPU0_RC_DN':
 C_SIGNAL='@baseboard_fab2_lib.baseboard_fab2(sch_1):clk_322m_osc_cpu0_rc_dn';
NODE_NAME     U5D1 AL26
 '@BASEBOARD_FAB2_LIB.BASEBOARD_FAB2(SCH_1):PAGE22_I204@CHPSET_LIB.SKX_EXT_B(CHIPS)':
 'RSVD'<213>: CDS_PINID='RSVD(213)';
NODE_NAME     R6F10 2
 '@BASEBOARD_FAB2_LIB.BASEBOARD_FAB2(SCH_1):PAGE104_I78@MSTR_DISCRETE.RES(CHIPS)':
 'B': CDS_PINID='B';
NET_NAME
'CLK_322M_OSC_CPU0_RC_DP'
 '@BASEBOARD_FAB2_LIB.BASEBOARD_FAB2(SCH_1):CLK_322M_OSC_CPU0_RC_DP':
 C_SIGNAL='@baseboard_fab2_lib.baseboard_fab2(sch_1):clk_322m_osc_cpu0_rc_dp';
NODE_NAME     U5D1 AK27
 '@BASEBOARD_FAB2_LIB.BASEBOARD_FAB2(SCH_1):PAGE22_I204@CHPSET_LIB.SKX_EXT_B(CHIPS)':
 'RSVD'<220>: CDS_PINID='RSVD(220)';
NODE_NAME     R6F11 2
 '@BASEBOARD_FAB2_LIB.BASEBOARD_FAB2(SCH_1):PAGE104_I79@MSTR_DISCRETE.RES(CHIPS)':
 'B': CDS_PINID='B';
NET_NAME
'CLK_322M_OSC_CPU1_RC_DN'
 '@BASEBOARD_FAB2_LIB.BASEBOARD_FAB2(SCH_1):CLK_322M_OSC_CPU1_RC_DN':
 C_SIGNAL='@baseboard_fab2_lib.baseboard_fab2(sch_1):clk_322m_osc_cpu1_rc_dn';
NODE_NAME     U2D1 AL26
 '@BASEBOARD_FAB2_LIB.BASEBOARD_FAB2(SCH_1):PAGE56_I169@CHPSET_LIB.SKX_EXT_B(CHIPS)':
 'RSVD'<213>: CDS_PINID='RSVD(213)';
NODE_NAME     R3F5 2
 '@BASEBOARD_FAB2_LIB.BASEBOARD_FAB2(SCH_1):PAGE104_I84@MSTR_DISCRETE.RES(CHIPS)':
 'B': CDS_PINID='B';
NET_NAME
'CLK_322M_OSC_CPU1_RC_DP'
 '@BASEBOARD_FAB2_LIB.BASEBOARD_FAB2(SCH_1):CLK_322M_OSC_CPU1_RC_DP':
 C_SIGNAL='@baseboard_fab2_lib.baseboard_fab2(sch_1):clk_322m_osc_cpu1_rc_dp';
NODE_NAME     U2D1 AK27
 '@BASEBOARD_FAB2_LIB.BASEBOARD_FAB2(SCH_1):PAGE56_I169@CHPSET_LIB.SKX_EXT_B(CHIPS)':
 'RSVD'<220>: CDS_PINID='RSVD(220)';
NODE_NAME     R3F6 2
 '@BASEBOARD_FAB2_LIB.BASEBOARD_FAB2(SCH_1):PAGE104_I88@MSTR_DISCRETE.RES(CHIPS)':
 'B': CDS_PINID='B';
NET_NAME
'CLK_32K_SUSCLK_PLD'
 '@BASEBOARD_FAB2_LIB.BASEBOARD_FAB2(SCH_1):CLK_32K_SUSCLK_PLD':
 C_SIGNAL='@baseboard_fab2_lib.baseboard_fab2(sch_1):clk_32k_susclk_pld';
NODE_NAME     U8D7 E1
 '@BASEBOARD_FAB2_LIB.BASEBOARD_FAB2(SCH_1):PAGE190_I179@MSTR_MEMORY.LCMXO2_A(CHIPS)':
 'PL3A_PCLKT5_0': CDS_PINID='PL3A_PCLKT5_0';
NODE_NAME     R8F27 2
 '@BASEBOARD_FAB2_LIB.BASEBOARD_FAB2(SCH_1):PAGE101_I142@MSTR_DISCRETE.RES(CHIPS)':
 'B': CDS_PINID='B';
NET_NAME
'CLK_32K_SUSCLK_PLD_R'
 '@BASEBOARD_FAB2_LIB.BASEBOARD_FAB2(SCH_1):CLK_32K_SUSCLK_PLD_R':
 C_SIGNAL='@baseboard_fab2_lib.baseboard_fab2(sch_1):clk_32k_susclk_pld_r';
NODE_NAME     EU8F2 13
 '@BASEBOARD_FAB2_LIB.BASEBOARD_FAB2(SCH_1):PAGE101_I34@MSTR_CLOCK.ICS9FGP204(CHIPS)':
 '32KHZ': CDS_PINID='\32khz\';
NODE_NAME     R8F27 1
 '@BASEBOARD_FAB2_LIB.BASEBOARD_FAB2(SCH_1):PAGE101_I142@MSTR_DISCRETE.RES(CHIPS)':
 'A': CDS_PINID='A';
NET_NAME
'CLK_48M_USB_BMC'
 '@BASEBOARD_FAB2_LIB.BASEBOARD_FAB2(SCH_1):CLK_48M_USB_BMC':
 C_SIGNAL='@baseboard_fab2_lib.baseboard_fab2(sch_1):clk_48m_usb_bmc';
NODE_NAME     U7C1 BW50
 '@BASEBOARD_FAB2_LIB.BASEBOARD_FAB2(SCH_1):PAGE114_I40@MSTR_U_PROC.LBG_CORE_QAT_EXT_D(CHIPS)':
 'CLOCKSE_BMCCLK': CDS_PINID='CLOCKSE_BMCCLK';
NODE_NAME     R25W140 1
 '@BASEBOARD_FAB2_LIB.BASEBOARD_FAB2(SCH_1):PAGE144_I148@MSTR_DISCRETE.RES(CHIPS)':
 'A': CDS_PINID='A';
NET_NAME
'CLK_48M_USB_BMC_R'
 '@BASEBOARD_FAB2_LIB.BASEBOARD_FAB2(SCH_1):CLK_48M_USB_BMC_R':
 C_SIGNAL='@baseboard_fab2_lib.baseboard_fab2(sch_1):clk_48m_usb_bmc_r';
NODE_NAME     U25W4 J20
 '@BASEBOARD_FAB2_LIB.BASEBOARD_FAB2(SCH_1):PAGE144_I95@W_HDL.AST2520A1-GP-GP(CHIPS)':
 'GPIOB4_USBCKI': CDS_PINID='GPIOB4_USBCKI';
NODE_NAME     R25W140 2
 '@BASEBOARD_FAB2_LIB.BASEBOARD_FAB2(SCH_1):PAGE144_I148@MSTR_DISCRETE.RES(CHIPS)':
 'B': CDS_PINID='B';
NET_NAME
'CLK_50M_CKMNG_BMC_1'
 '@BASEBOARD_FAB2_LIB.BASEBOARD_FAB2(SCH_1):CLK_50M_CKMNG_BMC_1':
 C_SIGNAL='@baseboard_fab2_lib.baseboard_fab2(sch_1):clk_50m_ckmng_bmc_1';
NODE_NAME     R2T46 2
 '@BASEBOARD_FAB2_LIB.BASEBOARD_FAB2(SCH_1):PAGE101_I125@MSTR_DISCRETE.RES(CHIPS)':
 'B': CDS_PINID='B';
NODE_NAME     U25W4 B4
 '@BASEBOARD_FAB2_LIB.BASEBOARD_FAB2(SCH_1):PAGE147_I106@W_HDL.AST2520A1-GP-GP(CHIPS)':
 'RGMII1RXCK_RMII1RCLKI_GPIOU4': CDS_PINID='RGMII1RXCK_RMII1RCLKI_GPIOU4';
NET_NAME
'CLK_50M_CKMNG_BMC_1_R'
 '@BASEBOARD_FAB2_LIB.BASEBOARD_FAB2(SCH_1):CLK_50M_CKMNG_BMC_1_R':
 C_SIGNAL='@baseboard_fab2_lib.baseboard_fab2(sch_1):clk_50m_ckmng_bmc_1_r';
NODE_NAME     EU8F2 32
 '@BASEBOARD_FAB2_LIB.BASEBOARD_FAB2(SCH_1):PAGE101_I34@MSTR_CLOCK.ICS9FGP204(CHIPS)':
 'RMII'<1>: CDS_PINID='RMII(1)';
NODE_NAME     R2T46 1
 '@BASEBOARD_FAB2_LIB.BASEBOARD_FAB2(SCH_1):PAGE101_I125@MSTR_DISCRETE.RES(CHIPS)':
 'A': CDS_PINID='A';
NET_NAME
'CLK_50M_CKMNG_BMC_2'
 '@BASEBOARD_FAB2_LIB.BASEBOARD_FAB2(SCH_1):CLK_50M_CKMNG_BMC_2':
 C_SIGNAL='@baseboard_fab2_lib.baseboard_fab2(sch_1):clk_50m_ckmng_bmc_2';
NODE_NAME     U25W4 C2
 '@BASEBOARD_FAB2_LIB.BASEBOARD_FAB2(SCH_1):PAGE147_I106@W_HDL.AST2520A1-GP-GP(CHIPS)':
 'RGMII2RXCK_RMII2RCLKI_GPIOV2': CDS_PINID='RGMII2RXCK_RMII2RCLKI_GPIOV2';
NODE_NAME     R8G1 2
 '@BASEBOARD_FAB2_LIB.BASEBOARD_FAB2(SCH_1):PAGE101_I145@MSTR_DISCRETE.RES(CHIPS)':
 'B': CDS_PINID='B';
NET_NAME
'CLK_50M_CKMNG_BMC_2_R'
 '@BASEBOARD_FAB2_LIB.BASEBOARD_FAB2(SCH_1):CLK_50M_CKMNG_BMC_2_R':
 C_SIGNAL='@baseboard_fab2_lib.baseboard_fab2(sch_1):clk_50m_ckmng_bmc_2_r';
NODE_NAME     EU8F2 29
 '@BASEBOARD_FAB2_LIB.BASEBOARD_FAB2(SCH_1):PAGE101_I34@MSTR_CLOCK.ICS9FGP204(CHIPS)':
 'RMII'<2>: CDS_PINID='RMII(2)';
NODE_NAME     R8G1 1
 '@BASEBOARD_FAB2_LIB.BASEBOARD_FAB2(SCH_1):PAGE101_I145@MSTR_DISCRETE.RES(CHIPS)':
 'A': CDS_PINID='A';
NET_NAME
'CLK_50M_CKMNG_OCP'
 '@BASEBOARD_FAB2_LIB.BASEBOARD_FAB2(SCH_1):CLK_50M_CKMNG_OCP':
 C_SIGNAL='@baseboard_fab2_lib.baseboard_fab2(sch_1):clk_50m_ckmng_ocp';
NODE_NAME     R2T42 2
 '@BASEBOARD_FAB2_LIB.BASEBOARD_FAB2(SCH_1):PAGE101_I124@MSTR_DISCRETE.RES(CHIPS)':
 'B': CDS_PINID='B';
NODE_NAME     J9B3 29
 '@BASEBOARD_FAB2_LIB.BASEBOARD_FAB2(SCH_1):PAGE186_I336@MSTR_SCONN.SCONN120_A28699018(CHIPS)':
 'IO29': CDS_PINID='IO29';
NET_NAME
'CLK_50M_CKMNG_OCP_R'
 '@BASEBOARD_FAB2_LIB.BASEBOARD_FAB2(SCH_1):CLK_50M_CKMNG_OCP_R':
 C_SIGNAL='@baseboard_fab2_lib.baseboard_fab2(sch_1):clk_50m_ckmng_ocp_r';
NODE_NAME     EU8F2 33
 '@BASEBOARD_FAB2_LIB.BASEBOARD_FAB2(SCH_1):PAGE101_I34@MSTR_CLOCK.ICS9FGP204(CHIPS)':
 'RMII'<0>: CDS_PINID='RMII(0)';
NODE_NAME     R2T42 1
 '@BASEBOARD_FAB2_LIB.BASEBOARD_FAB2(SCH_1):PAGE101_I124@MSTR_DISCRETE.RES(CHIPS)':
 'A': CDS_PINID='A';
NET_NAME
'CLK_50M_CKMNG_PCH_10GBE'
 '@BASEBOARD_FAB2_LIB.BASEBOARD_FAB2(SCH_1):CLK_50M_CKMNG_PCH_10GBE':
 C_SIGNAL='@baseboard_fab2_lib.baseboard_fab2(sch_1):clk_50m_ckmng_pch_10gbe';
NODE_NAME     U7C1 AJ1
 '@BASEBOARD_FAB2_LIB.BASEBOARD_FAB2(SCH_1):PAGE121_I34@MSTR_U_PROC.LBG_CORE_QAT_EXT_D(CHIPS)':
 'GPP_K0_LAN_NCSI_CLK_IN': CDS_PINID='GPP_K0_LAN_NCSI_CLK_IN';
NODE_NAME     R7C20 1
 '@BASEBOARD_FAB2_LIB.BASEBOARD_FAB2(SCH_1):PAGE121_I73@MSTR_DISCRETE.RES(CHIPS)':
 'A': CDS_PINID='A';
NODE_NAME     R8G24 2
 '@BASEBOARD_FAB2_LIB.BASEBOARD_FAB2(SCH_1):PAGE101_I143@MSTR_DISCRETE.RES(CHIPS)':
 'B': CDS_PINID='B';
NET_NAME
'CLK_50M_CKMNG_PCH_10GBE_R'
 '@BASEBOARD_FAB2_LIB.BASEBOARD_FAB2(SCH_1):CLK_50M_CKMNG_PCH_10GBE_R':
 C_SIGNAL='@baseboard_fab2_lib.baseboard_fab2(sch_1):clk_50m_ckmng_pch_10gbe_r';
NODE_NAME     EU8F2 25
 '@BASEBOARD_FAB2_LIB.BASEBOARD_FAB2(SCH_1):PAGE101_I34@MSTR_CLOCK.ICS9FGP204(CHIPS)':
 'RMII'<4>: CDS_PINID='RMII(4)';
NODE_NAME     R8G24 1
 '@BASEBOARD_FAB2_LIB.BASEBOARD_FAB2(SCH_1):PAGE101_I143@MSTR_DISCRETE.RES(CHIPS)':
 'A': CDS_PINID='A';
NET_NAME
'CLK_50M_CKMNG_SPRVLLE'
 '@BASEBOARD_FAB2_LIB.BASEBOARD_FAB2(SCH_1):CLK_50M_CKMNG_SPRVLLE':
 C_SIGNAL='@baseboard_fab2_lib.baseboard_fab2(sch_1):clk_50m_ckmng_sprvlle';
NODE_NAME     EU9E1 2
 '@BASEBOARD_FAB2_LIB.BASEBOARD_FAB2(SCH_1):PAGE139_I72@MSTR_INTEL.SPRINGVILLE(CHIPS)':
 'NC_SI_CLK_IN': CDS_PINID='NC_SI_CLK_IN';
NODE_NAME     R1R12 1
 '@BASEBOARD_FAB2_LIB.BASEBOARD_FAB2(SCH_1):PAGE139_I213@MSTR_DISCRETE.RES(CHIPS)':
 'A': CDS_PINID='A';
NODE_NAME     R8G25 2
 '@BASEBOARD_FAB2_LIB.BASEBOARD_FAB2(SCH_1):PAGE101_I144@MSTR_DISCRETE.RES(CHIPS)':
 'B': CDS_PINID='B';
NET_NAME
'CLK_50M_CKMNG_SPRVLLE_R'
 '@BASEBOARD_FAB2_LIB.BASEBOARD_FAB2(SCH_1):CLK_50M_CKMNG_SPRVLLE_R':
 C_SIGNAL='@baseboard_fab2_lib.baseboard_fab2(sch_1):clk_50m_ckmng_sprvlle_r';
NODE_NAME     EU8F2 28
 '@BASEBOARD_FAB2_LIB.BASEBOARD_FAB2(SCH_1):PAGE101_I34@MSTR_CLOCK.ICS9FGP204(CHIPS)':
 'RMII'<3>: CDS_PINID='RMII(3)';
NODE_NAME     R8G25 1
 '@BASEBOARD_FAB2_LIB.BASEBOARD_FAB2(SCH_1):PAGE101_I144@MSTR_DISCRETE.RES(CHIPS)':
 'A': CDS_PINID='A';
NET_NAME
'CPU_XDP_PRESENT_N'
 '@BASEBOARD_FAB2_LIB.BASEBOARD_FAB2(SCH_1):CPU_XDP_PRESENT_N':
 C_SIGNAL='@baseboard_fab2_lib.baseboard_fab2(sch_1):cpu_xdp_present_n';
NODE_NAME     U5D1 AV21
 '@BASEBOARD_FAB2_LIB.BASEBOARD_FAB2(SCH_1):PAGE22_I204@CHPSET_LIB.SKX_EXT_B(CHIPS)':
 'DEBUG_EN_N': CDS_PINID='DEBUG_EN_N';
NODE_NAME     U2D1 AV21
 '@BASEBOARD_FAB2_LIB.BASEBOARD_FAB2(SCH_1):PAGE56_I169@CHPSET_LIB.SKX_EXT_B(CHIPS)':
 'DEBUG_EN_N': CDS_PINID='DEBUG_EN_N';
NODE_NAME     R9A4 1
 '@BASEBOARD_FAB2_LIB.BASEBOARD_FAB2(SCH_1):PAGE111_I55@MSTR_DISCRETE.RES(CHIPS)':
 'A': CDS_PINID='A';
NODE_NAME     U25W15 4
 '@BASEBOARD_FAB2_LIB.BASEBOARD_FAB2(SCH_1):PAGE268_I12@MSTR_TTL.TTL1G07_A(CHIPS)':
 'Y': CDS_PINID='Y';
NODE_NAME     U25W14 4
 '@BASEBOARD_FAB2_LIB.BASEBOARD_FAB2(SCH_1):PAGE268_I13@MSTR_TTL.TTL1G07_A(CHIPS)':
 'Y': CDS_PINID='Y';
NET_NAME
'DEBUG_CARD2_PRSNT'
 '@BASEBOARD_FAB2_LIB.BASEBOARD_FAB2(SCH_1):DEBUG_CARD2_PRSNT':
 C_SIGNAL='@baseboard_fab2_lib.baseboard_fab2(sch_1):debug_card2_prsnt';
NODE_NAME     J9B1 7
 '@BASEBOARD_FAB2_LIB.BASEBOARD_FAB2(SCH_1):PAGE176_I69@MSTR_CONN.CONN9_H51826001(CHIPS)':
 'GND_DRAIN': CDS_PINID='GND_DRAIN';
NODE_NAME     U6W4 1
 '@BASEBOARD_FAB2_LIB.BASEBOARD_FAB2(SCH_1):PAGE176_I146@MSTR_TTL.TTL1G126_A(CHIPS)':
 'OE': CDS_PINID='OE';
NODE_NAME     U6W5 1
 '@BASEBOARD_FAB2_LIB.BASEBOARD_FAB2(SCH_1):PAGE176_I148@MSTR_TTL.TTL1G126_A(CHIPS)':
 'OE': CDS_PINID='OE';
NODE_NAME     Q6W4 1
 '@BASEBOARD_FAB2_LIB.BASEBOARD_FAB2(SCH_1):PAGE168_I43@MSTR_DISCRETE.FET_N(CHIPS)':
 'GATE': CDS_PINID='GATE';
NODE_NAME     R6W38 1
 '@BASEBOARD_FAB2_LIB.BASEBOARD_FAB2(SCH_1):PAGE176_I156@MSTR_DISCRETE.RES(CHIPS)':
 'A': CDS_PINID='A';
NODE_NAME     U1W3 5
 '@BASEBOARD_FAB2_LIB.BASEBOARD_FAB2(SCH_1):PAGE176_I162@MSTR_DIGITAL.PCA9617(CHIPS)':
 'EN': CDS_PINID='EN';
NODE_NAME     U6W12 6
 '@BASEBOARD_FAB2_LIB.BASEBOARD_FAB2(SCH_1):PAGE176_I182@MSTR_ANALOG.NC7SB3157(CHIPS)':
 'S': CDS_PINID='S';
NET_NAME
'DMI_CPU0_PCH_RX_C_DN<0>'
 '@BASEBOARD_FAB2_LIB.BASEBOARD_FAB2(SCH_1):DMI_CPU0_PCH_RX_C_DN'<0>:
 C_SIGNAL='@baseboard_fab2_lib.baseboard_fab2(sch_1):dmi_cpu0_pch_rx_c_dn(0)';
NODE_NAME     U5D1 CK9
 '@BASEBOARD_FAB2_LIB.BASEBOARD_FAB2(SCH_1):PAGE29_I61@CHPSET_LIB.SKX_EXT_B(CHIPS)':
 'DMI_RX_DN'<0>: CDS_PINID='DMI_RX_DN(0)';
NODE_NAME     C3M44 2
 '@BASEBOARD_FAB2_LIB.BASEBOARD_FAB2(SCH_1):PAGE129_I80@MSTR_DISCRETE.CAP(CHIPS)':
 'B': CDS_PINID='B';
NET_NAME
'DMI_CPU0_PCH_RX_C_DN<1>'
 '@BASEBOARD_FAB2_LIB.BASEBOARD_FAB2(SCH_1):DMI_CPU0_PCH_RX_C_DN'<1>:
 C_SIGNAL='@baseboard_fab2_lib.baseboard_fab2(sch_1):dmi_cpu0_pch_rx_c_dn(1)';
NODE_NAME     U5D1 CM11
 '@BASEBOARD_FAB2_LIB.BASEBOARD_FAB2(SCH_1):PAGE29_I61@CHPSET_LIB.SKX_EXT_B(CHIPS)':
 'DMI_RX_DN'<1>: CDS_PINID='DMI_RX_DN(1)';
NODE_NAME     C3M41 2
 '@BASEBOARD_FAB2_LIB.BASEBOARD_FAB2(SCH_1):PAGE129_I81@MSTR_DISCRETE.CAP(CHIPS)':
 'B': CDS_PINID='B';
NET_NAME
'DMI_CPU0_PCH_RX_C_DN<2>'
 '@BASEBOARD_FAB2_LIB.BASEBOARD_FAB2(SCH_1):DMI_CPU0_PCH_RX_C_DN'<2>:
 C_SIGNAL='@baseboard_fab2_lib.baseboard_fab2(sch_1):dmi_cpu0_pch_rx_c_dn(2)';
NODE_NAME     U5D1 CR12
 '@BASEBOARD_FAB2_LIB.BASEBOARD_FAB2(SCH_1):PAGE29_I61@CHPSET_LIB.SKX_EXT_B(CHIPS)':
 'DMI_RX_DN'<2>: CDS_PINID='DMI_RX_DN(2)';
NODE_NAME     C3M45 2
 '@BASEBOARD_FAB2_LIB.BASEBOARD_FAB2(SCH_1):PAGE129_I82@MSTR_DISCRETE.CAP(CHIPS)':
 'B': CDS_PINID='B';
NET_NAME
'DMI_CPU0_PCH_RX_C_DN<3>'
 '@BASEBOARD_FAB2_LIB.BASEBOARD_FAB2(SCH_1):DMI_CPU0_PCH_RX_C_DN'<3>:
 C_SIGNAL='@baseboard_fab2_lib.baseboard_fab2(sch_1):dmi_cpu0_pch_rx_c_dn(3)';
NODE_NAME     U5D1 CT11
 '@BASEBOARD_FAB2_LIB.BASEBOARD_FAB2(SCH_1):PAGE29_I61@CHPSET_LIB.SKX_EXT_B(CHIPS)':
 'DMI_RX_DN'<3>: CDS_PINID='DMI_RX_DN(3)';
NODE_NAME     C3N13 2
 '@BASEBOARD_FAB2_LIB.BASEBOARD_FAB2(SCH_1):PAGE129_I83@MSTR_DISCRETE.CAP(CHIPS)':
 'B': CDS_PINID='B';
NET_NAME
'DMI_CPU0_PCH_RX_C_DP<0>'
 '@BASEBOARD_FAB2_LIB.BASEBOARD_FAB2(SCH_1):DMI_CPU0_PCH_RX_C_DP'<0>:
 C_SIGNAL='@baseboard_fab2_lib.baseboard_fab2(sch_1):dmi_cpu0_pch_rx_c_dp(0)';
NODE_NAME     U5D1 CL10
 '@BASEBOARD_FAB2_LIB.BASEBOARD_FAB2(SCH_1):PAGE29_I61@CHPSET_LIB.SKX_EXT_B(CHIPS)':
 'DMI_RX_DP'<0>: CDS_PINID='DMI_RX_DP(0)';
NODE_NAME     C3M40 2
 '@BASEBOARD_FAB2_LIB.BASEBOARD_FAB2(SCH_1):PAGE129_I72@MSTR_DISCRETE.CAP(CHIPS)':
 'B': CDS_PINID='B';
NET_NAME
'DMI_CPU0_PCH_RX_C_DP<1>'
 '@BASEBOARD_FAB2_LIB.BASEBOARD_FAB2(SCH_1):DMI_CPU0_PCH_RX_C_DP'<1>:
 C_SIGNAL='@baseboard_fab2_lib.baseboard_fab2(sch_1):dmi_cpu0_pch_rx_c_dp(1)';
NODE_NAME     U5D1 CN10
 '@BASEBOARD_FAB2_LIB.BASEBOARD_FAB2(SCH_1):PAGE29_I61@CHPSET_LIB.SKX_EXT_B(CHIPS)':
 'DMI_RX_DP'<1>: CDS_PINID='DMI_RX_DP(1)';
NODE_NAME     C3M37 2
 '@BASEBOARD_FAB2_LIB.BASEBOARD_FAB2(SCH_1):PAGE129_I73@MSTR_DISCRETE.CAP(CHIPS)':
 'B': CDS_PINID='B';
NET_NAME
'DMI_CPU0_PCH_RX_C_DP<2>'
 '@BASEBOARD_FAB2_LIB.BASEBOARD_FAB2(SCH_1):DMI_CPU0_PCH_RX_C_DP'<2>:
 C_SIGNAL='@baseboard_fab2_lib.baseboard_fab2(sch_1):dmi_cpu0_pch_rx_c_dp(2)';
NODE_NAME     U5D1 CP11
 '@BASEBOARD_FAB2_LIB.BASEBOARD_FAB2(SCH_1):PAGE29_I61@CHPSET_LIB.SKX_EXT_B(CHIPS)':
 'DMI_RX_DP'<2>: CDS_PINID='DMI_RX_DP(2)';
NODE_NAME     C3N9 2
 '@BASEBOARD_FAB2_LIB.BASEBOARD_FAB2(SCH_1):PAGE129_I74@MSTR_DISCRETE.CAP(CHIPS)':
 'B': CDS_PINID='B';
NET_NAME
'DMI_CPU0_PCH_RX_C_DP<3>'
 '@BASEBOARD_FAB2_LIB.BASEBOARD_FAB2(SCH_1):DMI_CPU0_PCH_RX_C_DP'<3>:
 C_SIGNAL='@baseboard_fab2_lib.baseboard_fab2(sch_1):dmi_cpu0_pch_rx_c_dp(3)';
NODE_NAME     U5D1 CV11
 '@BASEBOARD_FAB2_LIB.BASEBOARD_FAB2(SCH_1):PAGE29_I61@CHPSET_LIB.SKX_EXT_B(CHIPS)':
 'DMI_RX_DP'<3>: CDS_PINID='DMI_RX_DP(3)';
NODE_NAME     C3N8 2
 '@BASEBOARD_FAB2_LIB.BASEBOARD_FAB2(SCH_1):PAGE129_I75@MSTR_DISCRETE.CAP(CHIPS)':
 'B': CDS_PINID='B';
NET_NAME
'DMI_CPU0_PCH_RX_DN<0>'
 '@BASEBOARD_FAB2_LIB.BASEBOARD_FAB2(SCH_1):DMI_CPU0_PCH_RX_DN'<0>:
 C_SIGNAL='@baseboard_fab2_lib.baseboard_fab2(sch_1):dmi_cpu0_pch_rx_dn(0)';
NODE_NAME     U7C1 H46
 '@BASEBOARD_FAB2_LIB.BASEBOARD_FAB2(SCH_1):PAGE117_I9@MSTR_U_PROC.LBG_CORE_QAT_EXT_D(CHIPS)':
 'DMI_TXN'<0>: CDS_PINID='DMI_TXN(0)';
NODE_NAME     C3M44 1
 '@BASEBOARD_FAB2_LIB.BASEBOARD_FAB2(SCH_1):PAGE129_I80@MSTR_DISCRETE.CAP(CHIPS)':
 'A': CDS_PINID='A';
NET_NAME
'DMI_CPU0_PCH_RX_DN<1>'
 '@BASEBOARD_FAB2_LIB.BASEBOARD_FAB2(SCH_1):DMI_CPU0_PCH_RX_DN'<1>:
 C_SIGNAL='@baseboard_fab2_lib.baseboard_fab2(sch_1):dmi_cpu0_pch_rx_dn(1)';
NODE_NAME     U7C1 J48
 '@BASEBOARD_FAB2_LIB.BASEBOARD_FAB2(SCH_1):PAGE117_I9@MSTR_U_PROC.LBG_CORE_QAT_EXT_D(CHIPS)':
 'DMI_TXN'<1>: CDS_PINID='DMI_TXN(1)';
NODE_NAME     C3M41 1
 '@BASEBOARD_FAB2_LIB.BASEBOARD_FAB2(SCH_1):PAGE129_I81@MSTR_DISCRETE.CAP(CHIPS)':
 'A': CDS_PINID='A';
NET_NAME
'DMI_CPU0_PCH_RX_DN<2>'
 '@BASEBOARD_FAB2_LIB.BASEBOARD_FAB2(SCH_1):DMI_CPU0_PCH_RX_DN'<2>:
 C_SIGNAL='@baseboard_fab2_lib.baseboard_fab2(sch_1):dmi_cpu0_pch_rx_dn(2)';
NODE_NAME     U7C1 K50
 '@BASEBOARD_FAB2_LIB.BASEBOARD_FAB2(SCH_1):PAGE117_I9@MSTR_U_PROC.LBG_CORE_QAT_EXT_D(CHIPS)':
 'DMI_TXN'<2>: CDS_PINID='DMI_TXN(2)';
NODE_NAME     C3M45 1
 '@BASEBOARD_FAB2_LIB.BASEBOARD_FAB2(SCH_1):PAGE129_I82@MSTR_DISCRETE.CAP(CHIPS)':
 'A': CDS_PINID='A';
NET_NAME
'DMI_CPU0_PCH_RX_DN<3>'
 '@BASEBOARD_FAB2_LIB.BASEBOARD_FAB2(SCH_1):DMI_CPU0_PCH_RX_DN'<3>:
 C_SIGNAL='@baseboard_fab2_lib.baseboard_fab2(sch_1):dmi_cpu0_pch_rx_dn(3)';
NODE_NAME     U7C1 P52
 '@BASEBOARD_FAB2_LIB.BASEBOARD_FAB2(SCH_1):PAGE117_I9@MSTR_U_PROC.LBG_CORE_QAT_EXT_D(CHIPS)':
 'DMI_TXN'<3>: CDS_PINID='DMI_TXN(3)';
NODE_NAME     C3N13 1
 '@BASEBOARD_FAB2_LIB.BASEBOARD_FAB2(SCH_1):PAGE129_I83@MSTR_DISCRETE.CAP(CHIPS)':
 'A': CDS_PINID='A';
NET_NAME
'DMI_CPU0_PCH_RX_DP<0>'
 '@BASEBOARD_FAB2_LIB.BASEBOARD_FAB2(SCH_1):DMI_CPU0_PCH_RX_DP'<0>:
 C_SIGNAL='@baseboard_fab2_lib.baseboard_fab2(sch_1):dmi_cpu0_pch_rx_dp(0)';
NODE_NAME     U7C1 K46
 '@BASEBOARD_FAB2_LIB.BASEBOARD_FAB2(SCH_1):PAGE117_I9@MSTR_U_PROC.LBG_CORE_QAT_EXT_D(CHIPS)':
 'DMI_TXP'<0>: CDS_PINID='DMI_TXP(0)';
NODE_NAME     C3M40 1
 '@BASEBOARD_FAB2_LIB.BASEBOARD_FAB2(SCH_1):PAGE129_I72@MSTR_DISCRETE.CAP(CHIPS)':
 'A': CDS_PINID='A';
NET_NAME
'DMI_CPU0_PCH_RX_DP<1>'
 '@BASEBOARD_FAB2_LIB.BASEBOARD_FAB2(SCH_1):DMI_CPU0_PCH_RX_DP'<1>:
 C_SIGNAL='@baseboard_fab2_lib.baseboard_fab2(sch_1):dmi_cpu0_pch_rx_dp(1)';
NODE_NAME     U7C1 H50
 '@BASEBOARD_FAB2_LIB.BASEBOARD_FAB2(SCH_1):PAGE117_I9@MSTR_U_PROC.LBG_CORE_QAT_EXT_D(CHIPS)':
 'DMI_TXP'<1>: CDS_PINID='DMI_TXP(1)';
NODE_NAME     C3M37 1
 '@BASEBOARD_FAB2_LIB.BASEBOARD_FAB2(SCH_1):PAGE129_I73@MSTR_DISCRETE.CAP(CHIPS)':
 'A': CDS_PINID='A';
NET_NAME
'DMI_CPU0_PCH_RX_DP<2>'
 '@BASEBOARD_FAB2_LIB.BASEBOARD_FAB2(SCH_1):DMI_CPU0_PCH_RX_DP'<2>:
 C_SIGNAL='@baseboard_fab2_lib.baseboard_fab2(sch_1):dmi_cpu0_pch_rx_dp(2)';
NODE_NAME     U7C1 M52
 '@BASEBOARD_FAB2_LIB.BASEBOARD_FAB2(SCH_1):PAGE117_I9@MSTR_U_PROC.LBG_CORE_QAT_EXT_D(CHIPS)':
 'DMI_TXP'<2>: CDS_PINID='DMI_TXP(2)';
NODE_NAME     C3N9 1
 '@BASEBOARD_FAB2_LIB.BASEBOARD_FAB2(SCH_1):PAGE129_I74@MSTR_DISCRETE.CAP(CHIPS)':
 'A': CDS_PINID='A';
NET_NAME
'DMI_CPU0_PCH_RX_DP<3>'
 '@BASEBOARD_FAB2_LIB.BASEBOARD_FAB2(SCH_1):DMI_CPU0_PCH_RX_DP'<3>:
 C_SIGNAL='@baseboard_fab2_lib.baseboard_fab2(sch_1):dmi_cpu0_pch_rx_dp(3)';
NODE_NAME     U7C1 N54
 '@BASEBOARD_FAB2_LIB.BASEBOARD_FAB2(SCH_1):PAGE117_I9@MSTR_U_PROC.LBG_CORE_QAT_EXT_D(CHIPS)':
 'DMI_TXP'<3>: CDS_PINID='DMI_TXP(3)';
NODE_NAME     C3N8 1
 '@BASEBOARD_FAB2_LIB.BASEBOARD_FAB2(SCH_1):PAGE129_I75@MSTR_DISCRETE.CAP(CHIPS)':
 'A': CDS_PINID='A';
NET_NAME
'DMI_CPU0_PCH_TX_C_DN<0>'
 '@BASEBOARD_FAB2_LIB.BASEBOARD_FAB2(SCH_1):DMI_CPU0_PCH_TX_C_DN'<0>:
 C_SIGNAL='@baseboard_fab2_lib.baseboard_fab2(sch_1):dmi_cpu0_pch_tx_c_dn(0)';
NODE_NAME     U7C1 D42
 '@BASEBOARD_FAB2_LIB.BASEBOARD_FAB2(SCH_1):PAGE117_I9@MSTR_U_PROC.LBG_CORE_QAT_EXT_D(CHIPS)':
 'DMI_RXN'<0>: CDS_PINID='DMI_RXN(0)';
NODE_NAME     C7C3 2
 '@BASEBOARD_FAB2_LIB.BASEBOARD_FAB2(SCH_1):PAGE129_I76@MSTR_DISCRETE.CAP(CHIPS)':
 'B': CDS_PINID='B';
NET_NAME
'DMI_CPU0_PCH_TX_C_DN<1>'
 '@BASEBOARD_FAB2_LIB.BASEBOARD_FAB2(SCH_1):DMI_CPU0_PCH_TX_C_DN'<1>:
 C_SIGNAL='@baseboard_fab2_lib.baseboard_fab2(sch_1):dmi_cpu0_pch_tx_c_dn(1)';
NODE_NAME     U7C1 C43
 '@BASEBOARD_FAB2_LIB.BASEBOARD_FAB2(SCH_1):PAGE117_I9@MSTR_U_PROC.LBG_CORE_QAT_EXT_D(CHIPS)':
 'DMI_RXN'<1>: CDS_PINID='DMI_RXN(1)';
NODE_NAME     C7C1 2
 '@BASEBOARD_FAB2_LIB.BASEBOARD_FAB2(SCH_1):PAGE129_I77@MSTR_DISCRETE.CAP(CHIPS)':
 'B': CDS_PINID='B';
NET_NAME
'DMI_CPU0_PCH_TX_C_DN<2>'
 '@BASEBOARD_FAB2_LIB.BASEBOARD_FAB2(SCH_1):DMI_CPU0_PCH_TX_C_DN'<2>:
 C_SIGNAL='@baseboard_fab2_lib.baseboard_fab2(sch_1):dmi_cpu0_pch_tx_c_dn(2)';
NODE_NAME     U7C1 D44
 '@BASEBOARD_FAB2_LIB.BASEBOARD_FAB2(SCH_1):PAGE117_I9@MSTR_U_PROC.LBG_CORE_QAT_EXT_D(CHIPS)':
 'DMI_RXN'<2>: CDS_PINID='DMI_RXN(2)';
NODE_NAME     C7B29 2
 '@BASEBOARD_FAB2_LIB.BASEBOARD_FAB2(SCH_1):PAGE129_I78@MSTR_DISCRETE.CAP(CHIPS)':
 'B': CDS_PINID='B';
NET_NAME
'DMI_CPU0_PCH_TX_C_DN<3>'
 '@BASEBOARD_FAB2_LIB.BASEBOARD_FAB2(SCH_1):DMI_CPU0_PCH_TX_C_DN'<3>:
 C_SIGNAL='@baseboard_fab2_lib.baseboard_fab2(sch_1):dmi_cpu0_pch_tx_c_dn(3)';
NODE_NAME     U7C1 C45
 '@BASEBOARD_FAB2_LIB.BASEBOARD_FAB2(SCH_1):PAGE117_I9@MSTR_U_PROC.LBG_CORE_QAT_EXT_D(CHIPS)':
 'DMI_RXN'<3>: CDS_PINID='DMI_RXN(3)';
NODE_NAME     C7B26 2
 '@BASEBOARD_FAB2_LIB.BASEBOARD_FAB2(SCH_1):PAGE129_I79@MSTR_DISCRETE.CAP(CHIPS)':
 'B': CDS_PINID='B';
NET_NAME
'DMI_CPU0_PCH_TX_C_DP<0>'
 '@BASEBOARD_FAB2_LIB.BASEBOARD_FAB2(SCH_1):DMI_CPU0_PCH_TX_C_DP'<0>:
 C_SIGNAL='@baseboard_fab2_lib.baseboard_fab2(sch_1):dmi_cpu0_pch_tx_c_dp(0)';
NODE_NAME     U7C1 B42
 '@BASEBOARD_FAB2_LIB.BASEBOARD_FAB2(SCH_1):PAGE117_I9@MSTR_U_PROC.LBG_CORE_QAT_EXT_D(CHIPS)':
 'DMI_RXP'<0>: CDS_PINID='DMI_RXP(0)';
NODE_NAME     C7C2 2
 '@BASEBOARD_FAB2_LIB.BASEBOARD_FAB2(SCH_1):PAGE129_I71@MSTR_DISCRETE.CAP(CHIPS)':
 'B': CDS_PINID='B';
NET_NAME
'DMI_CPU0_PCH_TX_C_DP<1>'
 '@BASEBOARD_FAB2_LIB.BASEBOARD_FAB2(SCH_1):DMI_CPU0_PCH_TX_C_DP'<1>:
 C_SIGNAL='@baseboard_fab2_lib.baseboard_fab2(sch_1):dmi_cpu0_pch_tx_c_dp(1)';
NODE_NAME     U7C1 A43
 '@BASEBOARD_FAB2_LIB.BASEBOARD_FAB2(SCH_1):PAGE117_I9@MSTR_U_PROC.LBG_CORE_QAT_EXT_D(CHIPS)':
 'DMI_RXP'<1>: CDS_PINID='DMI_RXP(1)';
NODE_NAME     C7B28 2
 '@BASEBOARD_FAB2_LIB.BASEBOARD_FAB2(SCH_1):PAGE129_I70@MSTR_DISCRETE.CAP(CHIPS)':
 'B': CDS_PINID='B';
NET_NAME
'DMI_CPU0_PCH_TX_C_DP<2>'
 '@BASEBOARD_FAB2_LIB.BASEBOARD_FAB2(SCH_1):DMI_CPU0_PCH_TX_C_DP'<2>:
 C_SIGNAL='@baseboard_fab2_lib.baseboard_fab2(sch_1):dmi_cpu0_pch_tx_c_dp(2)';
NODE_NAME     U7C1 B44
 '@BASEBOARD_FAB2_LIB.BASEBOARD_FAB2(SCH_1):PAGE117_I9@MSTR_U_PROC.LBG_CORE_QAT_EXT_D(CHIPS)':
 'DMI_RXP'<2>: CDS_PINID='DMI_RXP(2)';
NODE_NAME     C7B27 2
 '@BASEBOARD_FAB2_LIB.BASEBOARD_FAB2(SCH_1):PAGE129_I69@MSTR_DISCRETE.CAP(CHIPS)':
 'B': CDS_PINID='B';
NET_NAME
'DMI_CPU0_PCH_TX_C_DP<3>'
 '@BASEBOARD_FAB2_LIB.BASEBOARD_FAB2(SCH_1):DMI_CPU0_PCH_TX_C_DP'<3>:
 C_SIGNAL='@baseboard_fab2_lib.baseboard_fab2(sch_1):dmi_cpu0_pch_tx_c_dp(3)';
NODE_NAME     U7C1 A45
 '@BASEBOARD_FAB2_LIB.BASEBOARD_FAB2(SCH_1):PAGE117_I9@MSTR_U_PROC.LBG_CORE_QAT_EXT_D(CHIPS)':
 'DMI_RXP'<3>: CDS_PINID='DMI_RXP(3)';
NODE_NAME     C7B25 2
 '@BASEBOARD_FAB2_LIB.BASEBOARD_FAB2(SCH_1):PAGE129_I35@MSTR_DISCRETE.CAP(CHIPS)':
 'B': CDS_PINID='B';
NET_NAME
'DMI_CPU0_PCH_TX_DN<0>'
 '@BASEBOARD_FAB2_LIB.BASEBOARD_FAB2(SCH_1):DMI_CPU0_PCH_TX_DN'<0>:
 C_SIGNAL='@baseboard_fab2_lib.baseboard_fab2(sch_1):dmi_cpu0_pch_tx_dn(0)';
NODE_NAME     U5D1 CG4
 '@BASEBOARD_FAB2_LIB.BASEBOARD_FAB2(SCH_1):PAGE29_I61@CHPSET_LIB.SKX_EXT_B(CHIPS)':
 'DMI_TX_DN'<0>: CDS_PINID='DMI_TX_DN(0)';
NODE_NAME     C7C3 1
 '@BASEBOARD_FAB2_LIB.BASEBOARD_FAB2(SCH_1):PAGE129_I76@MSTR_DISCRETE.CAP(CHIPS)':
 'A': CDS_PINID='A';
NET_NAME
'DMI_CPU0_PCH_TX_DN<1>'
 '@BASEBOARD_FAB2_LIB.BASEBOARD_FAB2(SCH_1):DMI_CPU0_PCH_TX_DN'<1>:
 C_SIGNAL='@baseboard_fab2_lib.baseboard_fab2(sch_1):dmi_cpu0_pch_tx_dn(1)';
NODE_NAME     U5D1 CJ4
 '@BASEBOARD_FAB2_LIB.BASEBOARD_FAB2(SCH_1):PAGE29_I61@CHPSET_LIB.SKX_EXT_B(CHIPS)':
 'DMI_TX_DN'<1>: CDS_PINID='DMI_TX_DN(1)';
NODE_NAME     C7C1 1
 '@BASEBOARD_FAB2_LIB.BASEBOARD_FAB2(SCH_1):PAGE129_I77@MSTR_DISCRETE.CAP(CHIPS)':
 'A': CDS_PINID='A';
NET_NAME
'DMI_CPU0_PCH_TX_DN<2>'
 '@BASEBOARD_FAB2_LIB.BASEBOARD_FAB2(SCH_1):DMI_CPU0_PCH_TX_DN'<2>:
 C_SIGNAL='@baseboard_fab2_lib.baseboard_fab2(sch_1):dmi_cpu0_pch_tx_dn(2)';
NODE_NAME     U5D1 CN4
 '@BASEBOARD_FAB2_LIB.BASEBOARD_FAB2(SCH_1):PAGE29_I61@CHPSET_LIB.SKX_EXT_B(CHIPS)':
 'DMI_TX_DN'<2>: CDS_PINID='DMI_TX_DN(2)';
NODE_NAME     C7B29 1
 '@BASEBOARD_FAB2_LIB.BASEBOARD_FAB2(SCH_1):PAGE129_I78@MSTR_DISCRETE.CAP(CHIPS)':
 'A': CDS_PINID='A';
NET_NAME
'DMI_CPU0_PCH_TX_DN<3>'
 '@BASEBOARD_FAB2_LIB.BASEBOARD_FAB2(SCH_1):DMI_CPU0_PCH_TX_DN'<3>:
 C_SIGNAL='@baseboard_fab2_lib.baseboard_fab2(sch_1):dmi_cpu0_pch_tx_dn(3)';
NODE_NAME     U5D1 CP5
 '@BASEBOARD_FAB2_LIB.BASEBOARD_FAB2(SCH_1):PAGE29_I61@CHPSET_LIB.SKX_EXT_B(CHIPS)':
 'DMI_TX_DN'<3>: CDS_PINID='DMI_TX_DN(3)';
NODE_NAME     C7B26 1
 '@BASEBOARD_FAB2_LIB.BASEBOARD_FAB2(SCH_1):PAGE129_I79@MSTR_DISCRETE.CAP(CHIPS)':
 'A': CDS_PINID='A';
NET_NAME
'DMI_CPU0_PCH_TX_DP<0>'
 '@BASEBOARD_FAB2_LIB.BASEBOARD_FAB2(SCH_1):DMI_CPU0_PCH_TX_DP'<0>:
 C_SIGNAL='@baseboard_fab2_lib.baseboard_fab2(sch_1):dmi_cpu0_pch_tx_dp(0)';
NODE_NAME     U5D1 CH5
 '@BASEBOARD_FAB2_LIB.BASEBOARD_FAB2(SCH_1):PAGE29_I61@CHPSET_LIB.SKX_EXT_B(CHIPS)':
 'DMI_TX_DP'<0>: CDS_PINID='DMI_TX_DP(0)';
NODE_NAME     C7C2 1
 '@BASEBOARD_FAB2_LIB.BASEBOARD_FAB2(SCH_1):PAGE129_I71@MSTR_DISCRETE.CAP(CHIPS)':
 'A': CDS_PINID='A';
NET_NAME
'DMI_CPU0_PCH_TX_DP<1>'
 '@BASEBOARD_FAB2_LIB.BASEBOARD_FAB2(SCH_1):DMI_CPU0_PCH_TX_DP'<1>:
 C_SIGNAL='@baseboard_fab2_lib.baseboard_fab2(sch_1):dmi_cpu0_pch_tx_dp(1)';
NODE_NAME     U5D1 CL4
 '@BASEBOARD_FAB2_LIB.BASEBOARD_FAB2(SCH_1):PAGE29_I61@CHPSET_LIB.SKX_EXT_B(CHIPS)':
 'DMI_TX_DP'<1>: CDS_PINID='DMI_TX_DP(1)';
NODE_NAME     C7B28 1
 '@BASEBOARD_FAB2_LIB.BASEBOARD_FAB2(SCH_1):PAGE129_I70@MSTR_DISCRETE.CAP(CHIPS)':
 'A': CDS_PINID='A';
NET_NAME
'DMI_CPU0_PCH_TX_DP<2>'
 '@BASEBOARD_FAB2_LIB.BASEBOARD_FAB2(SCH_1):DMI_CPU0_PCH_TX_DP'<2>:
 C_SIGNAL='@baseboard_fab2_lib.baseboard_fab2(sch_1):dmi_cpu0_pch_tx_dp(2)';
NODE_NAME     U5D1 CM3
 '@BASEBOARD_FAB2_LIB.BASEBOARD_FAB2(SCH_1):PAGE29_I61@CHPSET_LIB.SKX_EXT_B(CHIPS)':
 'DMI_TX_DP'<2>: CDS_PINID='DMI_TX_DP(2)';
NODE_NAME     C7B27 1
 '@BASEBOARD_FAB2_LIB.BASEBOARD_FAB2(SCH_1):PAGE129_I69@MSTR_DISCRETE.CAP(CHIPS)':
 'A': CDS_PINID='A';
NET_NAME
'DMI_CPU0_PCH_TX_DP<3>'
 '@BASEBOARD_FAB2_LIB.BASEBOARD_FAB2(SCH_1):DMI_CPU0_PCH_TX_DP'<3>:
 C_SIGNAL='@baseboard_fab2_lib.baseboard_fab2(sch_1):dmi_cpu0_pch_tx_dp(3)';
NODE_NAME     U5D1 CR4
 '@BASEBOARD_FAB2_LIB.BASEBOARD_FAB2(SCH_1):PAGE29_I61@CHPSET_LIB.SKX_EXT_B(CHIPS)':
 'DMI_TX_DP'<3>: CDS_PINID='DMI_TX_DP(3)';
NODE_NAME     C7B25 1
 '@BASEBOARD_FAB2_LIB.BASEBOARD_FAB2(SCH_1):PAGE129_I35@MSTR_DISCRETE.CAP(CHIPS)':
 'A': CDS_PINID='A';
NET_NAME
'EXT_MDIO_I2C_SEL'
 '@BASEBOARD_FAB2_LIB.BASEBOARD_FAB2(SCH_1):EXT_MDIO_I2C_SEL':
 C_SIGNAL='@baseboard_fab2_lib.baseboard_fab2(sch_1):ext_mdio_i2c_sel';
NODE_NAME     J8E4 3
 '@BASEBOARD_FAB2_LIB.BASEBOARD_FAB2(SCH_1):PAGE188_I27@MSTR_SCONN.SCONN64_H87568002_A(CHIPS)':
 'IO3': CDS_PINID='IO3';
NODE_NAME     R1W40 2
 '@BASEBOARD_FAB2_LIB.BASEBOARD_FAB2(SCH_1):PAGE188_I128@MSTR_DISCRETE.RES(CHIPS)':
 'B': CDS_PINID='B';
NODE_NAME     R1W41 2
 '@BASEBOARD_FAB2_LIB.BASEBOARD_FAB2(SCH_1):PAGE188_I129@MSTR_DISCRETE.RES(CHIPS)':
 'B': CDS_PINID='B';
NET_NAME
'FAN_PWM_OUT_SYS0'
 '@BASEBOARD_FAB2_LIB.BASEBOARD_FAB2(SCH_1):FAN_PWM_OUT_SYS0':
 C_SIGNAL='@baseboard_fab2_lib.baseboard_fab2(sch_1):fan_pwm_out_sys0';
NODE_NAME     U8G2 2
 '@BASEBOARD_FAB2_LIB.BASEBOARD_FAB2(SCH_1):PAGE161_I88@MSTR_TTL.TTL1G07_A(CHIPS)':
 'A': CDS_PINID='A';
NODE_NAME     U25W4 V2
 '@BASEBOARD_FAB2_LIB.BASEBOARD_FAB2(SCH_1):PAGE147_I106@W_HDL.AST2520A1-GP-GP(CHIPS)':
 'GPION0_PWM0': CDS_PINID='GPION0_PWM0';
NET_NAME
'FAN_PWM_OUT_SYS0_BUF'
 '@BASEBOARD_FAB2_LIB.BASEBOARD_FAB2(SCH_1):FAN_PWM_OUT_SYS0_BUF':
 C_SIGNAL='@baseboard_fab2_lib.baseboard_fab2(sch_1):fan_pwm_out_sys0_buf';
NODE_NAME     U8G2 4
 '@BASEBOARD_FAB2_LIB.BASEBOARD_FAB2(SCH_1):PAGE161_I88@MSTR_TTL.TTL1G07_A(CHIPS)':
 'Y': CDS_PINID='Y';
NODE_NAME     R2U42 1
 '@BASEBOARD_FAB2_LIB.BASEBOARD_FAB2(SCH_1):PAGE161_I99@MSTR_DISCRETE.RES(CHIPS)':
 'A': CDS_PINID='A';
NET_NAME
'FAN_PWM_OUT_SYS0_R'
 '@BASEBOARD_FAB2_LIB.BASEBOARD_FAB2(SCH_1):FAN_PWM_OUT_SYS0_R':
 C_SIGNAL='@baseboard_fab2_lib.baseboard_fab2(sch_1):fan_pwm_out_sys0_r';
NODE_NAME     CR1E1 2
 '@BASEBOARD_FAB2_LIB.BASEBOARD_FAB2(SCH_1):PAGE161_I50@MSTR_DISCRETE.DIODE(CHIPS)':
 'A': CDS_PINID='A';
NODE_NAME     R1E12 2
 '@BASEBOARD_FAB2_LIB.BASEBOARD_FAB2(SCH_1):PAGE161_I51@MSTR_DISCRETE.RES(CHIPS)':
 'B': CDS_PINID='B';
NODE_NAME     R2U42 2
 '@BASEBOARD_FAB2_LIB.BASEBOARD_FAB2(SCH_1):PAGE161_I99@MSTR_DISCRETE.RES(CHIPS)':
 'B': CDS_PINID='B';
NODE_NAME     R9T1 1
 '@BASEBOARD_FAB2_LIB.BASEBOARD_FAB2(SCH_1):PAGE181_I26@MSTR_DISCRETE.RES(CHIPS)':
 'A': CDS_PINID='A';
NODE_NAME     J1F2 4
 '@BASEBOARD_FAB2_LIB.BASEBOARD_FAB2(SCH_1):PAGE161_I139@W_HDL.LOTES-CON4-S1-GP(CHIPS)':
 '4': CDS_PINID='\4\';
NET_NAME
'FAN_PWM_OUT_SYS0_R1'
 '@BASEBOARD_FAB2_LIB.BASEBOARD_FAB2(SCH_1):FAN_PWM_OUT_SYS0_R1':
 C_SIGNAL='@baseboard_fab2_lib.baseboard_fab2(sch_1):fan_pwm_out_sys0_r1';
NODE_NAME     R9T1 2
 '@BASEBOARD_FAB2_LIB.BASEBOARD_FAB2(SCH_1):PAGE181_I26@MSTR_DISCRETE.RES(CHIPS)':
 'B': CDS_PINID='B';
NODE_NAME     R1F9 2
 '@BASEBOARD_FAB2_LIB.BASEBOARD_FAB2(SCH_1):PAGE182_I7@MSTR_DISCRETE.RES(CHIPS)':
 'B': CDS_PINID='B';
NODE_NAME     J1F1 F4
 '@BASEBOARD_FAB2_LIB.BASEBOARD_FAB2(SCH_1):PAGE181_I134@W_HDL.DM-FCI-CONN76-8R-GP-U-01(CHIPS)':
 'FAN_PWM0': CDS_PINID='FAN_PWM0';
NET_NAME
'FAN_PWM_OUT_SYS1'
 '@BASEBOARD_FAB2_LIB.BASEBOARD_FAB2(SCH_1):FAN_PWM_OUT_SYS1':
 C_SIGNAL='@baseboard_fab2_lib.baseboard_fab2(sch_1):fan_pwm_out_sys1';
NODE_NAME     U8G3 2
 '@BASEBOARD_FAB2_LIB.BASEBOARD_FAB2(SCH_1):PAGE161_I92@MSTR_TTL.TTL1G07_A(CHIPS)':
 'A': CDS_PINID='A';
NODE_NAME     U25W4 W2
 '@BASEBOARD_FAB2_LIB.BASEBOARD_FAB2(SCH_1):PAGE147_I106@W_HDL.AST2520A1-GP-GP(CHIPS)':
 'GPION1_PWM1': CDS_PINID='GPION1_PWM1';
NET_NAME
'FAN_PWM_OUT_SYS1_BUF'
 '@BASEBOARD_FAB2_LIB.BASEBOARD_FAB2(SCH_1):FAN_PWM_OUT_SYS1_BUF':
 C_SIGNAL='@baseboard_fab2_lib.baseboard_fab2(sch_1):fan_pwm_out_sys1_buf';
NODE_NAME     U8G3 4
 '@BASEBOARD_FAB2_LIB.BASEBOARD_FAB2(SCH_1):PAGE161_I92@MSTR_TTL.TTL1G07_A(CHIPS)':
 'Y': CDS_PINID='Y';
NODE_NAME     R2U44 1
 '@BASEBOARD_FAB2_LIB.BASEBOARD_FAB2(SCH_1):PAGE161_I102@MSTR_DISCRETE.RES(CHIPS)':
 'A': CDS_PINID='A';
NET_NAME
'FAN_PWM_OUT_SYS1_R'
 '@BASEBOARD_FAB2_LIB.BASEBOARD_FAB2(SCH_1):FAN_PWM_OUT_SYS1_R':
 C_SIGNAL='@baseboard_fab2_lib.baseboard_fab2(sch_1):fan_pwm_out_sys1_r';
NODE_NAME     CR1B1 2
 '@BASEBOARD_FAB2_LIB.BASEBOARD_FAB2(SCH_1):PAGE161_I64@MSTR_DISCRETE.DIODE(CHIPS)':
 'A': CDS_PINID='A';
NODE_NAME     R7F33 2
 '@BASEBOARD_FAB2_LIB.BASEBOARD_FAB2(SCH_1):PAGE161_I65@MSTR_DISCRETE.RES(CHIPS)':
 'B': CDS_PINID='B';
NODE_NAME     R2U44 2
 '@BASEBOARD_FAB2_LIB.BASEBOARD_FAB2(SCH_1):PAGE161_I102@MSTR_DISCRETE.RES(CHIPS)':
 'B': CDS_PINID='B';
NODE_NAME     J10W1 4
 '@BASEBOARD_FAB2_LIB.BASEBOARD_FAB2(SCH_1):PAGE161_I140@W_HDL.LOTES-CON4-S1-GP(CHIPS)':
 '4': CDS_PINID='\4\';
NET_NAME
'FAN_TACH0'
 '@BASEBOARD_FAB2_LIB.BASEBOARD_FAB2(SCH_1):FAN_TACH0':
 C_SIGNAL='@baseboard_fab2_lib.baseboard_fab2(sch_1):fan_tach0';
NODE_NAME     R1F2 1
 '@BASEBOARD_FAB2_LIB.BASEBOARD_FAB2(SCH_1):PAGE161_I43@MSTR_DISCRETE.RES(CHIPS)':
 'A': CDS_PINID='A';
NODE_NAME     R1F1 2
 '@BASEBOARD_FAB2_LIB.BASEBOARD_FAB2(SCH_1):PAGE161_I45@MSTR_DISCRETE.RES(CHIPS)':
 'B': CDS_PINID='B';
NODE_NAME     C1F9 1
 '@BASEBOARD_FAB2_LIB.BASEBOARD_FAB2(SCH_1):PAGE161_I46@DEV_DISCRETE.CAP_A(CHIPS)':
 'A': CDS_PINID='A';
NODE_NAME     R1U5 1
 '@BASEBOARD_FAB2_LIB.BASEBOARD_FAB2(SCH_1):PAGE147_I66@MSTR_DISCRETE.RES(CHIPS)':
 'A': CDS_PINID='A';
NODE_NAME     U25W4 U5
 '@BASEBOARD_FAB2_LIB.BASEBOARD_FAB2(SCH_1):PAGE147_I106@W_HDL.AST2520A1-GP-GP(CHIPS)':
 'GPIOO0_TACH0_VPIG8': CDS_PINID='GPIOO0_TACH0_VPIG8';
NODE_NAME     R1F8 1
 '@BASEBOARD_FAB2_LIB.BASEBOARD_FAB2(SCH_1):PAGE181_I22@MSTR_DISCRETE.RES(CHIPS)':
 'A': CDS_PINID='A';
NET_NAME
'FAN_TACH0_CPU0_D1'
 '@BASEBOARD_FAB2_LIB.BASEBOARD_FAB2(SCH_1):FAN_TACH0_CPU0_D1':
 C_SIGNAL='@baseboard_fab2_lib.baseboard_fab2(sch_1):fan_tach0_cpu0_d1';
NODE_NAME     CR1F1 1
 '@BASEBOARD_FAB2_LIB.BASEBOARD_FAB2(SCH_1):PAGE161_I42@MSTR_DISCRETE.DIODE(CHIPS)':
 'C': CDS_PINID='C';
NODE_NAME     J1F2 3
 '@BASEBOARD_FAB2_LIB.BASEBOARD_FAB2(SCH_1):PAGE161_I139@W_HDL.LOTES-CON4-S1-GP(CHIPS)':
 '3': CDS_PINID='\3\';
NET_NAME
'FAN_TACH0_CPU0_D2'
 '@BASEBOARD_FAB2_LIB.BASEBOARD_FAB2(SCH_1):FAN_TACH0_CPU0_D2':
 C_SIGNAL='@baseboard_fab2_lib.baseboard_fab2(sch_1):fan_tach0_cpu0_d2';
NODE_NAME     CR1F1 2
 '@BASEBOARD_FAB2_LIB.BASEBOARD_FAB2(SCH_1):PAGE161_I42@MSTR_DISCRETE.DIODE(CHIPS)':
 'A': CDS_PINID='A';
NODE_NAME     R1F2 2
 '@BASEBOARD_FAB2_LIB.BASEBOARD_FAB2(SCH_1):PAGE161_I43@MSTR_DISCRETE.RES(CHIPS)':
 'B': CDS_PINID='B';
NET_NAME
'FAN_TACH0_R'
 '@BASEBOARD_FAB2_LIB.BASEBOARD_FAB2(SCH_1):FAN_TACH0_R':
 C_SIGNAL='@baseboard_fab2_lib.baseboard_fab2(sch_1):fan_tach0_r';
NODE_NAME     R1F8 2
 '@BASEBOARD_FAB2_LIB.BASEBOARD_FAB2(SCH_1):PAGE181_I22@MSTR_DISCRETE.RES(CHIPS)':
 'B': CDS_PINID='B';
NODE_NAME     R1C31 2
 '@BASEBOARD_FAB2_LIB.BASEBOARD_FAB2(SCH_1):PAGE182_I6@MSTR_DISCRETE.RES(CHIPS)':
 'B': CDS_PINID='B';
NODE_NAME     J1F1 D4
 '@BASEBOARD_FAB2_LIB.BASEBOARD_FAB2(SCH_1):PAGE181_I134@W_HDL.DM-FCI-CONN76-8R-GP-U-01(CHIPS)':
 'FAN_TACH0': CDS_PINID='FAN_TACH0';
NET_NAME
'FAN_TACH1'
 '@BASEBOARD_FAB2_LIB.BASEBOARD_FAB2(SCH_1):FAN_TACH1':
 C_SIGNAL='@baseboard_fab2_lib.baseboard_fab2(sch_1):fan_tach1';
NODE_NAME     R1U4 1
 '@BASEBOARD_FAB2_LIB.BASEBOARD_FAB2(SCH_1):PAGE147_I65@MSTR_DISCRETE.RES(CHIPS)':
 'A': CDS_PINID='A';
NODE_NAME     U25W4 U4
 '@BASEBOARD_FAB2_LIB.BASEBOARD_FAB2(SCH_1):PAGE147_I106@W_HDL.AST2520A1-GP-GP(CHIPS)':
 'GPIOO1_TACH1_VPIG9': CDS_PINID='GPIOO1_TACH1_VPIG9';
NODE_NAME     R9R10 1
 '@BASEBOARD_FAB2_LIB.BASEBOARD_FAB2(SCH_1):PAGE181_I31@MSTR_DISCRETE.RES(CHIPS)':
 'A': CDS_PINID='A';
NET_NAME
'FAN_TACH1_R'
 '@BASEBOARD_FAB2_LIB.BASEBOARD_FAB2(SCH_1):FAN_TACH1_R':
 C_SIGNAL='@baseboard_fab2_lib.baseboard_fab2(sch_1):fan_tach1_r';
NODE_NAME     R9R10 2
 '@BASEBOARD_FAB2_LIB.BASEBOARD_FAB2(SCH_1):PAGE181_I31@MSTR_DISCRETE.RES(CHIPS)':
 'B': CDS_PINID='B';
NODE_NAME     R1C11 2
 '@BASEBOARD_FAB2_LIB.BASEBOARD_FAB2(SCH_1):PAGE182_I10@MSTR_DISCRETE.RES(CHIPS)':
 'B': CDS_PINID='B';
NODE_NAME     J1F1 C4
 '@BASEBOARD_FAB2_LIB.BASEBOARD_FAB2(SCH_1):PAGE181_I134@W_HDL.DM-FCI-CONN76-8R-GP-U-01(CHIPS)':
 'FAN_TACH1': CDS_PINID='FAN_TACH1';
NET_NAME
'FAN_TACH2'
 '@BASEBOARD_FAB2_LIB.BASEBOARD_FAB2(SCH_1):FAN_TACH2':
 C_SIGNAL='@baseboard_fab2_lib.baseboard_fab2(sch_1):fan_tach2';
NODE_NAME     R1B22 1
 '@BASEBOARD_FAB2_LIB.BASEBOARD_FAB2(SCH_1):PAGE161_I67@MSTR_DISCRETE.RES(CHIPS)':
 'A': CDS_PINID='A';
NODE_NAME     C1B15 1
 '@BASEBOARD_FAB2_LIB.BASEBOARD_FAB2(SCH_1):PAGE161_I68@DEV_DISCRETE.CAP_A(CHIPS)':
 'A': CDS_PINID='A';
NODE_NAME     R1B21 2
 '@BASEBOARD_FAB2_LIB.BASEBOARD_FAB2(SCH_1):PAGE161_I70@MSTR_DISCRETE.RES(CHIPS)':
 'B': CDS_PINID='B';
NODE_NAME     R1U2 1
 '@BASEBOARD_FAB2_LIB.BASEBOARD_FAB2(SCH_1):PAGE147_I62@MSTR_DISCRETE.RES(CHIPS)':
 'A': CDS_PINID='A';
NODE_NAME     U25W4 V5
 '@BASEBOARD_FAB2_LIB.BASEBOARD_FAB2(SCH_1):PAGE147_I106@W_HDL.AST2520A1-GP-GP(CHIPS)':
 'GPIOO2_TACH2': CDS_PINID='GPIOO2_TACH2';
NODE_NAME     R9R12 1
 '@BASEBOARD_FAB2_LIB.BASEBOARD_FAB2(SCH_1):PAGE181_I27@MSTR_DISCRETE.RES(CHIPS)':
 'A': CDS_PINID='A';
NET_NAME
'FAN_TACH2_CPU1_D1'
 '@BASEBOARD_FAB2_LIB.BASEBOARD_FAB2(SCH_1):FAN_TACH2_CPU1_D1':
 C_SIGNAL='@baseboard_fab2_lib.baseboard_fab2(sch_1):fan_tach2_cpu1_d1';
NODE_NAME     CR1B2 1
 '@BASEBOARD_FAB2_LIB.BASEBOARD_FAB2(SCH_1):PAGE161_I62@MSTR_DISCRETE.DIODE(CHIPS)':
 'C': CDS_PINID='C';
NODE_NAME     J10W1 3
 '@BASEBOARD_FAB2_LIB.BASEBOARD_FAB2(SCH_1):PAGE161_I140@W_HDL.LOTES-CON4-S1-GP(CHIPS)':
 '3': CDS_PINID='\3\';
NET_NAME
'FAN_TACH2_CPU1_D2'
 '@BASEBOARD_FAB2_LIB.BASEBOARD_FAB2(SCH_1):FAN_TACH2_CPU1_D2':
 C_SIGNAL='@baseboard_fab2_lib.baseboard_fab2(sch_1):fan_tach2_cpu1_d2';
NODE_NAME     CR1B2 2
 '@BASEBOARD_FAB2_LIB.BASEBOARD_FAB2(SCH_1):PAGE161_I62@MSTR_DISCRETE.DIODE(CHIPS)':
 'A': CDS_PINID='A';
NODE_NAME     R1B22 2
 '@BASEBOARD_FAB2_LIB.BASEBOARD_FAB2(SCH_1):PAGE161_I67@MSTR_DISCRETE.RES(CHIPS)':
 'B': CDS_PINID='B';
NET_NAME
'FAN_TACH2_R'
 '@BASEBOARD_FAB2_LIB.BASEBOARD_FAB2(SCH_1):FAN_TACH2_R':
 C_SIGNAL='@baseboard_fab2_lib.baseboard_fab2(sch_1):fan_tach2_r';
NODE_NAME     R9R12 2
 '@BASEBOARD_FAB2_LIB.BASEBOARD_FAB2(SCH_1):PAGE181_I27@MSTR_DISCRETE.RES(CHIPS)':
 'B': CDS_PINID='B';
NODE_NAME     R1C9 2
 '@BASEBOARD_FAB2_LIB.BASEBOARD_FAB2(SCH_1):PAGE182_I8@MSTR_DISCRETE.RES(CHIPS)':
 'B': CDS_PINID='B';
NODE_NAME     J1F1 B4
 '@BASEBOARD_FAB2_LIB.BASEBOARD_FAB2(SCH_1):PAGE181_I134@W_HDL.DM-FCI-CONN76-8R-GP-U-01(CHIPS)':
 'FAN_TACH2': CDS_PINID='FAN_TACH2';
NET_NAME
'FAN_TACH3'
 '@BASEBOARD_FAB2_LIB.BASEBOARD_FAB2(SCH_1):FAN_TACH3':
 C_SIGNAL='@baseboard_fab2_lib.baseboard_fab2(sch_1):fan_tach3';
NODE_NAME     R1U1 1
 '@BASEBOARD_FAB2_LIB.BASEBOARD_FAB2(SCH_1):PAGE147_I61@MSTR_DISCRETE.RES(CHIPS)':
 'A': CDS_PINID='A';
NODE_NAME     U25W4 AB4
 '@BASEBOARD_FAB2_LIB.BASEBOARD_FAB2(SCH_1):PAGE147_I106@W_HDL.AST2520A1-GP-GP(CHIPS)':
 'GPIOO3_TACH3': CDS_PINID='GPIOO3_TACH3';
NODE_NAME     R9R9 1
 '@BASEBOARD_FAB2_LIB.BASEBOARD_FAB2(SCH_1):PAGE181_I32@MSTR_DISCRETE.RES(CHIPS)':
 'A': CDS_PINID='A';
NET_NAME
'FAN_TACH3_R'
 '@BASEBOARD_FAB2_LIB.BASEBOARD_FAB2(SCH_1):FAN_TACH3_R':
 C_SIGNAL='@baseboard_fab2_lib.baseboard_fab2(sch_1):fan_tach3_r';
NODE_NAME     R9R9 2
 '@BASEBOARD_FAB2_LIB.BASEBOARD_FAB2(SCH_1):PAGE181_I32@MSTR_DISCRETE.RES(CHIPS)':
 'B': CDS_PINID='B';
NODE_NAME     R1C10 2
 '@BASEBOARD_FAB2_LIB.BASEBOARD_FAB2(SCH_1):PAGE182_I9@MSTR_DISCRETE.RES(CHIPS)':
 'B': CDS_PINID='B';
NODE_NAME     J1F1 A4
 '@BASEBOARD_FAB2_LIB.BASEBOARD_FAB2(SCH_1):PAGE181_I134@W_HDL.DM-FCI-CONN76-8R-GP-U-01(CHIPS)':
 'FAN_TACH3': CDS_PINID='FAN_TACH3';
NET_NAME
'FM_100M_N'
 '@BASEBOARD_FAB2_LIB.BASEBOARD_FAB2(SCH_1):FM_100M_N':
 C_SIGNAL='@baseboard_fab2_lib.baseboard_fab2(sch_1):fm_100m_n';
NODE_NAME     EU4D2 4
 '@BASEBOARD_FAB2_LIB.BASEBOARD_FAB2(SCH_1):PAGE102_I1@MSTR_CLOCK.NB3W1200L(CHIPS)':
 '100M_133M_N': CDS_PINID='\100m_133m_n\';
NODE_NAME     R4D40 2
 '@BASEBOARD_FAB2_LIB.BASEBOARD_FAB2(SCH_1):PAGE102_I45@MSTR_DISCRETE.RES(CHIPS)':
 'B': CDS_PINID='B';
NODE_NAME     R6P23 1
 '@BASEBOARD_FAB2_LIB.BASEBOARD_FAB2(SCH_1):PAGE102_I46@MSTR_DISCRETE.RES(CHIPS)':
 'A': CDS_PINID='A';
NET_NAME
'FM_10GBE_LOM_DISABLE_N'
 '@BASEBOARD_FAB2_LIB.BASEBOARD_FAB2(SCH_1):FM_10GBE_LOM_DISABLE_N':
 C_SIGNAL='@baseboard_fab2_lib.baseboard_fab2(sch_1):fm_10gbe_lom_disable_n';
NODE_NAME     R8C23 2
 '@BASEBOARD_FAB2_LIB.BASEBOARD_FAB2(SCH_1):PAGE118_I125@MSTR_DISCRETE.RES(CHIPS)':
 'B': CDS_PINID='B';
NODE_NAME     U7C1 BY21
 '@BASEBOARD_FAB2_LIB.BASEBOARD_FAB2(SCH_1):PAGE120_I147@MSTR_U_PROC.LBG_CORE_QAT_EXT_D(CHIPS)':
 'GPP_I9_LAN_DIS_N': CDS_PINID='GPP_I9_LAN_DIS_N';
NET_NAME
'FM_156M_CPU0_BRD_OSC_EN'
 '@BASEBOARD_FAB2_LIB.BASEBOARD_FAB2(SCH_1):FM_156M_CPU0_BRD_OSC_EN':
 C_SIGNAL='@baseboard_fab2_lib.baseboard_fab2(sch_1):fm_156m_cpu0_brd_osc_en';
NODE_NAME     R8D43 1
 '@BASEBOARD_FAB2_LIB.BASEBOARD_FAB2(SCH_1):PAGE104_I93@MSTR_DISCRETE.RES(CHIPS)':
 'A': CDS_PINID='A';
NODE_NAME     U8D7 T10
 '@BASEBOARD_FAB2_LIB.BASEBOARD_FAB2(SCH_1):PAGE190_I179@MSTR_MEMORY.LCMXO2_A(CHIPS)':
 'PB18B': CDS_PINID='PB18B';
NET_NAME
'FM_156M_CPU1_BRD_OSC_EN'
 '@BASEBOARD_FAB2_LIB.BASEBOARD_FAB2(SCH_1):FM_156M_CPU1_BRD_OSC_EN':
 C_SIGNAL='@baseboard_fab2_lib.baseboard_fab2(sch_1):fm_156m_cpu1_brd_osc_en';
NODE_NAME     R7D36 1
 '@BASEBOARD_FAB2_LIB.BASEBOARD_FAB2(SCH_1):PAGE104_I96@MSTR_DISCRETE.RES(CHIPS)':
 'A': CDS_PINID='A';
NODE_NAME     U8D7 N8
 '@BASEBOARD_FAB2_LIB.BASEBOARD_FAB2(SCH_1):PAGE190_I179@MSTR_MEMORY.LCMXO2_A(CHIPS)':
 'PB12C': CDS_PINID='PB12C';
NET_NAME
'FM_1GB_LOM_DISABLE_N'
 '@BASEBOARD_FAB2_LIB.BASEBOARD_FAB2(SCH_1):FM_1GB_LOM_DISABLE_N':
 C_SIGNAL='@baseboard_fab2_lib.baseboard_fab2(sch_1):fm_1gb_lom_disable_n';
NODE_NAME     R8C24 2
 '@BASEBOARD_FAB2_LIB.BASEBOARD_FAB2(SCH_1):PAGE118_I120@MSTR_DISCRETE.RES(CHIPS)':
 'B': CDS_PINID='B';
NODE_NAME     EU9E1 61
 '@BASEBOARD_FAB2_LIB.BASEBOARD_FAB2(SCH_1):PAGE139_I72@MSTR_INTEL.SPRINGVILLE(CHIPS)':
 'SDP1_PCIE_DIS_SDP1': CDS_PINID='SDP1_PCIE_DIS_SDP1';
NET_NAME
'FM_ADR_COMPLETE'
 '@BASEBOARD_FAB2_LIB.BASEBOARD_FAB2(SCH_1):FM_ADR_COMPLETE':
 C_SIGNAL='@baseboard_fab2_lib.baseboard_fab2(sch_1):fm_adr_complete';
NODE_NAME     R4T2 1
 '@BASEBOARD_FAB2_LIB.BASEBOARD_FAB2(SCH_1):PAGE89_I1@MSTR_DISCRETE.RES(CHIPS)':
 'A': CDS_PINID='A';
NODE_NAME     R2N26 1
 '@BASEBOARD_FAB2_LIB.BASEBOARD_FAB2(SCH_1):PAGE120_I219@MSTR_DISCRETE.RES(CHIPS)':
 'A': CDS_PINID='A';
NODE_NAME     U8D7 C8
 '@BASEBOARD_FAB2_LIB.BASEBOARD_FAB2(SCH_1):PAGE191_I59@MSTR_MEMORY.LCMXO2_A(CHIPS)':
 'PT17A_PCLKT0_1': CDS_PINID='PT17A_PCLKT0_1';
NET_NAME
'FM_ADR_COMPLETE_ABC_N'
 '@BASEBOARD_FAB2_LIB.BASEBOARD_FAB2(SCH_1):FM_ADR_COMPLETE_ABC_N':
 C_SIGNAL='@baseboard_fab2_lib.baseboard_fab2(sch_1):fm_adr_complete_abc_n';
NODE_NAME     J4G1 230
 '@BASEBOARD_FAB2_LIB.BASEBOARD_FAB2(SCH_1):PAGE43_I1@MSTR_SCONN.SCONN288_H44441004(CHIPS)':
 'SAVE_N_NC': CDS_PINID='SAVE_N_NC';
NODE_NAME     J6T1 230
 '@BASEBOARD_FAB2_LIB.BASEBOARD_FAB2(SCH_1):PAGE44_I13@MSTR_SCONN.SCONN288_H44441003(CHIPS)':
 'SAVE_N_NC': CDS_PINID='SAVE_N_NC';
NODE_NAME     J4G2 230
 '@BASEBOARD_FAB2_LIB.BASEBOARD_FAB2(SCH_1):PAGE45_I111@MSTR_SCONN.SCONN288_H44441004(CHIPS)':
 'SAVE_N_NC': CDS_PINID='SAVE_N_NC';
NODE_NAME     J6U1 230
 '@BASEBOARD_FAB2_LIB.BASEBOARD_FAB2(SCH_1):PAGE46_I14@MSTR_SCONN.SCONN288_H44441003(CHIPS)':
 'SAVE_N_NC': CDS_PINID='SAVE_N_NC';
NODE_NAME     J4G3 230
 '@BASEBOARD_FAB2_LIB.BASEBOARD_FAB2(SCH_1):PAGE47_I111@MSTR_SCONN.SCONN288_H44441004(CHIPS)':
 'SAVE_N_NC': CDS_PINID='SAVE_N_NC';
NODE_NAME     J6U2 230
 '@BASEBOARD_FAB2_LIB.BASEBOARD_FAB2(SCH_1):PAGE48_I111@MSTR_SCONN.SCONN288_H44441003(CHIPS)':
 'SAVE_N_NC': CDS_PINID='SAVE_N_NC';
NODE_NAME     R6F4 2
 '@BASEBOARD_FAB2_LIB.BASEBOARD_FAB2(SCH_1):PAGE89_I3@MSTR_DISCRETE.RES(CHIPS)':
 'B': CDS_PINID='B';
NET_NAME
'FM_ADR_COMPLETE_CPU0_R'
 '@BASEBOARD_FAB2_LIB.BASEBOARD_FAB2(SCH_1):FM_ADR_COMPLETE_CPU0_R':
 C_SIGNAL='@baseboard_fab2_lib.baseboard_fab2(sch_1):fm_adr_complete_cpu0_r';
NODE_NAME     Q1F1 1
 '@BASEBOARD_FAB2_LIB.BASEBOARD_FAB2(SCH_1):PAGE89_I53@MSTR_DISCRETE.NPN(CHIPS)':
 'B': CDS_PINID='B';
NODE_NAME     R1W32 2
 '@BASEBOARD_FAB2_LIB.BASEBOARD_FAB2(SCH_1):PAGE89_I54@MSTR_DISCRETE.RES(CHIPS)':
 'B': CDS_PINID='B';
NET_NAME
'FM_ADR_COMPLETE_CPU1_N'
 '@BASEBOARD_FAB2_LIB.BASEBOARD_FAB2(SCH_1):FM_ADR_COMPLETE_CPU1_N':
 C_SIGNAL='@baseboard_fab2_lib.baseboard_fab2(sch_1):fm_adr_complete_cpu1_n';
NODE_NAME     R6F5 1
 '@BASEBOARD_FAB2_LIB.BASEBOARD_FAB2(SCH_1):PAGE89_I5@MSTR_DISCRETE.RES(CHIPS)':
 'A': CDS_PINID='A';
NODE_NAME     R6F2 1
 '@BASEBOARD_FAB2_LIB.BASEBOARD_FAB2(SCH_1):PAGE89_I6@MSTR_DISCRETE.RES(CHIPS)':
 'A': CDS_PINID='A';
NODE_NAME     R6W29 2
 '@BASEBOARD_FAB2_LIB.BASEBOARD_FAB2(SCH_1):PAGE89_I40@MSTR_DISCRETE.RES(CHIPS)':
 'B': CDS_PINID='B';
NODE_NAME     WR8D30 1
 '@BASEBOARD_FAB2_LIB.BASEBOARD_FAB2(SCH_1):PAGE89_I45@MSTR_DISCRETE.RES(CHIPS)':
 'A': CDS_PINID='A';
NODE_NAME     Q1W6 3
 '@BASEBOARD_FAB2_LIB.BASEBOARD_FAB2(SCH_1):PAGE89_I55@MSTR_DISCRETE.NPN(CHIPS)':
 'C': CDS_PINID='C';
NET_NAME
'FM_ADR_COMPLETE_CPU1_R'
 '@BASEBOARD_FAB2_LIB.BASEBOARD_FAB2(SCH_1):FM_ADR_COMPLETE_CPU1_R':
 C_SIGNAL='@baseboard_fab2_lib.baseboard_fab2(sch_1):fm_adr_complete_cpu1_r';
NODE_NAME     Q1W6 1
 '@BASEBOARD_FAB2_LIB.BASEBOARD_FAB2(SCH_1):PAGE89_I55@MSTR_DISCRETE.NPN(CHIPS)':
 'B': CDS_PINID='B';
NODE_NAME     R1W31 2
 '@BASEBOARD_FAB2_LIB.BASEBOARD_FAB2(SCH_1):PAGE89_I56@MSTR_DISCRETE.RES(CHIPS)':
 'B': CDS_PINID='B';
NET_NAME
'FM_ADR_COMPLETE_DEF_N'
 '@BASEBOARD_FAB2_LIB.BASEBOARD_FAB2(SCH_1):FM_ADR_COMPLETE_DEF_N':
 C_SIGNAL='@baseboard_fab2_lib.baseboard_fab2(sch_1):fm_adr_complete_def_n';
NODE_NAME     J4B1 230
 '@BASEBOARD_FAB2_LIB.BASEBOARD_FAB2(SCH_1):PAGE49_I111@MSTR_SCONN.SCONN288_H44441004(CHIPS)':
 'SAVE_N_NC': CDS_PINID='SAVE_N_NC';
NODE_NAME     J6M1 230
 '@BASEBOARD_FAB2_LIB.BASEBOARD_FAB2(SCH_1):PAGE50_I158@MSTR_SCONN.SCONN288_H44441003(CHIPS)':
 'SAVE_N_NC': CDS_PINID='SAVE_N_NC';
NODE_NAME     J4A2 230
 '@BASEBOARD_FAB2_LIB.BASEBOARD_FAB2(SCH_1):PAGE51_I111@MSTR_SCONN.SCONN288_H44441004(CHIPS)':
 'SAVE_N_NC': CDS_PINID='SAVE_N_NC';
NODE_NAME     J6L2 230
 '@BASEBOARD_FAB2_LIB.BASEBOARD_FAB2(SCH_1):PAGE52_I12@MSTR_SCONN.SCONN288_H44441003(CHIPS)':
 'SAVE_N_NC': CDS_PINID='SAVE_N_NC';
NODE_NAME     J4A1 230
 '@BASEBOARD_FAB2_LIB.BASEBOARD_FAB2(SCH_1):PAGE53_I111@MSTR_SCONN.SCONN288_H44441004(CHIPS)':
 'SAVE_N_NC': CDS_PINID='SAVE_N_NC';
NODE_NAME     J6L1 230
 '@BASEBOARD_FAB2_LIB.BASEBOARD_FAB2(SCH_1):PAGE54_I111@MSTR_SCONN.SCONN288_H44441003(CHIPS)':
 'SAVE_N_NC': CDS_PINID='SAVE_N_NC';
NODE_NAME     R6F1 2
 '@BASEBOARD_FAB2_LIB.BASEBOARD_FAB2(SCH_1):PAGE89_I4@MSTR_DISCRETE.RES(CHIPS)':
 'B': CDS_PINID='B';
NET_NAME
'FM_ADR_COMPLETE_DLY'
 '@BASEBOARD_FAB2_LIB.BASEBOARD_FAB2(SCH_1):FM_ADR_COMPLETE_DLY':
 C_SIGNAL='@baseboard_fab2_lib.baseboard_fab2(sch_1):fm_adr_complete_dly';
NODE_NAME     R4T1 1
 '@BASEBOARD_FAB2_LIB.BASEBOARD_FAB2(SCH_1):PAGE89_I2@MSTR_DISCRETE.RES(CHIPS)':
 'A': CDS_PINID='A';
NODE_NAME     U8D7 B16
 '@BASEBOARD_FAB2_LIB.BASEBOARD_FAB2(SCH_1):PAGE191_I59@MSTR_MEMORY.LCMXO2_A(CHIPS)':
 'PR1D': CDS_PINID='PR1D';
NET_NAME
'FM_ADR_COMPLETE_GHJ_N'
 '@BASEBOARD_FAB2_LIB.BASEBOARD_FAB2(SCH_1):FM_ADR_COMPLETE_GHJ_N':
 C_SIGNAL='@baseboard_fab2_lib.baseboard_fab2(sch_1):fm_adr_complete_ghj_n';
NODE_NAME     J1G1 230
 '@BASEBOARD_FAB2_LIB.BASEBOARD_FAB2(SCH_1):PAGE77_I111@MSTR_SCONN.SCONN288_H44441004(CHIPS)':
 'SAVE_N_NC': CDS_PINID='SAVE_N_NC';
NODE_NAME     J9T1 230
 '@BASEBOARD_FAB2_LIB.BASEBOARD_FAB2(SCH_1):PAGE78_I13@MSTR_SCONN.SCONN288_H44441003(CHIPS)':
 'SAVE_N_NC': CDS_PINID='SAVE_N_NC';
NODE_NAME     J1G2 230
 '@BASEBOARD_FAB2_LIB.BASEBOARD_FAB2(SCH_1):PAGE79_I111@MSTR_SCONN.SCONN288_H44441004(CHIPS)':
 'SAVE_N_NC': CDS_PINID='SAVE_N_NC';
NODE_NAME     J9U1 230
 '@BASEBOARD_FAB2_LIB.BASEBOARD_FAB2(SCH_1):PAGE80_I24@MSTR_SCONN.SCONN288_H44441003(CHIPS)':
 'SAVE_N_NC': CDS_PINID='SAVE_N_NC';
NODE_NAME     J1G3 230
 '@BASEBOARD_FAB2_LIB.BASEBOARD_FAB2(SCH_1):PAGE81_I186@MSTR_SCONN.SCONN288_H44441004(CHIPS)':
 'SAVE_N_NC': CDS_PINID='SAVE_N_NC';
NODE_NAME     J9U2 230
 '@BASEBOARD_FAB2_LIB.BASEBOARD_FAB2(SCH_1):PAGE82_I187@MSTR_SCONN.SCONN288_H44441003(CHIPS)':
 'SAVE_N_NC': CDS_PINID='SAVE_N_NC';
NODE_NAME     R6F5 2
 '@BASEBOARD_FAB2_LIB.BASEBOARD_FAB2(SCH_1):PAGE89_I5@MSTR_DISCRETE.RES(CHIPS)':
 'B': CDS_PINID='B';
NET_NAME
'FM_ADR_COMPLETE_KLM_N'
 '@BASEBOARD_FAB2_LIB.BASEBOARD_FAB2(SCH_1):FM_ADR_COMPLETE_KLM_N':
 C_SIGNAL='@baseboard_fab2_lib.baseboard_fab2(sch_1):fm_adr_complete_klm_n';
NODE_NAME     J1B1 230
 '@BASEBOARD_FAB2_LIB.BASEBOARD_FAB2(SCH_1):PAGE83_I111@MSTR_SCONN.SCONN288_H44441004(CHIPS)':
 'SAVE_N_NC': CDS_PINID='SAVE_N_NC';
NODE_NAME     J9M1 230
 '@BASEBOARD_FAB2_LIB.BASEBOARD_FAB2(SCH_1):PAGE84_I14@MSTR_SCONN.SCONN288_H44441003(CHIPS)':
 'SAVE_N_NC': CDS_PINID='SAVE_N_NC';
NODE_NAME     J1A2 230
 '@BASEBOARD_FAB2_LIB.BASEBOARD_FAB2(SCH_1):PAGE85_I111@MSTR_SCONN.SCONN288_H44441004(CHIPS)':
 'SAVE_N_NC': CDS_PINID='SAVE_N_NC';
NODE_NAME     J9L2 230
 '@BASEBOARD_FAB2_LIB.BASEBOARD_FAB2(SCH_1):PAGE86_I12@MSTR_SCONN.SCONN288_H44441003(CHIPS)':
 'SAVE_N_NC': CDS_PINID='SAVE_N_NC';
NODE_NAME     J1A1 230
 '@BASEBOARD_FAB2_LIB.BASEBOARD_FAB2(SCH_1):PAGE87_I186@MSTR_SCONN.SCONN288_H44441004(CHIPS)':
 'SAVE_N_NC': CDS_PINID='SAVE_N_NC';
NODE_NAME     J9L1 230
 '@BASEBOARD_FAB2_LIB.BASEBOARD_FAB2(SCH_1):PAGE88_I111@MSTR_SCONN.SCONN288_H44441003(CHIPS)':
 'SAVE_N_NC': CDS_PINID='SAVE_N_NC';
NODE_NAME     R6F2 2
 '@BASEBOARD_FAB2_LIB.BASEBOARD_FAB2(SCH_1):PAGE89_I6@MSTR_DISCRETE.RES(CHIPS)':
 'B': CDS_PINID='B';
NET_NAME
'FM_ADR_COMPLETE_R'
 '@BASEBOARD_FAB2_LIB.BASEBOARD_FAB2(SCH_1):FM_ADR_COMPLETE_R':
 C_SIGNAL='@baseboard_fab2_lib.baseboard_fab2(sch_1):fm_adr_complete_r';
NODE_NAME     R4T2 2
 '@BASEBOARD_FAB2_LIB.BASEBOARD_FAB2(SCH_1):PAGE89_I1@MSTR_DISCRETE.RES(CHIPS)':
 'B': CDS_PINID='B';
NODE_NAME     R4T1 2
 '@BASEBOARD_FAB2_LIB.BASEBOARD_FAB2(SCH_1):PAGE89_I2@MSTR_DISCRETE.RES(CHIPS)':
 'B': CDS_PINID='B';
NODE_NAME     R1W32 1
 '@BASEBOARD_FAB2_LIB.BASEBOARD_FAB2(SCH_1):PAGE89_I54@MSTR_DISCRETE.RES(CHIPS)':
 'A': CDS_PINID='A';
NODE_NAME     R1W31 1
 '@BASEBOARD_FAB2_LIB.BASEBOARD_FAB2(SCH_1):PAGE89_I56@MSTR_DISCRETE.RES(CHIPS)':
 'A': CDS_PINID='A';
NET_NAME
'FM_ADR_COMPLETE_R1'
 '@BASEBOARD_FAB2_LIB.BASEBOARD_FAB2(SCH_1):FM_ADR_COMPLETE_R1':
 C_SIGNAL='@baseboard_fab2_lib.baseboard_fab2(sch_1):fm_adr_complete_r1';
NODE_NAME     U7C1 BD9
 '@BASEBOARD_FAB2_LIB.BASEBOARD_FAB2(SCH_1):PAGE120_I147@MSTR_U_PROC.LBG_CORE_QAT_EXT_D(CHIPS)':
 'GPP_G17_ADR_COMPLETE': CDS_PINID='GPP_G17_ADR_COMPLETE';
NODE_NAME     R2N26 2
 '@BASEBOARD_FAB2_LIB.BASEBOARD_FAB2(SCH_1):PAGE120_I219@MSTR_DISCRETE.RES(CHIPS)':
 'B': CDS_PINID='B';
NET_NAME
'FM_ADR_MODE_SEL'
 '@BASEBOARD_FAB2_LIB.BASEBOARD_FAB2(SCH_1):FM_ADR_MODE_SEL':
 C_SIGNAL='@baseboard_fab2_lib.baseboard_fab2(sch_1):fm_adr_mode_sel';
NODE_NAME     R2M7 2
 '@BASEBOARD_FAB2_LIB.BASEBOARD_FAB2(SCH_1):PAGE119_I174@MSTR_DISCRETE.RES(CHIPS)':
 'B': CDS_PINID='B';
NODE_NAME     U8D7 T2
 '@BASEBOARD_FAB2_LIB.BASEBOARD_FAB2(SCH_1):PAGE190_I179@MSTR_MEMORY.LCMXO2_A(CHIPS)':
 'PB3C': CDS_PINID='PB3C';
NET_NAME
'FM_ADR_MODE_SEL_R'
 '@BASEBOARD_FAB2_LIB.BASEBOARD_FAB2(SCH_1):FM_ADR_MODE_SEL_R':
 C_SIGNAL='@baseboard_fab2_lib.baseboard_fab2(sch_1):fm_adr_mode_sel_r';
NODE_NAME     U7C1 CA43
 '@BASEBOARD_FAB2_LIB.BASEBOARD_FAB2(SCH_1):PAGE119_I115@MSTR_U_PROC.LBG_CORE_QAT_EXT_D(CHIPS)':
 'GPP_D19': CDS_PINID='GPP_D19';
NODE_NAME     R2M7 1
 '@BASEBOARD_FAB2_LIB.BASEBOARD_FAB2(SCH_1):PAGE119_I174@MSTR_DISCRETE.RES(CHIPS)':
 'A': CDS_PINID='A';
NET_NAME
'FM_ADR_SMI_GPIO_N'
 '@BASEBOARD_FAB2_LIB.BASEBOARD_FAB2(SCH_1):FM_ADR_SMI_GPIO_N':
 C_SIGNAL='@baseboard_fab2_lib.baseboard_fab2(sch_1):fm_adr_smi_gpio_n';
NODE_NAME     R2P12 2
 '@BASEBOARD_FAB2_LIB.BASEBOARD_FAB2(SCH_1):PAGE89_I23@MSTR_DISCRETE.RES(CHIPS)':
 'B': CDS_PINID='B';
NODE_NAME     U7C1 BJ48
 '@BASEBOARD_FAB2_LIB.BASEBOARD_FAB2(SCH_1):PAGE120_I147@MSTR_U_PROC.LBG_CORE_QAT_EXT_D(CHIPS)':
 'GPP_E7_CPU_GP1': CDS_PINID='GPP_E7_CPU_GP1';
NODE_NAME     R8E11 2
 '@BASEBOARD_FAB2_LIB.BASEBOARD_FAB2(SCH_1):PAGE156_I279@MSTR_DISCRETE.RES(CHIPS)':
 'B': CDS_PINID='B';
NODE_NAME     R2M2 2
 '@BASEBOARD_FAB2_LIB.BASEBOARD_FAB2(SCH_1):PAGE157_I346@MSTR_DISCRETE.RES(CHIPS)':
 'B': CDS_PINID='B';
NODE_NAME     R2R4 2
 '@BASEBOARD_FAB2_LIB.BASEBOARD_FAB2(SCH_1):PAGE191_I184@MSTR_DISCRETE.RES(CHIPS)':
 'B': CDS_PINID='B';
NET_NAME
'FM_ADR_SMI_GPIO_R_N'
 '@BASEBOARD_FAB2_LIB.BASEBOARD_FAB2(SCH_1):FM_ADR_SMI_GPIO_R_N':
 C_SIGNAL='@baseboard_fab2_lib.baseboard_fab2(sch_1):fm_adr_smi_gpio_r_n';
NODE_NAME     U8D7 C4
 '@BASEBOARD_FAB2_LIB.BASEBOARD_FAB2(SCH_1):PAGE191_I59@MSTR_MEMORY.LCMXO2_A(CHIPS)':
 'PT9A': CDS_PINID='PT9A';
NODE_NAME     R2R4 1
 '@BASEBOARD_FAB2_LIB.BASEBOARD_FAB2(SCH_1):PAGE191_I184@MSTR_DISCRETE.RES(CHIPS)':
 'A': CDS_PINID='A';
NET_NAME
'FM_ALL_WAKE_N'
 '@BASEBOARD_FAB2_LIB.BASEBOARD_FAB2(SCH_1):FM_ALL_WAKE_N':
 C_SIGNAL='@baseboard_fab2_lib.baseboard_fab2(sch_1):fm_all_wake_n';
NODE_NAME     U8E4 2
 '@BASEBOARD_FAB2_LIB.BASEBOARD_FAB2(SCH_1):PAGE142_I1@MSTR_TTL.TTL1G126_A(CHIPS)':
 'A': CDS_PINID='A';
NODE_NAME     R8E29 2
 '@BASEBOARD_FAB2_LIB.BASEBOARD_FAB2(SCH_1):PAGE142_I18@MSTR_DISCRETE.RES(CHIPS)':
 'B': CDS_PINID='B';
NODE_NAME     R8E26 2
 '@BASEBOARD_FAB2_LIB.BASEBOARD_FAB2(SCH_1):PAGE142_I30@MSTR_DISCRETE.RES(CHIPS)':
 'B': CDS_PINID='B';
NODE_NAME     R8E28 2
 '@BASEBOARD_FAB2_LIB.BASEBOARD_FAB2(SCH_1):PAGE142_I31@MSTR_DISCRETE.RES(CHIPS)':
 'B': CDS_PINID='B';
NODE_NAME     R8E27 2
 '@BASEBOARD_FAB2_LIB.BASEBOARD_FAB2(SCH_1):PAGE142_I32@MSTR_DISCRETE.RES(CHIPS)':
 'B': CDS_PINID='B';
NODE_NAME     R8E21 2
 '@BASEBOARD_FAB2_LIB.BASEBOARD_FAB2(SCH_1):PAGE142_I33@MSTR_DISCRETE.RES(CHIPS)':
 'B': CDS_PINID='B';
NODE_NAME     R8E30 2
 '@BASEBOARD_FAB2_LIB.BASEBOARD_FAB2(SCH_1):PAGE142_I35@W_HDL.2K15R2F-1-GP(CHIPS)':
 '2': CDS_PINID='\2\';
NET_NAME
'FM_BACKUP_BIOS_SEL_N'
 '@BASEBOARD_FAB2_LIB.BASEBOARD_FAB2(SCH_1):FM_BACKUP_BIOS_SEL_N':
 C_SIGNAL='@baseboard_fab2_lib.baseboard_fab2(sch_1):fm_backup_bios_sel_n';
NODE_NAME     U7C1 AW4
 '@BASEBOARD_FAB2_LIB.BASEBOARD_FAB2(SCH_1):PAGE120_I147@MSTR_U_PROC.LBG_CORE_QAT_EXT_D(CHIPS)':
 'GPP_H1_SRCCLKREQ7_N': CDS_PINID='GPP_H1_SRCCLKREQ7_N';
NODE_NAME     U2T2 1
 '@BASEBOARD_FAB2_LIB.BASEBOARD_FAB2(SCH_1):PAGE154_I100@MSTR_TTL.TTL1G32_A(CHIPS)':
 'A': CDS_PINID='A';
NODE_NAME     Q8F1 1
 '@BASEBOARD_FAB2_LIB.BASEBOARD_FAB2(SCH_1):PAGE154_I126@MSTR_DISCRETE.FET_N(CHIPS)':
 'GATE': CDS_PINID='GATE';
NODE_NAME     R2T6 2
 '@BASEBOARD_FAB2_LIB.BASEBOARD_FAB2(SCH_1):PAGE154_I127@MSTR_DISCRETE.RES(CHIPS)':
 'B': CDS_PINID='B';
NODE_NAME     U25W4 W3
 '@BASEBOARD_FAB2_LIB.BASEBOARD_FAB2(SCH_1):PAGE147_I106@W_HDL.AST2520A1-GP-GP(CHIPS)':
 'GPION4_PWM4_VPIG4': CDS_PINID='GPION4_PWM4_VPIG4';
NET_NAME
'FM_BATTERY_SENSE_EN'
 '@BASEBOARD_FAB2_LIB.BASEBOARD_FAB2(SCH_1):FM_BATTERY_SENSE_EN':
 C_SIGNAL='@baseboard_fab2_lib.baseboard_fab2(sch_1):fm_battery_sense_en';
NODE_NAME     Q9G1 5
 '@BASEBOARD_FAB2_LIB.BASEBOARD_FAB2(SCH_1):PAGE169_I157@MSTR_DISCRETE.FET_N_DUAL(CHIPS)':
 'GATE'<0>: CDS_PINID='GATE(0)';
NODE_NAME     Q9G1 6
 '@BASEBOARD_FAB2_LIB.BASEBOARD_FAB2(SCH_1):PAGE169_I162@MSTR_DISCRETE.FET_N_DUAL(CHIPS)':
 'DRAIN'<0>: CDS_PINID='DRAIN(0)';
NODE_NAME     R1U49 2
 '@BASEBOARD_FAB2_LIB.BASEBOARD_FAB2(SCH_1):PAGE169_I163@MSTR_DISCRETE.RES(CHIPS)':
 'B': CDS_PINID='B';
NET_NAME
'FM_BATTERY_SENSE_EN_N'
 '@BASEBOARD_FAB2_LIB.BASEBOARD_FAB2(SCH_1):FM_BATTERY_SENSE_EN_N':
 C_SIGNAL='@baseboard_fab2_lib.baseboard_fab2(sch_1):fm_battery_sense_en_n';
NODE_NAME     Q9G1 2
 '@BASEBOARD_FAB2_LIB.BASEBOARD_FAB2(SCH_1):PAGE169_I162@MSTR_DISCRETE.FET_N_DUAL(CHIPS)':
 'GATE'<0>: CDS_PINID='GATE(0)';
NODE_NAME     R9G35 2
 '@BASEBOARD_FAB2_LIB.BASEBOARD_FAB2(SCH_1):PAGE169_I164@MSTR_DISCRETE.RES(CHIPS)':
 'B': CDS_PINID='B';
NODE_NAME     U25W4 G17
 '@BASEBOARD_FAB2_LIB.BASEBOARD_FAB2(SCH_1):PAGE145_I117@W_HDL.AST2520A1-GP-GP(CHIPS)':
 'GPIOF6_TXD4_LHSIRQ#': CDS_PINID='\gpiof6_txd4_lhsirq#\';
NODE_NAME     R7W6 1
 '@BASEBOARD_FAB2_LIB.BASEBOARD_FAB2(SCH_1):PAGE118_I176@MSTR_DISCRETE.RES(CHIPS)':
 'A': CDS_PINID='A';
NET_NAME
'FM_BATTERY_SENSE_EN_R_N'
 '@BASEBOARD_FAB2_LIB.BASEBOARD_FAB2(SCH_1):FM_BATTERY_SENSE_EN_R_N':
 C_SIGNAL='@baseboard_fab2_lib.baseboard_fab2(sch_1):fm_battery_sense_en_r_n';
NODE_NAME     U7C1 H9
 '@BASEBOARD_FAB2_LIB.BASEBOARD_FAB2(SCH_1):PAGE118_I73@MSTR_U_PROC.LBG_CORE_QAT_EXT_D(CHIPS)':
 'GPD7': CDS_PINID='GPD7';
NODE_NAME     R7W6 2
 '@BASEBOARD_FAB2_LIB.BASEBOARD_FAB2(SCH_1):PAGE118_I176@MSTR_DISCRETE.RES(CHIPS)':
 'B': CDS_PINID='B';
NODE_NAME     R7W19 2
 '@BASEBOARD_FAB2_LIB.BASEBOARD_FAB2(SCH_1):PAGE118_I180@MSTR_DISCRETE.RES(CHIPS)':
 'B': CDS_PINID='B';
NET_NAME
'FM_BB_BMC_MP_GPIO'
 '@BASEBOARD_FAB2_LIB.BASEBOARD_FAB2(SCH_1):FM_BB_BMC_MP_GPIO':
 C_SIGNAL='@baseboard_fab2_lib.baseboard_fab2(sch_1):fm_bb_bmc_mp_gpio';
NODE_NAME     U7C1 BW39
 '@BASEBOARD_FAB2_LIB.BASEBOARD_FAB2(SCH_1):PAGE119_I115@MSTR_U_PROC.LBG_CORE_QAT_EXT_D(CHIPS)':
 'GPP_C19': CDS_PINID='GPP_C19';
NODE_NAME     U25W4 C13
 '@BASEBOARD_FAB2_LIB.BASEBOARD_FAB2(SCH_1):PAGE147_I106@W_HDL.AST2520A1-GP-GP(CHIPS)':
 'GPIOA6_TIMER7_MDC2': CDS_PINID='GPIOA6_TIMER7_MDC2';
NODE_NAME     J1C1 C4
 '@BASEBOARD_FAB2_LIB.BASEBOARD_FAB2(SCH_1):PAGE182_I79@W_HDL.DM-FCI-CONN76-8R-GP-U-01(CHIPS)':
 'FAN_TACH1': CDS_PINID='FAN_TACH1';
NET_NAME
'FM_BEEP_LED_P'
 '@BASEBOARD_FAB2_LIB.BASEBOARD_FAB2(SCH_1):FM_BEEP_LED_P':
 C_SIGNAL='@baseboard_fab2_lib.baseboard_fab2(sch_1):fm_beep_led_p';
NODE_NAME     R1L33 1
 '@BASEBOARD_FAB2_LIB.BASEBOARD_FAB2(SCH_1):PAGE175_I45@MSTR_DISCRETE.RES(CHIPS)':
 'A': CDS_PINID='A';
NODE_NAME     DS9A3 2
 '@BASEBOARD_FAB2_LIB.BASEBOARD_FAB2(SCH_1):PAGE175_I67@MSTR_DISCRETE.LED(CHIPS)':
 'A': CDS_PINID='A';
NET_NAME
'FM_BIOS_MRC_DEBUG_MSG_DIS_N'
 '@BASEBOARD_FAB2_LIB.BASEBOARD_FAB2(SCH_1):FM_BIOS_MRC_DEBUG_MSG_DIS_N':
 C_SIGNAL='@baseboard_fab2_lib.baseboard_fab2(sch_1):fm_bios_mrc_debug_msg_dis_n~
',
 PHYS_NET_NAME='FM_BIOS_MRC_DEBUG_MSG_DIS_N';
NODE_NAME     U7C1 BV25
 '@BASEBOARD_FAB2_LIB.BASEBOARD_FAB2(SCH_1):PAGE120_I147@MSTR_U_PROC.LBG_CORE_QAT_EXT_D(CHIPS)':
 'GPP_I10': CDS_PINID='GPP_I10';
NODE_NAME     U25W4 F19
 '@BASEBOARD_FAB2_LIB.BASEBOARD_FAB2(SCH_1):PAGE145_I117@W_HDL.AST2520A1-GP-GP(CHIPS)':
 'GPIOD0_SD2CLK': CDS_PINID='GPIOD0_SD2CLK';
NET_NAME
'FM_BIOS_POST_CMPLT_N'
 '@BASEBOARD_FAB2_LIB.BASEBOARD_FAB2(SCH_1):FM_BIOS_POST_CMPLT_N':
 C_SIGNAL='@baseboard_fab2_lib.baseboard_fab2(sch_1):fm_bios_post_cmplt_n';
NODE_NAME     U7C1 BJ22
 '@BASEBOARD_FAB2_LIB.BASEBOARD_FAB2(SCH_1):PAGE119_I115@MSTR_U_PROC.LBG_CORE_QAT_EXT_D(CHIPS)':
 'GPP_B20': CDS_PINID='GPP_B20';
NODE_NAME     U7C1 BY33
 '@BASEBOARD_FAB2_LIB.BASEBOARD_FAB2(SCH_1):PAGE119_I115@MSTR_U_PROC.LBG_CORE_QAT_EXT_D(CHIPS)':
 'GPP_C21': CDS_PINID='GPP_C21';
NODE_NAME     R8C6 2
 '@BASEBOARD_FAB2_LIB.BASEBOARD_FAB2(SCH_1):PAGE133_I303@MSTR_DISCRETE.RES(CHIPS)':
 'B': CDS_PINID='B';
NODE_NAME     U25W4 P19
 '@BASEBOARD_FAB2_LIB.BASEBOARD_FAB2(SCH_1):PAGE146_I104@W_HDL.AST2520A1-GP-GP(CHIPS)':
 'GPIOAA7_VPOR9_NORD7_SALT14': CDS_PINID='GPIOAA7_VPOR9_NORD7_SALT14';
NET_NAME
'FM_BIOS_PREFRB2_GOOD'
 '@BASEBOARD_FAB2_LIB.BASEBOARD_FAB2(SCH_1):FM_BIOS_PREFRB2_GOOD':
 C_SIGNAL='@baseboard_fab2_lib.baseboard_fab2(sch_1):fm_bios_prefrb2_good';
NODE_NAME     U7C1 BK20
 '@BASEBOARD_FAB2_LIB.BASEBOARD_FAB2(SCH_1):PAGE119_I115@MSTR_U_PROC.LBG_CORE_QAT_EXT_D(CHIPS)':
 'GPP_B19': CDS_PINID='GPP_B19';
NODE_NAME     R2N13 1
 '@BASEBOARD_FAB2_LIB.BASEBOARD_FAB2(SCH_1):PAGE147_I75@MSTR_DISCRETE.RES(CHIPS)':
 'A': CDS_PINID='A';
NODE_NAME     U25W4 V3
 '@BASEBOARD_FAB2_LIB.BASEBOARD_FAB2(SCH_1):PAGE147_I106@W_HDL.AST2520A1-GP-GP(CHIPS)':
 'GPION2_PWM2_VPIG2': CDS_PINID='GPION2_PWM2_VPIG2';
NET_NAME
'FM_BIOS_SMI_ACTIVE_N'
 '@BASEBOARD_FAB2_LIB.BASEBOARD_FAB2(SCH_1):FM_BIOS_SMI_ACTIVE_N':
 C_SIGNAL='@baseboard_fab2_lib.baseboard_fab2(sch_1):fm_bios_smi_active_n';
NODE_NAME     U7C1 BE15
 '@BASEBOARD_FAB2_LIB.BASEBOARD_FAB2(SCH_1):PAGE120_I147@MSTR_U_PROC.LBG_CORE_QAT_EXT_D(CHIPS)':
 'GPP_G19_SMI_N': CDS_PINID='GPP_G19_SMI_N';
NODE_NAME     U7C1 BA2
 '@BASEBOARD_FAB2_LIB.BASEBOARD_FAB2(SCH_1):PAGE120_I147@MSTR_U_PROC.LBG_CORE_QAT_EXT_D(CHIPS)':
 'GPP_H21_SSATAXPCIE3_SSATAGP3': CDS_PINID='GPP_H21_SSATAXPCIE3_SSATAGP3';
NODE_NAME     R2N32 2
 '@BASEBOARD_FAB2_LIB.BASEBOARD_FAB2(SCH_1):PAGE133_I341@MSTR_DISCRETE.RES(CHIPS)':
 'B': CDS_PINID='B';
NODE_NAME     U25W4 E14
 '@BASEBOARD_FAB2_LIB.BASEBOARD_FAB2(SCH_1):PAGE145_I117@W_HDL.AST2520A1-GP-GP(CHIPS)':
 'GPIOG7_SGPS2I1_SALT4': CDS_PINID='GPIOG7_SGPS2I1_SALT4';
NET_NAME
'FM_BIOS_SPI_BMC_CTRL'
 '@BASEBOARD_FAB2_LIB.BASEBOARD_FAB2(SCH_1):FM_BIOS_SPI_BMC_CTRL':
 C_SIGNAL='@baseboard_fab2_lib.baseboard_fab2(sch_1):fm_bios_spi_bmc_ctrl';
NODE_NAME     U8F1 1
 '@BASEBOARD_FAB2_LIB.BASEBOARD_FAB2(SCH_1):PAGE154_I74@MSTR_DIGITAL.PI3B3257A(CHIPS)':
 'S': CDS_PINID='S';
NODE_NAME     U2T1 1
 '@BASEBOARD_FAB2_LIB.BASEBOARD_FAB2(SCH_1):PAGE154_I75@MSTR_DIGITAL.PI3B3257A(CHIPS)':
 'S': CDS_PINID='S';
NODE_NAME     R1U6 1
 '@BASEBOARD_FAB2_LIB.BASEBOARD_FAB2(SCH_1):PAGE154_I128@MSTR_DISCRETE.RES(CHIPS)':
 'A': CDS_PINID='A';
NODE_NAME     U25W4 AA3
 '@BASEBOARD_FAB2_LIB.BASEBOARD_FAB2(SCH_1):PAGE147_I106@W_HDL.AST2520A1-GP-GP(CHIPS)':
 'GPION5_PWM5_VPIG5': CDS_PINID='GPION5_PWM5_VPIG5';
NET_NAME
'FM_BIOS_TOP_SWAP'
 '@BASEBOARD_FAB2_LIB.BASEBOARD_FAB2(SCH_1):FM_BIOS_TOP_SWAP':
 C_SIGNAL='@baseboard_fab2_lib.baseboard_fab2(sch_1):fm_bios_top_swap';
NODE_NAME     U7C1 AP15
 '@BASEBOARD_FAB2_LIB.BASEBOARD_FAB2(SCH_1):PAGE120_I147@MSTR_U_PROC.LBG_CORE_QAT_EXT_D(CHIPS)':
 'GPP_F17_USB2_OC6_N': CDS_PINID='GPP_F17_USB2_OC6_N';
NODE_NAME     U8E3 2
 '@BASEBOARD_FAB2_LIB.BASEBOARD_FAB2(SCH_1):PAGE136_I130@MSTR_TTL.TTL1G126_A(CHIPS)':
 'A': CDS_PINID='A';
NODE_NAME     R8E16 1
 '@BASEBOARD_FAB2_LIB.BASEBOARD_FAB2(SCH_1):PAGE136_I140@MSTR_DISCRETE.RES(CHIPS)':
 'A': CDS_PINID='A';
NODE_NAME     J7G3 10
 '@BASEBOARD_FAB2_LIB.BASEBOARD_FAB2(SCH_1):PAGE136_I174@MSTR_CONN.CONN12_C73564003(CHIPS)':
 'IO10': CDS_PINID='IO10';
NODE_NAME     R8E19 2
 '@BASEBOARD_FAB2_LIB.BASEBOARD_FAB2(SCH_1):PAGE157_I361@MSTR_DISCRETE.RES(CHIPS)':
 'B': CDS_PINID='B';
NODE_NAME     U25W4 U2
 '@BASEBOARD_FAB2_LIB.BASEBOARD_FAB2(SCH_1):PAGE145_I117@W_HDL.AST2520A1-GP-GP(CHIPS)':
 'GPIOL3_NRI1_VPIHS': CDS_PINID='GPIOL3_NRI1_VPIHS';
NET_NAME
'FM_BIOS_TOP_SWAP_SPKR'
 '@BASEBOARD_FAB2_LIB.BASEBOARD_FAB2(SCH_1):FM_BIOS_TOP_SWAP_SPKR':
 C_SIGNAL='@baseboard_fab2_lib.baseboard_fab2(sch_1):fm_bios_top_swap_spkr';
NODE_NAME     U7C1 BH13
 '@BASEBOARD_FAB2_LIB.BASEBOARD_FAB2(SCH_1):PAGE119_I115@MSTR_U_PROC.LBG_CORE_QAT_EXT_D(CHIPS)':
 'GPP_B14_SPKR': CDS_PINID='GPP_B14_SPKR';
NODE_NAME     R8E20 2
 '@BASEBOARD_FAB2_LIB.BASEBOARD_FAB2(SCH_1):PAGE136_I126@MSTR_DISCRETE.RES(CHIPS)':
 'B': CDS_PINID='B';
NODE_NAME     Q9A3 1
 '@BASEBOARD_FAB2_LIB.BASEBOARD_FAB2(SCH_1):PAGE175_I49@MSTR_DISCRETE.FET_N(CHIPS)':
 'GATE': CDS_PINID='GATE';
NET_NAME
'FM_BIOS_TOP_SWAP_SPKR_R'
 '@BASEBOARD_FAB2_LIB.BASEBOARD_FAB2(SCH_1):FM_BIOS_TOP_SWAP_SPKR_R':
 C_SIGNAL='@baseboard_fab2_lib.baseboard_fab2(sch_1):fm_bios_top_swap_spkr_r';
NODE_NAME     R8E20 1
 '@BASEBOARD_FAB2_LIB.BASEBOARD_FAB2(SCH_1):PAGE136_I126@MSTR_DISCRETE.RES(CHIPS)':
 'A': CDS_PINID='A';
NODE_NAME     U8E3 4
 '@BASEBOARD_FAB2_LIB.BASEBOARD_FAB2(SCH_1):PAGE136_I130@MSTR_TTL.TTL1G126_A(CHIPS)':
 'Y': CDS_PINID='Y';
NET_NAME
'FM_BIOS_USB_RECOVERY'
 '@BASEBOARD_FAB2_LIB.BASEBOARD_FAB2(SCH_1):FM_BIOS_USB_RECOVERY':
 C_SIGNAL='@baseboard_fab2_lib.baseboard_fab2(sch_1):fm_bios_usb_recovery';
NODE_NAME     U7C1 AH17
 '@BASEBOARD_FAB2_LIB.BASEBOARD_FAB2(SCH_1):PAGE120_I147@MSTR_U_PROC.LBG_CORE_QAT_EXT_D(CHIPS)':
 'GPP_F5_SATA_DEVSLP3': CDS_PINID='GPP_F5_SATA_DEVSLP3';
NODE_NAME     R3T14 1
 '@BASEBOARD_FAB2_LIB.BASEBOARD_FAB2(SCH_1):PAGE136_I156@MSTR_DISCRETE.RES(CHIPS)':
 'A': CDS_PINID='A';
NODE_NAME     J7G3 4
 '@BASEBOARD_FAB2_LIB.BASEBOARD_FAB2(SCH_1):PAGE136_I174@MSTR_CONN.CONN12_C73564003(CHIPS)':
 'IO4': CDS_PINID='IO4';
NET_NAME
'FM_BMC_CPLD_GPO'
 '@BASEBOARD_FAB2_LIB.BASEBOARD_FAB2(SCH_1):FM_BMC_CPLD_GPO':
 C_SIGNAL='@baseboard_fab2_lib.baseboard_fab2(sch_1):fm_bmc_cpld_gpo',
 PHYS_NET_NAME='FM_BMC_CPLD_GPO';
NODE_NAME     U7C1 CA45
 '@BASEBOARD_FAB2_LIB.BASEBOARD_FAB2(SCH_1):PAGE119_I115@MSTR_U_PROC.LBG_CORE_QAT_EXT_D(CHIPS)':
 'GPP_D7': CDS_PINID='GPP_D7';
NODE_NAME     R2M5 2
 '@BASEBOARD_FAB2_LIB.BASEBOARD_FAB2(SCH_1):PAGE157_I348@MSTR_DISCRETE.RES(CHIPS)':
 'B': CDS_PINID='B';
NODE_NAME     U8D7 R1
 '@BASEBOARD_FAB2_LIB.BASEBOARD_FAB2(SCH_1):PAGE190_I179@MSTR_MEMORY.LCMXO2_A(CHIPS)':
 'PL14C': CDS_PINID='PL14C';
NODE_NAME     U25W4 Y20
 '@BASEBOARD_FAB2_LIB.BASEBOARD_FAB2(SCH_1):PAGE146_I104@W_HDL.AST2520A1-GP-GP(CHIPS)':
 'GPIOZ0_VPOG2_NORA0_SIOPBI#': CDS_PINID='\gpioz0_vpog2_nora0_siopbi#\';
NET_NAME
'FM_BMC_CPLD_MP_RST_N'
 '@BASEBOARD_FAB2_LIB.BASEBOARD_FAB2(SCH_1):FM_BMC_CPLD_MP_RST_N':
 C_SIGNAL='@baseboard_fab2_lib.baseboard_fab2(sch_1):fm_bmc_cpld_mp_rst_n';
NODE_NAME     U7C1 A15
 '@BASEBOARD_FAB2_LIB.BASEBOARD_FAB2(SCH_1):PAGE118_I73@MSTR_U_PROC.LBG_CORE_QAT_EXT_D(CHIPS)':
 'GPD9': CDS_PINID='GPD9';
NODE_NAME     R1L7 2
 '@BASEBOARD_FAB2_LIB.BASEBOARD_FAB2(SCH_1):PAGE157_I382@MSTR_DISCRETE.RES(CHIPS)':
 'B': CDS_PINID='B';
NODE_NAME     U8D7 R4
 '@BASEBOARD_FAB2_LIB.BASEBOARD_FAB2(SCH_1):PAGE190_I179@MSTR_MEMORY.LCMXO2_A(CHIPS)':
 'PB6D': CDS_PINID='PB6D';
NODE_NAME     U25W4 B13
 '@BASEBOARD_FAB2_LIB.BASEBOARD_FAB2(SCH_1):PAGE147_I106@W_HDL.AST2520A1-GP-GP(CHIPS)':
 'GPIOA7_TIMER8_MDIO2': CDS_PINID='GPIOA7_TIMER8_MDIO2';
NET_NAME
'FM_BMC_ENABLE_N'
 '@BASEBOARD_FAB2_LIB.BASEBOARD_FAB2(SCH_1):FM_BMC_ENABLE_N':
 C_SIGNAL='@baseboard_fab2_lib.baseboard_fab2(sch_1):fm_bmc_enable_n';
NODE_NAME     U7C1 BM38
 '@BASEBOARD_FAB2_LIB.BASEBOARD_FAB2(SCH_1):PAGE119_I115@MSTR_U_PROC.LBG_CORE_QAT_EXT_D(CHIPS)':
 'GPP_D5': CDS_PINID='GPP_D5';
NODE_NAME     R9E14 2
 '@BASEBOARD_FAB2_LIB.BASEBOARD_FAB2(SCH_1):PAGE157_I393@MSTR_DISCRETE.RES(CHIPS)':
 'B': CDS_PINID='B';
NODE_NAME     R7W22 2
 '@BASEBOARD_FAB2_LIB.BASEBOARD_FAB2(SCH_1):PAGE119_I230@MSTR_DISCRETE.RES(CHIPS)':
 'B': CDS_PINID='B';
NET_NAME
'FM_BMC_FAULT_LED'
 '@BASEBOARD_FAB2_LIB.BASEBOARD_FAB2(SCH_1):FM_BMC_FAULT_LED':
 C_SIGNAL='@baseboard_fab2_lib.baseboard_fab2(sch_1):fm_bmc_fault_led';
NODE_NAME     Q9F1 5
 '@BASEBOARD_FAB2_LIB.BASEBOARD_FAB2(SCH_1):PAGE177_I79@MSTR_DISCRETE.FET_N_DUAL(CHIPS)':
 'GATE'<0>: CDS_PINID='GATE(0)';
NODE_NAME     Q9F1 6
 '@BASEBOARD_FAB2_LIB.BASEBOARD_FAB2(SCH_1):PAGE177_I80@MSTR_DISCRETE.FET_N_DUAL(CHIPS)':
 'DRAIN'<0>: CDS_PINID='DRAIN(0)';
NODE_NAME     R9F52 2
 '@BASEBOARD_FAB2_LIB.BASEBOARD_FAB2(SCH_1):PAGE177_I82@MSTR_DISCRETE.RES(CHIPS)':
 'B': CDS_PINID='B';
NET_NAME
'FM_BMC_FAULT_LED_N'
 '@BASEBOARD_FAB2_LIB.BASEBOARD_FAB2(SCH_1):FM_BMC_FAULT_LED_N':
 C_SIGNAL='@baseboard_fab2_lib.baseboard_fab2(sch_1):fm_bmc_fault_led_n';
NODE_NAME     U7C1 BR38
 '@BASEBOARD_FAB2_LIB.BASEBOARD_FAB2(SCH_1):PAGE119_I115@MSTR_U_PROC.LBG_CORE_QAT_EXT_D(CHIPS)':
 'GPP_D8': CDS_PINID='GPP_D8';
NODE_NAME     R9F30 2
 '@BASEBOARD_FAB2_LIB.BASEBOARD_FAB2(SCH_1):PAGE177_I76@MSTR_DISCRETE.RES(CHIPS)':
 'B': CDS_PINID='B';
NODE_NAME     Q9F1 2
 '@BASEBOARD_FAB2_LIB.BASEBOARD_FAB2(SCH_1):PAGE177_I80@MSTR_DISCRETE.FET_N_DUAL(CHIPS)':
 'GATE'<0>: CDS_PINID='GATE(0)';
NODE_NAME     U25W4 A4
 '@BASEBOARD_FAB2_LIB.BASEBOARD_FAB2(SCH_1):PAGE147_I106@W_HDL.AST2520A1-GP-GP(CHIPS)':
 'RGMII1RXCTL_GPIOU5': CDS_PINID='RGMII1RXCTL_GPIOU5';
NET_NAME
'FM_BMC_HEARTBEAT_N'
 '@BASEBOARD_FAB2_LIB.BASEBOARD_FAB2(SCH_1):FM_BMC_HEARTBEAT_N':
 C_SIGNAL='@baseboard_fab2_lib.baseboard_fab2(sch_1):fm_bmc_heartbeat_n';
NODE_NAME     U7C1 CA48
 '@BASEBOARD_FAB2_LIB.BASEBOARD_FAB2(SCH_1):PAGE119_I115@MSTR_U_PROC.LBG_CORE_QAT_EXT_D(CHIPS)':
 'GPP_D20': CDS_PINID='GPP_D20';
NODE_NAME     U25W4 Y18
 '@BASEBOARD_FAB2_LIB.BASEBOARD_FAB2(SCH_1):PAGE146_I105@W_HDL.AST2520A1-GP-GP(CHIPS)':
 'HBLED#': CDS_PINID='\hbled#\';
NODE_NAME     R8B25 2
 '@BASEBOARD_FAB2_LIB.BASEBOARD_FAB2(SCH_1):PAGE151_I175@MSTR_DISCRETE.RES(CHIPS)':
 'B': CDS_PINID='B';
NODE_NAME     Q9E1 2
 '@BASEBOARD_FAB2_LIB.BASEBOARD_FAB2(SCH_1):PAGE151_I198@MSTR_DISCRETE.FET_N_DUAL(CHIPS)':
 'GATE'<0>: CDS_PINID='GATE(0)';
NET_NAME
'FM_BMC_NMI_N'
 '@BASEBOARD_FAB2_LIB.BASEBOARD_FAB2(SCH_1):FM_BMC_NMI_N':
 C_SIGNAL='@baseboard_fab2_lib.baseboard_fab2(sch_1):fm_bmc_nmi_n';
NODE_NAME     U7C1 BF3
 '@BASEBOARD_FAB2_LIB.BASEBOARD_FAB2(SCH_1):PAGE120_I147@MSTR_U_PROC.LBG_CORE_QAT_EXT_D(CHIPS)':
 'GPP_H20_SSATAXPCIE2_SSATAGP2': CDS_PINID='GPP_H20_SSATAXPCIE2_SSATAGP2';
NODE_NAME     R2N27 2
 '@BASEBOARD_FAB2_LIB.BASEBOARD_FAB2(SCH_1):PAGE157_I97@MSTR_DISCRETE.RES(CHIPS)':
 'B': CDS_PINID='B';
NODE_NAME     R2N25 2
 '@BASEBOARD_FAB2_LIB.BASEBOARD_FAB2(SCH_1):PAGE157_I302@MSTR_DISCRETE.RES(CHIPS)':
 'B': CDS_PINID='B';
NODE_NAME     R25W83 1
 '@BASEBOARD_FAB2_LIB.BASEBOARD_FAB2(SCH_1):PAGE146_I26@MSTR_DISCRETE.RES(CHIPS)':
 'A': CDS_PINID='A';
NET_NAME
'FM_BMC_NMI_N_R'
 '@BASEBOARD_FAB2_LIB.BASEBOARD_FAB2(SCH_1):FM_BMC_NMI_N_R':
 C_SIGNAL='@baseboard_fab2_lib.baseboard_fab2(sch_1):fm_bmc_nmi_n_r';
NODE_NAME     R25W83 2
 '@BASEBOARD_FAB2_LIB.BASEBOARD_FAB2(SCH_1):PAGE146_I26@MSTR_DISCRETE.RES(CHIPS)':
 'B': CDS_PINID='B';
NODE_NAME     U25W4 AB20
 '@BASEBOARD_FAB2_LIB.BASEBOARD_FAB2(SCH_1):PAGE146_I104@W_HDL.AST2520A1-GP-GP(CHIPS)':
 'GPIOZ1_VPOG3_NORA1_SIOPWRGD': CDS_PINID='GPIOZ1_VPOG3_NORA1_SIOPWRGD';
NET_NAME
'FM_BMC_ONCTL_N'
 '@BASEBOARD_FAB2_LIB.BASEBOARD_FAB2(SCH_1):FM_BMC_ONCTL_N':
 C_SIGNAL='@baseboard_fab2_lib.baseboard_fab2(sch_1):fm_bmc_onctl_n';
NODE_NAME     U8D7 C7
 '@BASEBOARD_FAB2_LIB.BASEBOARD_FAB2(SCH_1):PAGE191_I59@MSTR_MEMORY.LCMXO2_A(CHIPS)':
 'PT13B': CDS_PINID='PT13B';
NODE_NAME     R1T15 1
 '@BASEBOARD_FAB2_LIB.BASEBOARD_FAB2(SCH_1):PAGE145_I100@MSTR_DISCRETE.RES(CHIPS)':
 'A': CDS_PINID='A';
NET_NAME
'FM_BMC_ONCTL_R_N'
 '@BASEBOARD_FAB2_LIB.BASEBOARD_FAB2(SCH_1):FM_BMC_ONCTL_R_N':
 C_SIGNAL='@baseboard_fab2_lib.baseboard_fab2(sch_1):fm_bmc_onctl_r_n';
NODE_NAME     R1T15 2
 '@BASEBOARD_FAB2_LIB.BASEBOARD_FAB2(SCH_1):PAGE145_I100@MSTR_DISCRETE.RES(CHIPS)':
 'B': CDS_PINID='B';
NODE_NAME     R1T23 1
 '@BASEBOARD_FAB2_LIB.BASEBOARD_FAB2(SCH_1):PAGE145_I101@MSTR_DISCRETE.RES(CHIPS)':
 'A': CDS_PINID='A';
NODE_NAME     U25W4 P21
 '@BASEBOARD_FAB2_LIB.BASEBOARD_FAB2(SCH_1):PAGE145_I117@W_HDL.AST2520A1-GP-GP(CHIPS)':
 'GPIOY3_SIOONCTRL#': CDS_PINID='\gpioy3_sioonctrl#\';
NET_NAME
'FM_BMC_PWRBTN_OUT_N'
 '@BASEBOARD_FAB2_LIB.BASEBOARD_FAB2(SCH_1):FM_BMC_PWRBTN_OUT_N':
 C_SIGNAL='@baseboard_fab2_lib.baseboard_fab2(sch_1):fm_bmc_pwrbtn_out_n';
NODE_NAME     R2T34 2
 '@BASEBOARD_FAB2_LIB.BASEBOARD_FAB2(SCH_1):PAGE156_I206@MSTR_DISCRETE.RES(CHIPS)':
 'B': CDS_PINID='B';
NODE_NAME     U25W4 F17
 '@BASEBOARD_FAB2_LIB.BASEBOARD_FAB2(SCH_1):PAGE145_I117@W_HDL.AST2520A1-GP-GP(CHIPS)':
 'GPIOE3_NRI3': CDS_PINID='GPIOE3_NRI3';
NODE_NAME     U8F3 3
 '@BASEBOARD_FAB2_LIB.BASEBOARD_FAB2(SCH_1):PAGE156_I340@W_HDL.SN74LVC2G07DCKR-GP(CHIPS)':
 '2A': CDS_PINID='\2a\';
NET_NAME
'FM_BMC_READY_N'
 '@BASEBOARD_FAB2_LIB.BASEBOARD_FAB2(SCH_1):FM_BMC_READY_N':
 C_SIGNAL='@baseboard_fab2_lib.baseboard_fab2(sch_1):fm_bmc_ready_n';
NODE_NAME     R7D6 2
 '@BASEBOARD_FAB2_LIB.BASEBOARD_FAB2(SCH_1):PAGE133_I306@MSTR_DISCRETE.RES(CHIPS)':
 'B': CDS_PINID='B';
NODE_NAME     U25W4 U19
 '@BASEBOARD_FAB2_LIB.BASEBOARD_FAB2(SCH_1):PAGE146_I104@W_HDL.AST2520A1-GP-GP(CHIPS)':
 'GPIOS1_VPOB3_BMCINT': CDS_PINID='GPIOS1_VPOB3_BMCINT';
NODE_NAME     R1F9 1
 '@BASEBOARD_FAB2_LIB.BASEBOARD_FAB2(SCH_1):PAGE182_I7@MSTR_DISCRETE.RES(CHIPS)':
 'A': CDS_PINID='A';
NODE_NAME     R7W13 1
 '@BASEBOARD_FAB2_LIB.BASEBOARD_FAB2(SCH_1):PAGE119_I226@MSTR_DISCRETE.RES(CHIPS)':
 'A': CDS_PINID='A';
NODE_NAME     R7W14 1
 '@BASEBOARD_FAB2_LIB.BASEBOARD_FAB2(SCH_1):PAGE120_I274@MSTR_DISCRETE.RES(CHIPS)':
 'A': CDS_PINID='A';
NET_NAME
'FM_BMC_READY_R1_N'
 '@BASEBOARD_FAB2_LIB.BASEBOARD_FAB2(SCH_1):FM_BMC_READY_R1_N':
 C_SIGNAL='@baseboard_fab2_lib.baseboard_fab2(sch_1):fm_bmc_ready_r1_n';
NODE_NAME     U7C1 AH13
 '@BASEBOARD_FAB2_LIB.BASEBOARD_FAB2(SCH_1):PAGE120_I147@MSTR_U_PROC.LBG_CORE_QAT_EXT_D(CHIPS)':
 'GPP_F4_SATAXPCIE7_SATAGP7': CDS_PINID='GPP_F4_SATAXPCIE7_SATAGP7';
NODE_NAME     R7W14 2
 '@BASEBOARD_FAB2_LIB.BASEBOARD_FAB2(SCH_1):PAGE120_I274@MSTR_DISCRETE.RES(CHIPS)':
 'B': CDS_PINID='B';
NET_NAME
'FM_BMC_READY_R_N'
 '@BASEBOARD_FAB2_LIB.BASEBOARD_FAB2(SCH_1):FM_BMC_READY_R_N':
 C_SIGNAL='@baseboard_fab2_lib.baseboard_fab2(sch_1):fm_bmc_ready_r_n';
NODE_NAME     U7C1 V1
 '@BASEBOARD_FAB2_LIB.BASEBOARD_FAB2(SCH_1):PAGE119_I115@MSTR_U_PROC.LBG_CORE_QAT_EXT_D(CHIPS)':
 'GPP_A23': CDS_PINID='GPP_A23';
NODE_NAME     R7W13 2
 '@BASEBOARD_FAB2_LIB.BASEBOARD_FAB2(SCH_1):PAGE119_I226@MSTR_DISCRETE.RES(CHIPS)':
 'B': CDS_PINID='B';
NET_NAME
'FM_BMC_SYS_THROTTLE_R_N'
 '@BASEBOARD_FAB2_LIB.BASEBOARD_FAB2(SCH_1):FM_BMC_SYS_THROTTLE_R_N':
 C_SIGNAL='@baseboard_fab2_lib.baseboard_fab2(sch_1):fm_bmc_sys_throttle_r_n';
NODE_NAME     U25W4 E13
 '@BASEBOARD_FAB2_LIB.BASEBOARD_FAB2(SCH_1):PAGE145_I117@W_HDL.AST2520A1-GP-GP(CHIPS)':
 'GPIOA3_TIMER4': CDS_PINID='GPIOA3_TIMER4';
NODE_NAME     R2T41 2
 '@BASEBOARD_FAB2_LIB.BASEBOARD_FAB2(SCH_1):PAGE145_I136@MSTR_DISCRETE.RES(CHIPS)':
 'B': CDS_PINID='B';
NET_NAME
'FM_BOARD_REV_ID0'
 '@BASEBOARD_FAB2_LIB.BASEBOARD_FAB2(SCH_1):FM_BOARD_REV_ID0':
 C_SIGNAL='@baseboard_fab2_lib.baseboard_fab2(sch_1):fm_board_rev_id0';
NODE_NAME     U7C1 CA30
 '@BASEBOARD_FAB2_LIB.BASEBOARD_FAB2(SCH_1):PAGE119_I115@MSTR_U_PROC.LBG_CORE_QAT_EXT_D(CHIPS)':
 'GPP_C12': CDS_PINID='GPP_C12';
NODE_NAME     U25W4 E21
 '@BASEBOARD_FAB2_LIB.BASEBOARD_FAB2(SCH_1):PAGE145_I117@W_HDL.AST2520A1-GP-GP(CHIPS)':
 'GPIOD1_SD2CMD': CDS_PINID='GPIOD1_SD2CMD';
NODE_NAME     R1T4 2
 '@BASEBOARD_FAB2_LIB.BASEBOARD_FAB2(SCH_1):PAGE164_I100@MSTR_DISCRETE.RES(CHIPS)':
 'B': CDS_PINID='B';
NODE_NAME     R1T10 1
 '@BASEBOARD_FAB2_LIB.BASEBOARD_FAB2(SCH_1):PAGE164_I101@MSTR_DISCRETE.RES(CHIPS)':
 'A': CDS_PINID='A';
NET_NAME
'FM_BOARD_REV_ID1'
 '@BASEBOARD_FAB2_LIB.BASEBOARD_FAB2(SCH_1):FM_BOARD_REV_ID1':
 C_SIGNAL='@baseboard_fab2_lib.baseboard_fab2(sch_1):fm_board_rev_id1';
NODE_NAME     U7C1 BV38
 '@BASEBOARD_FAB2_LIB.BASEBOARD_FAB2(SCH_1):PAGE119_I115@MSTR_U_PROC.LBG_CORE_QAT_EXT_D(CHIPS)':
 'GPP_C13': CDS_PINID='GPP_C13';
NODE_NAME     U25W4 D20
 '@BASEBOARD_FAB2_LIB.BASEBOARD_FAB2(SCH_1):PAGE145_I117@W_HDL.AST2520A1-GP-GP(CHIPS)':
 'GPIOD3_SD2DAT1': CDS_PINID='GPIOD3_SD2DAT1';
NODE_NAME     R1T6 2
 '@BASEBOARD_FAB2_LIB.BASEBOARD_FAB2(SCH_1):PAGE164_I51@MSTR_DISCRETE.RES(CHIPS)':
 'B': CDS_PINID='B';
NODE_NAME     R1T12 1
 '@BASEBOARD_FAB2_LIB.BASEBOARD_FAB2(SCH_1):PAGE164_I53@MSTR_DISCRETE.RES(CHIPS)':
 'A': CDS_PINID='A';
NET_NAME
'FM_BOARD_REV_ID2'
 '@BASEBOARD_FAB2_LIB.BASEBOARD_FAB2(SCH_1):FM_BOARD_REV_ID2':
 C_SIGNAL='@baseboard_fab2_lib.baseboard_fab2(sch_1):fm_board_rev_id2';
NODE_NAME     U7C1 BV33
 '@BASEBOARD_FAB2_LIB.BASEBOARD_FAB2(SCH_1):PAGE119_I115@MSTR_U_PROC.LBG_CORE_QAT_EXT_D(CHIPS)':
 'GPP_C11': CDS_PINID='GPP_C11';
NODE_NAME     R1T11 1
 '@BASEBOARD_FAB2_LIB.BASEBOARD_FAB2(SCH_1):PAGE164_I7@MSTR_DISCRETE.RES(CHIPS)':
 'A': CDS_PINID='A';
NODE_NAME     R1T5 2
 '@BASEBOARD_FAB2_LIB.BASEBOARD_FAB2(SCH_1):PAGE164_I11@MSTR_DISCRETE.RES(CHIPS)':
 'B': CDS_PINID='B';
NODE_NAME     U25W4 E20
 '@BASEBOARD_FAB2_LIB.BASEBOARD_FAB2(SCH_1):PAGE145_I117@W_HDL.AST2520A1-GP-GP(CHIPS)':
 'GPIOD5_SD2DAT3': CDS_PINID='GPIOD5_SD2DAT3';
NET_NAME
'FM_BOARD_SKU_ID0'
 '@BASEBOARD_FAB2_LIB.BASEBOARD_FAB2(SCH_1):FM_BOARD_SKU_ID0':
 C_SIGNAL='@baseboard_fab2_lib.baseboard_fab2(sch_1):fm_board_sku_id0';
NODE_NAME     U7C1 BD13
 '@BASEBOARD_FAB2_LIB.BASEBOARD_FAB2(SCH_1):PAGE120_I147@MSTR_U_PROC.LBG_CORE_QAT_EXT_D(CHIPS)':
 'GPP_G12': CDS_PINID='GPP_G12';
NODE_NAME     U25W4 V4
 '@BASEBOARD_FAB2_LIB.BASEBOARD_FAB2(SCH_1):PAGE147_I106@W_HDL.AST2520A1-GP-GP(CHIPS)':
 'GPIOP0_TACH8_VPIR6': CDS_PINID='GPIOP0_TACH8_VPIR6';
NODE_NAME     R1U23 2
 '@BASEBOARD_FAB2_LIB.BASEBOARD_FAB2(SCH_1):PAGE164_I34@MSTR_DISCRETE.RES(CHIPS)':
 'B': CDS_PINID='B';
NODE_NAME     R1U18 1
 '@BASEBOARD_FAB2_LIB.BASEBOARD_FAB2(SCH_1):PAGE164_I40@MSTR_DISCRETE.RES(CHIPS)':
 'A': CDS_PINID='A';
NET_NAME
'FM_BOARD_SKU_ID1'
 '@BASEBOARD_FAB2_LIB.BASEBOARD_FAB2(SCH_1):FM_BOARD_SKU_ID1':
 C_SIGNAL='@baseboard_fab2_lib.baseboard_fab2(sch_1):fm_board_sku_id1';
NODE_NAME     U7C1 AY18
 '@BASEBOARD_FAB2_LIB.BASEBOARD_FAB2(SCH_1):PAGE120_I147@MSTR_U_PROC.LBG_CORE_QAT_EXT_D(CHIPS)':
 'GPP_G13': CDS_PINID='GPP_G13';
NODE_NAME     U25W4 W5
 '@BASEBOARD_FAB2_LIB.BASEBOARD_FAB2(SCH_1):PAGE147_I106@W_HDL.AST2520A1-GP-GP(CHIPS)':
 'GPIOP1_TACH9_VPIR7': CDS_PINID='GPIOP1_TACH9_VPIR7';
NODE_NAME     R1U16 1
 '@BASEBOARD_FAB2_LIB.BASEBOARD_FAB2(SCH_1):PAGE164_I37@MSTR_DISCRETE.RES(CHIPS)':
 'A': CDS_PINID='A';
NODE_NAME     R1U22 2
 '@BASEBOARD_FAB2_LIB.BASEBOARD_FAB2(SCH_1):PAGE164_I43@MSTR_DISCRETE.RES(CHIPS)':
 'B': CDS_PINID='B';
NET_NAME
'FM_BOARD_SKU_ID2'
 '@BASEBOARD_FAB2_LIB.BASEBOARD_FAB2(SCH_1):FM_BOARD_SKU_ID2':
 C_SIGNAL='@baseboard_fab2_lib.baseboard_fab2(sch_1):fm_board_sku_id2';
NODE_NAME     U7C1 AV7
 '@BASEBOARD_FAB2_LIB.BASEBOARD_FAB2(SCH_1):PAGE120_I147@MSTR_U_PROC.LBG_CORE_QAT_EXT_D(CHIPS)':
 'GPP_G14': CDS_PINID='GPP_G14';
NODE_NAME     R1U17 1
 '@BASEBOARD_FAB2_LIB.BASEBOARD_FAB2(SCH_1):PAGE164_I21@MSTR_DISCRETE.RES(CHIPS)':
 'A': CDS_PINID='A';
NODE_NAME     U25W4 AA5
 '@BASEBOARD_FAB2_LIB.BASEBOARD_FAB2(SCH_1):PAGE147_I106@W_HDL.AST2520A1-GP-GP(CHIPS)':
 'GPIOP2_TACH10_VPIR8': CDS_PINID='GPIOP2_TACH10_VPIR8';
NODE_NAME     R1U24 2
 '@BASEBOARD_FAB2_LIB.BASEBOARD_FAB2(SCH_1):PAGE164_I47@MSTR_DISCRETE.RES(CHIPS)':
 'B': CDS_PINID='B';
NET_NAME
'FM_BOARD_SKU_ID3'
 '@BASEBOARD_FAB2_LIB.BASEBOARD_FAB2(SCH_1):FM_BOARD_SKU_ID3':
 C_SIGNAL='@baseboard_fab2_lib.baseboard_fab2(sch_1):fm_board_sku_id3';
NODE_NAME     U7C1 BE18
 '@BASEBOARD_FAB2_LIB.BASEBOARD_FAB2(SCH_1):PAGE120_I147@MSTR_U_PROC.LBG_CORE_QAT_EXT_D(CHIPS)':
 'GPP_G15': CDS_PINID='GPP_G15';
NODE_NAME     U25W4 AB5
 '@BASEBOARD_FAB2_LIB.BASEBOARD_FAB2(SCH_1):PAGE147_I106@W_HDL.AST2520A1-GP-GP(CHIPS)':
 'GPIOP3_TACH11_VPIR9': CDS_PINID='GPIOP3_TACH11_VPIR9';
NODE_NAME     R1U21 2
 '@BASEBOARD_FAB2_LIB.BASEBOARD_FAB2(SCH_1):PAGE164_I41@MSTR_DISCRETE.RES(CHIPS)':
 'B': CDS_PINID='B';
NODE_NAME     R1U15 1
 '@BASEBOARD_FAB2_LIB.BASEBOARD_FAB2(SCH_1):PAGE164_I48@MSTR_DISCRETE.RES(CHIPS)':
 'A': CDS_PINID='A';
NET_NAME
'FM_BOARD_SKU_ID4'
 '@BASEBOARD_FAB2_LIB.BASEBOARD_FAB2(SCH_1):FM_BOARD_SKU_ID4':
 C_SIGNAL='@baseboard_fab2_lib.baseboard_fab2(sch_1):fm_board_sku_id4';
NODE_NAME     U7C1 BD17
 '@BASEBOARD_FAB2_LIB.BASEBOARD_FAB2(SCH_1):PAGE120_I147@MSTR_U_PROC.LBG_CORE_QAT_EXT_D(CHIPS)':
 'GPP_G16': CDS_PINID='GPP_G16';
NODE_NAME     R2N18 1
 '@BASEBOARD_FAB2_LIB.BASEBOARD_FAB2(SCH_1):PAGE164_I32@MSTR_DISCRETE.RES(CHIPS)':
 'A': CDS_PINID='A';
NODE_NAME     U25W4 Y6
 '@BASEBOARD_FAB2_LIB.BASEBOARD_FAB2(SCH_1):PAGE147_I106@W_HDL.AST2520A1-GP-GP(CHIPS)':
 'GPIOP4_TACH12': CDS_PINID='GPIOP4_TACH12';
NODE_NAME     R2N17 2
 '@BASEBOARD_FAB2_LIB.BASEBOARD_FAB2(SCH_1):PAGE164_I46@MSTR_DISCRETE.RES(CHIPS)':
 'B': CDS_PINID='B';
NET_NAME
'FM_CPLD_ADR_TRIGGER_N'
 '@BASEBOARD_FAB2_LIB.BASEBOARD_FAB2(SCH_1):FM_CPLD_ADR_TRIGGER_N':
 C_SIGNAL='@baseboard_fab2_lib.baseboard_fab2(sch_1):fm_cpld_adr_trigger_n';
NODE_NAME     R2M1 1
 '@BASEBOARD_FAB2_LIB.BASEBOARD_FAB2(SCH_1):PAGE120_I218@MSTR_DISCRETE.RES(CHIPS)':
 'A': CDS_PINID='A';
NODE_NAME     U8D7 E14
 '@BASEBOARD_FAB2_LIB.BASEBOARD_FAB2(SCH_1):PAGE191_I59@MSTR_MEMORY.LCMXO2_A(CHIPS)':
 'PR2B': CDS_PINID='PR2B';
NET_NAME
'FM_CPLD_ADR_TRIGGER_R_N'
 '@BASEBOARD_FAB2_LIB.BASEBOARD_FAB2(SCH_1):FM_CPLD_ADR_TRIGGER_R_N':
 C_SIGNAL='@baseboard_fab2_lib.baseboard_fab2(sch_1):fm_cpld_adr_trigger_r_n';
NODE_NAME     U7C1 BE52
 '@BASEBOARD_FAB2_LIB.BASEBOARD_FAB2(SCH_1):PAGE120_I147@MSTR_U_PROC.LBG_CORE_QAT_EXT_D(CHIPS)':
 'GPP_E3_CPU_GP0': CDS_PINID='GPP_E3_CPU_GP0';
NODE_NAME     R2M1 2
 '@BASEBOARD_FAB2_LIB.BASEBOARD_FAB2(SCH_1):PAGE120_I218@MSTR_DISCRETE.RES(CHIPS)':
 'B': CDS_PINID='B';
NET_NAME
'FM_CPLD_BMC_PWRDN_N'
 '@BASEBOARD_FAB2_LIB.BASEBOARD_FAB2(SCH_1):FM_CPLD_BMC_PWRDN_N':
 C_SIGNAL='@baseboard_fab2_lib.baseboard_fab2(sch_1):fm_cpld_bmc_pwrdn_n',
 PHYS_NET_NAME='FM_CPLD_BMC_PWRDN_N';
NODE_NAME     U7C1 BW41
 '@BASEBOARD_FAB2_LIB.BASEBOARD_FAB2(SCH_1):PAGE119_I115@MSTR_U_PROC.LBG_CORE_QAT_EXT_D(CHIPS)':
 'GPP_D6': CDS_PINID='GPP_D6';
NODE_NAME     R2U4 2
 '@BASEBOARD_FAB2_LIB.BASEBOARD_FAB2(SCH_1):PAGE157_I367@MSTR_DISCRETE.RES(CHIPS)':
 'B': CDS_PINID='B';
NODE_NAME     U8D7 N9
 '@BASEBOARD_FAB2_LIB.BASEBOARD_FAB2(SCH_1):PAGE190_I179@MSTR_MEMORY.LCMXO2_A(CHIPS)':
 'PB16D': CDS_PINID='PB16D';
NODE_NAME     U25W4 D14
 '@BASEBOARD_FAB2_LIB.BASEBOARD_FAB2(SCH_1):PAGE145_I117@W_HDL.AST2520A1-GP-GP(CHIPS)':
 'GPIOA1_MAC2LINK': CDS_PINID='GPIOA1_MAC2LINK';
NET_NAME
'FM_CPLD_DBG_PWR_EN'
 '@BASEBOARD_FAB2_LIB.BASEBOARD_FAB2(SCH_1):FM_CPLD_DBG_PWR_EN':
 C_SIGNAL='@baseboard_fab2_lib.baseboard_fab2(sch_1):fm_cpld_dbg_pwr_en';
NODE_NAME     R1L9 2
 '@BASEBOARD_FAB2_LIB.BASEBOARD_FAB2(SCH_1):PAGE155_I130@MSTR_DISCRETE.RES(CHIPS)':
 'B': CDS_PINID='B';
NODE_NAME     Q1L2 3
 '@BASEBOARD_FAB2_LIB.BASEBOARD_FAB2(SCH_1):PAGE155_I187@MSTR_DISCRETE.FET_N_DUAL(CHIPS)':
 'DRAIN'<0>: CDS_PINID='DRAIN(0)';
NODE_NAME     Q1L2 2
 '@BASEBOARD_FAB2_LIB.BASEBOARD_FAB2(SCH_1):PAGE155_I188@MSTR_DISCRETE.FET_N_DUAL(CHIPS)':
 'GATE'<0>: CDS_PINID='GATE(0)';
NET_NAME
'FM_CPLD_DBG_PWR_EN_N'
 '@BASEBOARD_FAB2_LIB.BASEBOARD_FAB2(SCH_1):FM_CPLD_DBG_PWR_EN_N':
 C_SIGNAL='@baseboard_fab2_lib.baseboard_fab2(sch_1):fm_cpld_dbg_pwr_en_n';
NODE_NAME     R1L2 1
 '@BASEBOARD_FAB2_LIB.BASEBOARD_FAB2(SCH_1):PAGE155_I186@MSTR_DISCRETE.RES(CHIPS)':
 'A': CDS_PINID='A';
NODE_NAME     U8D7 T8
 '@BASEBOARD_FAB2_LIB.BASEBOARD_FAB2(SCH_1):PAGE190_I179@MSTR_MEMORY.LCMXO2_A(CHIPS)':
 'PB12B': CDS_PINID='PB12B';
NET_NAME
'FM_CPLD_DBG_PWR_EN_R_N'
 '@BASEBOARD_FAB2_LIB.BASEBOARD_FAB2(SCH_1):FM_CPLD_DBG_PWR_EN_R_N':
 C_SIGNAL='@baseboard_fab2_lib.baseboard_fab2(sch_1):fm_cpld_dbg_pwr_en_r_n';
NODE_NAME     R1L2 2
 '@BASEBOARD_FAB2_LIB.BASEBOARD_FAB2(SCH_1):PAGE155_I186@MSTR_DISCRETE.RES(CHIPS)':
 'B': CDS_PINID='B';
NODE_NAME     Q1L2 5
 '@BASEBOARD_FAB2_LIB.BASEBOARD_FAB2(SCH_1):PAGE155_I187@MSTR_DISCRETE.FET_N_DUAL(CHIPS)':
 'GATE'<0>: CDS_PINID='GATE(0)';
NET_NAME
'FM_CPLD_UART_CH_LOCK_N'
 '@BASEBOARD_FAB2_LIB.BASEBOARD_FAB2(SCH_1):FM_CPLD_UART_CH_LOCK_N':
 C_SIGNAL='@baseboard_fab2_lib.baseboard_fab2(sch_1):fm_cpld_uart_ch_lock_n';
NODE_NAME     R7D30 2
 '@BASEBOARD_FAB2_LIB.BASEBOARD_FAB2(SCH_1):PAGE135_I121@MSTR_DISCRETE.RES(CHIPS)':
 'B': CDS_PINID='B';
NODE_NAME     J8G2 9
 '@BASEBOARD_FAB2_LIB.BASEBOARD_FAB2(SCH_1):PAGE135_I124@MSTR_CONN.CONN12_C73564003(CHIPS)':
 'IO9': CDS_PINID='IO9';
NODE_NAME     U8D7 M9
 '@BASEBOARD_FAB2_LIB.BASEBOARD_FAB2(SCH_1):PAGE190_I179@MSTR_MEMORY.LCMXO2_A(CHIPS)':
 'PB18C': CDS_PINID='PB18C';
NET_NAME
'FM_CPLD_USB_P0_EN_N'
 '@BASEBOARD_FAB2_LIB.BASEBOARD_FAB2(SCH_1):FM_CPLD_USB_P0_EN_N':
 C_SIGNAL='@baseboard_fab2_lib.baseboard_fab2(sch_1):fm_cpld_usb_p0_en_n';
NODE_NAME     U8D7 R8
 '@BASEBOARD_FAB2_LIB.BASEBOARD_FAB2(SCH_1):PAGE190_I179@MSTR_MEMORY.LCMXO2_A(CHIPS)':
 'PB11B_PCLKC2_0': CDS_PINID='PB11B_PCLKC2_0';
NODE_NAME     R1W12 1
 '@BASEBOARD_FAB2_LIB.BASEBOARD_FAB2(SCH_1):PAGE176_I137@MSTR_DISCRETE.RES(CHIPS)':
 'A': CDS_PINID='A';
NET_NAME
'FM_CPU0_AND_CPU1_MCP_PRES'
 '@BASEBOARD_FAB2_LIB.BASEBOARD_FAB2(SCH_1):FM_CPU0_AND_CPU1_MCP_PRES':
 C_SIGNAL='@baseboard_fab2_lib.baseboard_fab2(sch_1):fm_cpu0_and_cpu1_mcp_pres';
NODE_NAME     U1M6 1
 '@BASEBOARD_FAB2_LIB.BASEBOARD_FAB2(SCH_1):PAGE113_I127@MSTR_TTL.74CBTLV1G125(CHIPS)':
 'OE_N': CDS_PINID='OE_N';
NODE_NAME     U8D7 D11
 '@BASEBOARD_FAB2_LIB.BASEBOARD_FAB2(SCH_1):PAGE191_I59@MSTR_MEMORY.LCMXO2_A(CHIPS)':
 'PT21D': CDS_PINID='PT21D';
NET_NAME
'FM_CPU0_CD_PRES'
 '@BASEBOARD_FAB2_LIB.BASEBOARD_FAB2(SCH_1):FM_CPU0_CD_PRES':
 C_SIGNAL='@baseboard_fab2_lib.baseboard_fab2(sch_1):fm_cpu0_cd_pres';
NODE_NAME     U2M1 6
 '@BASEBOARD_FAB2_LIB.BASEBOARD_FAB2(SCH_1):PAGE113_I255@MSTR_ANALOG.NC7SB3157(CHIPS)':
 'S': CDS_PINID='S';
NODE_NAME     U8D7 C11
 '@BASEBOARD_FAB2_LIB.BASEBOARD_FAB2(SCH_1):PAGE191_I59@MSTR_MEMORY.LCMXO2_A(CHIPS)':
 'PT21B': CDS_PINID='PT21B';
NET_NAME
'FM_CPU0_FIVR_FAULT_LVT3'
 '@BASEBOARD_FAB2_LIB.BASEBOARD_FAB2(SCH_1):FM_CPU0_FIVR_FAULT_LVT3':
 C_SIGNAL='@baseboard_fab2_lib.baseboard_fab2(sch_1):fm_cpu0_fivr_fault_lvt3';
NODE_NAME     R7D29 2
 '@BASEBOARD_FAB2_LIB.BASEBOARD_FAB2(SCH_1):PAGE92_I30@MSTR_DISCRETE.RES(CHIPS)':
 'B': CDS_PINID='B';
NODE_NAME     U8D7 M16
 '@BASEBOARD_FAB2_LIB.BASEBOARD_FAB2(SCH_1):PAGE191_I59@MSTR_MEMORY.LCMXO2_A(CHIPS)':
 'PR12B': CDS_PINID='PR12B';
NET_NAME
'FM_CPU0_FIVR_FAULT_LVT3_N'
 '@BASEBOARD_FAB2_LIB.BASEBOARD_FAB2(SCH_1):FM_CPU0_FIVR_FAULT_LVT3_N':
 C_SIGNAL='@baseboard_fab2_lib.baseboard_fab2(sch_1):fm_cpu0_fivr_fault_lvt3_n';
NODE_NAME     U8D7 F5
 '@BASEBOARD_FAB2_LIB.BASEBOARD_FAB2(SCH_1):PAGE190_I179@MSTR_MEMORY.LCMXO2_A(CHIPS)':
 'PL5C': CDS_PINID='PL5C';
NODE_NAME     R25W70 2
 '@BASEBOARD_FAB2_LIB.BASEBOARD_FAB2(SCH_1):PAGE144_I114@MSTR_DISCRETE.RES(CHIPS)':
 'B': CDS_PINID='B';
NET_NAME
'FM_CPU0_FIVR_FAULT_LVT3_R_N'
 '@BASEBOARD_FAB2_LIB.BASEBOARD_FAB2(SCH_1):FM_CPU0_FIVR_FAULT_LVT3_R_N':
 C_SIGNAL='@baseboard_fab2_lib.baseboard_fab2(sch_1):fm_cpu0_fivr_fault_lvt3_r_n~
';
NODE_NAME     U25W4 C18
 '@BASEBOARD_FAB2_LIB.BASEBOARD_FAB2(SCH_1):PAGE144_I95@W_HDL.AST2520A1-GP-GP(CHIPS)':
 'GPIOI0_SYSCS#': CDS_PINID='\gpioi0_syscs#\';
NODE_NAME     R25W70 1
 '@BASEBOARD_FAB2_LIB.BASEBOARD_FAB2(SCH_1):PAGE144_I114@MSTR_DISCRETE.RES(CHIPS)':
 'A': CDS_PINID='A';
NET_NAME
'FM_CPU0_FIVR_FAULT_R_LVT3'
 '@BASEBOARD_FAB2_LIB.BASEBOARD_FAB2(SCH_1):FM_CPU0_FIVR_FAULT_R_LVT3':
 C_SIGNAL='@baseboard_fab2_lib.baseboard_fab2(sch_1):fm_cpu0_fivr_fault_r_lvt3';
NODE_NAME     R7D29 1
 '@BASEBOARD_FAB2_LIB.BASEBOARD_FAB2(SCH_1):PAGE92_I30@MSTR_DISCRETE.RES(CHIPS)':
 'A': CDS_PINID='A';
NODE_NAME     U7D2 12
 '@BASEBOARD_FAB2_LIB.BASEBOARD_FAB2(SCH_1):PAGE92_I32@MSTR_DIGITAL.GTL2014(CHIPS)':
 'A1': CDS_PINID='A1';
NET_NAME
'FM_CPU0_MCP_CLK_EN_N'
 '@BASEBOARD_FAB2_LIB.BASEBOARD_FAB2(SCH_1):FM_CPU0_MCP_CLK_EN_N':
 C_SIGNAL='@baseboard_fab2_lib.baseboard_fab2(sch_1):fm_cpu0_mcp_clk_en_n';
NODE_NAME     EU4D2 29
 '@BASEBOARD_FAB2_LIB.BASEBOARD_FAB2(SCH_1):PAGE102_I1@MSTR_CLOCK.NB3W1200L(CHIPS)':
 'OE_3_N': CDS_PINID='OE_3_N';
NODE_NAME     EU4D2 36
 '@BASEBOARD_FAB2_LIB.BASEBOARD_FAB2(SCH_1):PAGE102_I1@MSTR_CLOCK.NB3W1200L(CHIPS)':
 'OE_4_N': CDS_PINID='OE_4_N';
NODE_NAME     EU4D2 37
 '@BASEBOARD_FAB2_LIB.BASEBOARD_FAB2(SCH_1):PAGE102_I1@MSTR_CLOCK.NB3W1200L(CHIPS)':
 'OE_5_N': CDS_PINID='OE_5_N';
NODE_NAME     R4D70 2
 '@BASEBOARD_FAB2_LIB.BASEBOARD_FAB2(SCH_1):PAGE102_I94@MSTR_DISCRETE.RES(CHIPS)':
 'B': CDS_PINID='B';
NODE_NAME     U8D7 F15
 '@BASEBOARD_FAB2_LIB.BASEBOARD_FAB2(SCH_1):PAGE191_I59@MSTR_MEMORY.LCMXO2_A(CHIPS)':
 'PR3B': CDS_PINID='PR3B';
NET_NAME
'FM_CPU0_OR_CPU1_MCP_PRES'
 '@BASEBOARD_FAB2_LIB.BASEBOARD_FAB2(SCH_1):FM_CPU0_OR_CPU1_MCP_PRES':
 C_SIGNAL='@baseboard_fab2_lib.baseboard_fab2(sch_1):fm_cpu0_or_cpu1_mcp_pres';
NODE_NAME     U9A5 1
 '@BASEBOARD_FAB2_LIB.BASEBOARD_FAB2(SCH_1):PAGE113_I185@MSTR_TTL.74CBTLV1G125(CHIPS)':
 'OE_N': CDS_PINID='OE_N';
NODE_NAME     U1M5 1
 '@BASEBOARD_FAB2_LIB.BASEBOARD_FAB2(SCH_1):PAGE113_I196@MSTR_TTL.74CBTLV1G125(CHIPS)':
 'OE_N': CDS_PINID='OE_N';
NODE_NAME     U8D7 A11
 '@BASEBOARD_FAB2_LIB.BASEBOARD_FAB2(SCH_1):PAGE191_I59@MSTR_MEMORY.LCMXO2_A(CHIPS)':
 'PT21A': CDS_PINID='PT21A';
NET_NAME
'FM_CPU0_PKGID0'
 '@BASEBOARD_FAB2_LIB.BASEBOARD_FAB2(SCH_1):FM_CPU0_PKGID0':
 C_SIGNAL='@baseboard_fab2_lib.baseboard_fab2(sch_1):fm_cpu0_pkgid0';
NODE_NAME     R5N1 2
 '@BASEBOARD_FAB2_LIB.BASEBOARD_FAB2(SCH_1):PAGE21_I238@MSTR_DISCRETE.RES(CHIPS)':
 'B': CDS_PINID='B';
NODE_NAME     U5D1 DC72
 '@BASEBOARD_FAB2_LIB.BASEBOARD_FAB2(SCH_1):PAGE21_I259@CHPSET_LIB.SKX_EXT_B(CHIPS)':
 'PKGID'<0>: CDS_PINID='PKGID(0)';
NODE_NAME     U8D7 F2
 '@BASEBOARD_FAB2_LIB.BASEBOARD_FAB2(SCH_1):PAGE190_I179@MSTR_MEMORY.LCMXO2_A(CHIPS)':
 'PL3B_PCLKC5_0': CDS_PINID='PL3B_PCLKC5_0';
NET_NAME
'FM_CPU0_PKGID1'
 '@BASEBOARD_FAB2_LIB.BASEBOARD_FAB2(SCH_1):FM_CPU0_PKGID1':
 C_SIGNAL='@baseboard_fab2_lib.baseboard_fab2(sch_1):fm_cpu0_pkgid1';
NODE_NAME     R5N5 2
 '@BASEBOARD_FAB2_LIB.BASEBOARD_FAB2(SCH_1):PAGE21_I239@MSTR_DISCRETE.RES(CHIPS)':
 'B': CDS_PINID='B';
NODE_NAME     U5D1 CW72
 '@BASEBOARD_FAB2_LIB.BASEBOARD_FAB2(SCH_1):PAGE21_I259@CHPSET_LIB.SKX_EXT_B(CHIPS)':
 'PKGID'<1>: CDS_PINID='PKGID(1)';
NODE_NAME     U4R1 1
 '@BASEBOARD_FAB2_LIB.BASEBOARD_FAB2(SCH_1):PAGE113_I206@MSTR_TTL.74CBTLV1G125(CHIPS)':
 'OE_N': CDS_PINID='OE_N';
NODE_NAME     U8D7 G3
 '@BASEBOARD_FAB2_LIB.BASEBOARD_FAB2(SCH_1):PAGE190_I179@MSTR_MEMORY.LCMXO2_A(CHIPS)':
 'PL5B': CDS_PINID='PL5B';
NET_NAME
'FM_CPU0_PKGID2'
 '@BASEBOARD_FAB2_LIB.BASEBOARD_FAB2(SCH_1):FM_CPU0_PKGID2':
 C_SIGNAL='@baseboard_fab2_lib.baseboard_fab2(sch_1):fm_cpu0_pkgid2';
NODE_NAME     R5N3 2
 '@BASEBOARD_FAB2_LIB.BASEBOARD_FAB2(SCH_1):PAGE21_I240@MSTR_DISCRETE.RES(CHIPS)':
 'B': CDS_PINID='B';
NODE_NAME     U5D1 DA72
 '@BASEBOARD_FAB2_LIB.BASEBOARD_FAB2(SCH_1):PAGE21_I259@CHPSET_LIB.SKX_EXT_B(CHIPS)':
 'PKGID'<2>: CDS_PINID='PKGID(2)';
NODE_NAME     U8D7 G2
 '@BASEBOARD_FAB2_LIB.BASEBOARD_FAB2(SCH_1):PAGE190_I179@MSTR_MEMORY.LCMXO2_A(CHIPS)':
 'PL5A': CDS_PINID='PL5A';
NET_NAME
'FM_CPU0_PROCHOT_LVT3_BMC_N'
 '@BASEBOARD_FAB2_LIB.BASEBOARD_FAB2(SCH_1):FM_CPU0_PROCHOT_LVT3_BMC_N':
 C_SIGNAL='@baseboard_fab2_lib.baseboard_fab2(sch_1):fm_cpu0_prochot_lvt3_bmc_n';
NODE_NAME     R1T36 2
 '@BASEBOARD_FAB2_LIB.BASEBOARD_FAB2(SCH_1):PAGE93_I122@MSTR_DISCRETE.RES(CHIPS)':
 'B': CDS_PINID='B';
NODE_NAME     U25W4 A20
 '@BASEBOARD_FAB2_LIB.BASEBOARD_FAB2(SCH_1):PAGE145_I117@W_HDL.AST2520A1-GP-GP(CHIPS)':
 'GPIOE6_TXD3': CDS_PINID='GPIOE6_TXD3';
NET_NAME
'FM_CPU0_PROCHOT_LVT3_K_N'
 '@BASEBOARD_FAB2_LIB.BASEBOARD_FAB2(SCH_1):FM_CPU0_PROCHOT_LVT3_K_N':
 C_SIGNAL='@baseboard_fab2_lib.baseboard_fab2(sch_1):fm_cpu0_prochot_lvt3_k_n';
NODE_NAME     R2T38 1
 '@BASEBOARD_FAB2_LIB.BASEBOARD_FAB2(SCH_1):PAGE93_I39@MSTR_DISCRETE.RES(CHIPS)':
 'A': CDS_PINID='A';
NODE_NAME     R2T71 1
 '@BASEBOARD_FAB2_LIB.BASEBOARD_FAB2(SCH_1):PAGE93_I109@MSTR_DISCRETE.RES(CHIPS)':
 'A': CDS_PINID='A';
NODE_NAME     R2T67 2
 '@BASEBOARD_FAB2_LIB.BASEBOARD_FAB2(SCH_1):PAGE93_I113@MSTR_DISCRETE.RES(CHIPS)':
 'B': CDS_PINID='B';
NET_NAME
'FM_CPU0_PROCHOT_LVT3_N'
 '@BASEBOARD_FAB2_LIB.BASEBOARD_FAB2(SCH_1):FM_CPU0_PROCHOT_LVT3_N':
 C_SIGNAL='@baseboard_fab2_lib.baseboard_fab2(sch_1):fm_cpu0_prochot_lvt3_n';
NODE_NAME     R2T38 2
 '@BASEBOARD_FAB2_LIB.BASEBOARD_FAB2(SCH_1):PAGE93_I39@MSTR_DISCRETE.RES(CHIPS)':
 'B': CDS_PINID='B';
NODE_NAME     R1T36 1
 '@BASEBOARD_FAB2_LIB.BASEBOARD_FAB2(SCH_1):PAGE93_I122@MSTR_DISCRETE.RES(CHIPS)':
 'A': CDS_PINID='A';
NODE_NAME     R1T35 1
 '@BASEBOARD_FAB2_LIB.BASEBOARD_FAB2(SCH_1):PAGE93_I135@MSTR_DISCRETE.RES(CHIPS)':
 'A': CDS_PINID='A';
NET_NAME
'FM_CPU0_PROCHOT_LVT3_R_N'
 '@BASEBOARD_FAB2_LIB.BASEBOARD_FAB2(SCH_1):FM_CPU0_PROCHOT_LVT3_R_N':
 C_SIGNAL='@baseboard_fab2_lib.baseboard_fab2(sch_1):fm_cpu0_prochot_lvt3_r_n';
NODE_NAME     U2T4 12
 '@BASEBOARD_FAB2_LIB.BASEBOARD_FAB2(SCH_1):PAGE93_I30@MSTR_DIGITAL.GTL2014(CHIPS)':
 'A1': CDS_PINID='A1';
NODE_NAME     R2T67 1
 '@BASEBOARD_FAB2_LIB.BASEBOARD_FAB2(SCH_1):PAGE93_I113@MSTR_DISCRETE.RES(CHIPS)':
 'A': CDS_PINID='A';
NET_NAME
'FM_CPU0_PROCHOT_PCH_N'
 '@BASEBOARD_FAB2_LIB.BASEBOARD_FAB2(SCH_1):FM_CPU0_PROCHOT_PCH_N':
 C_SIGNAL='@baseboard_fab2_lib.baseboard_fab2(sch_1):fm_cpu0_prochot_pch_n';
NODE_NAME     R1T35 2
 '@BASEBOARD_FAB2_LIB.BASEBOARD_FAB2(SCH_1):PAGE93_I135@MSTR_DISCRETE.RES(CHIPS)':
 'B': CDS_PINID='B';
NODE_NAME     U7C1 Y7
 '@BASEBOARD_FAB2_LIB.BASEBOARD_FAB2(SCH_1):PAGE121_I34@MSTR_U_PROC.LBG_CORE_QAT_EXT_D(CHIPS)':
 'GPP_L16_TESTCH1_D5': CDS_PINID='GPP_L16_TESTCH1_D5';
NET_NAME
'FM_CPU0_PROC_ID0'
 '@BASEBOARD_FAB2_LIB.BASEBOARD_FAB2(SCH_1):FM_CPU0_PROC_ID0':
 C_SIGNAL='@baseboard_fab2_lib.baseboard_fab2(sch_1):fm_cpu0_proc_id0';
NODE_NAME     R5N4 2
 '@BASEBOARD_FAB2_LIB.BASEBOARD_FAB2(SCH_1):PAGE21_I241@MSTR_DISCRETE.RES(CHIPS)':
 'B': CDS_PINID='B';
NODE_NAME     U5D1 CY71
 '@BASEBOARD_FAB2_LIB.BASEBOARD_FAB2(SCH_1):PAGE21_I259@CHPSET_LIB.SKX_EXT_B(CHIPS)':
 'PROC_ID'<0>: CDS_PINID='PROC_ID(0)';
NODE_NAME     U8D7 F1
 '@BASEBOARD_FAB2_LIB.BASEBOARD_FAB2(SCH_1):PAGE190_I179@MSTR_MEMORY.LCMXO2_A(CHIPS)':
 'PL4B': CDS_PINID='PL4B';
NET_NAME
'FM_CPU0_PROC_ID1'
 '@BASEBOARD_FAB2_LIB.BASEBOARD_FAB2(SCH_1):FM_CPU0_PROC_ID1':
 C_SIGNAL='@baseboard_fab2_lib.baseboard_fab2(sch_1):fm_cpu0_proc_id1';
NODE_NAME     R5N2 2
 '@BASEBOARD_FAB2_LIB.BASEBOARD_FAB2(SCH_1):PAGE21_I227@MSTR_DISCRETE.RES(CHIPS)':
 'B': CDS_PINID='B';
NODE_NAME     U5D1 DB71
 '@BASEBOARD_FAB2_LIB.BASEBOARD_FAB2(SCH_1):PAGE21_I259@CHPSET_LIB.SKX_EXT_B(CHIPS)':
 'PROC_ID'<1>: CDS_PINID='PROC_ID(1)';
NODE_NAME     U8D7 F3
 '@BASEBOARD_FAB2_LIB.BASEBOARD_FAB2(SCH_1):PAGE190_I179@MSTR_MEMORY.LCMXO2_A(CHIPS)':
 'PL4A': CDS_PINID='PL4A';
NET_NAME
'FM_CPU0_RC_EN'
 '@BASEBOARD_FAB2_LIB.BASEBOARD_FAB2(SCH_1):FM_CPU0_RC_EN':
 C_SIGNAL='@baseboard_fab2_lib.baseboard_fab2(sch_1):fm_cpu0_rc_en';
NODE_NAME     U7C1 BD20
 '@BASEBOARD_FAB2_LIB.BASEBOARD_FAB2(SCH_1):PAGE120_I147@MSTR_U_PROC.LBG_CORE_QAT_EXT_D(CHIPS)':
 'GPP_G22_SSATA_DEVSLP2': CDS_PINID='GPP_G22_SSATA_DEVSLP2';
NODE_NAME     R8D44 2
 '@BASEBOARD_FAB2_LIB.BASEBOARD_FAB2(SCH_1):PAGE133_I362@MSTR_DISCRETE.RES(CHIPS)':
 'B': CDS_PINID='B';
NODE_NAME     U8D7 R3
 '@BASEBOARD_FAB2_LIB.BASEBOARD_FAB2(SCH_1):PAGE190_I179@MSTR_MEMORY.LCMXO2_A(CHIPS)':
 'PB3D': CDS_PINID='PB3D';
NET_NAME
'FM_CPU0_RC_ERROR_N'
 '@BASEBOARD_FAB2_LIB.BASEBOARD_FAB2(SCH_1):FM_CPU0_RC_ERROR_N':
 C_SIGNAL='@baseboard_fab2_lib.baseboard_fab2(sch_1):fm_cpu0_rc_error_n';
NODE_NAME     U5D1 Y23
 '@BASEBOARD_FAB2_LIB.BASEBOARD_FAB2(SCH_1):PAGE22_I204@CHPSET_LIB.SKX_EXT_B(CHIPS)':
 'RSVD'<257>: CDS_PINID='RSVD(257)';
NODE_NAME     R2M8 2
 '@BASEBOARD_FAB2_LIB.BASEBOARD_FAB2(SCH_1):PAGE133_I349@MSTR_DISCRETE.RES(CHIPS)':
 'B': CDS_PINID='B';
NODE_NAME     U25W4 Y1
 '@BASEBOARD_FAB2_LIB.BASEBOARD_FAB2(SCH_1):PAGE145_I117@W_HDL.AST2520A1-GP-GP(CHIPS)':
 'GPIOM0_NCTS2_VPIB2': CDS_PINID='GPIOM0_NCTS2_VPIB2';
NODE_NAME     R7W9 1
 '@BASEBOARD_FAB2_LIB.BASEBOARD_FAB2(SCH_1):PAGE118_I177@MSTR_DISCRETE.RES(CHIPS)':
 'A': CDS_PINID='A';
NODE_NAME     R7W10 1
 '@BASEBOARD_FAB2_LIB.BASEBOARD_FAB2(SCH_1):PAGE120_I270@MSTR_DISCRETE.RES(CHIPS)':
 'A': CDS_PINID='A';
NET_NAME
'FM_CPU0_RC_ERROR_R1_N'
 '@BASEBOARD_FAB2_LIB.BASEBOARD_FAB2(SCH_1):FM_CPU0_RC_ERROR_R1_N':
 C_SIGNAL='@baseboard_fab2_lib.baseboard_fab2(sch_1):fm_cpu0_rc_error_r1_n';
NODE_NAME     U7C1 BH50
 '@BASEBOARD_FAB2_LIB.BASEBOARD_FAB2(SCH_1):PAGE120_I147@MSTR_U_PROC.LBG_CORE_QAT_EXT_D(CHIPS)':
 'GPP_E0_SATAXPCIE0_SATAGP0': CDS_PINID='GPP_E0_SATAXPCIE0_SATAGP0';
NODE_NAME     R7W10 2
 '@BASEBOARD_FAB2_LIB.BASEBOARD_FAB2(SCH_1):PAGE120_I270@MSTR_DISCRETE.RES(CHIPS)':
 'B': CDS_PINID='B';
NET_NAME
'FM_CPU0_RC_ERROR_R_N'
 '@BASEBOARD_FAB2_LIB.BASEBOARD_FAB2(SCH_1):FM_CPU0_RC_ERROR_R_N':
 C_SIGNAL='@baseboard_fab2_lib.baseboard_fab2(sch_1):fm_cpu0_rc_error_r_n';
NODE_NAME     U7C1 B14
 '@BASEBOARD_FAB2_LIB.BASEBOARD_FAB2(SCH_1):PAGE118_I73@MSTR_U_PROC.LBG_CORE_QAT_EXT_D(CHIPS)':
 'GPD10_SLP_S5_N': CDS_PINID='GPD10_SLP_S5_N';
NODE_NAME     R7W9 2
 '@BASEBOARD_FAB2_LIB.BASEBOARD_FAB2(SCH_1):PAGE118_I177@MSTR_DISCRETE.RES(CHIPS)':
 'B': CDS_PINID='B';
NET_NAME
'FM_CPU0_SKTOCC_LVT3_N'
 '@BASEBOARD_FAB2_LIB.BASEBOARD_FAB2(SCH_1):FM_CPU0_SKTOCC_LVT3_N':
 C_SIGNAL='@baseboard_fab2_lib.baseboard_fab2(sch_1):fm_cpu0_sktocc_lvt3_n';
NODE_NAME     R4R5 2
 '@BASEBOARD_FAB2_LIB.BASEBOARD_FAB2(SCH_1):PAGE21_I258@MSTR_DISCRETE.RES(CHIPS)':
 'B': CDS_PINID='B';
NODE_NAME     U5D1 AB13
 '@BASEBOARD_FAB2_LIB.BASEBOARD_FAB2(SCH_1):PAGE21_I259@CHPSET_LIB.SKX_EXT_B(CHIPS)':
 'SKTOCC_N': CDS_PINID='SKTOCC_N';
NODE_NAME     U7C1 G11
 '@BASEBOARD_FAB2_LIB.BASEBOARD_FAB2(SCH_1):PAGE118_I73@MSTR_U_PROC.LBG_CORE_QAT_EXT_D(CHIPS)':
 'GPD6_SLP_A_N': CDS_PINID='GPD6_SLP_A_N';
NODE_NAME     U8D7 T14
 '@BASEBOARD_FAB2_LIB.BASEBOARD_FAB2(SCH_1):PAGE190_I179@MSTR_MEMORY.LCMXO2_A(CHIPS)':
 'PB22D': CDS_PINID='PB22D';
NODE_NAME     U25W4 E16
 '@BASEBOARD_FAB2_LIB.BASEBOARD_FAB2(SCH_1):PAGE144_I95@W_HDL.AST2520A1-GP-GP(CHIPS)':
 'GPIOG3_SGPS1I1': CDS_PINID='GPIOG3_SGPS1I1';
NET_NAME
'FM_CPU0_SM_WP'
 '@BASEBOARD_FAB2_LIB.BASEBOARD_FAB2(SCH_1):FM_CPU0_SM_WP':
 C_SIGNAL='@baseboard_fab2_lib.baseboard_fab2(sch_1):fm_cpu0_sm_wp';
NODE_NAME     U5D1 CV59
 '@BASEBOARD_FAB2_LIB.BASEBOARD_FAB2(SCH_1):PAGE21_I259@CHPSET_LIB.SKX_EXT_B(CHIPS)':
 'SM_WP': CDS_PINID='SM_WP';
NODE_NAME     R3P54 2
 '@BASEBOARD_FAB2_LIB.BASEBOARD_FAB2(SCH_1):PAGE156_I331@MSTR_DISCRETE.RES(CHIPS)':
 'B': CDS_PINID='B';
NODE_NAME     R3P56 1
 '@BASEBOARD_FAB2_LIB.BASEBOARD_FAB2(SCH_1):PAGE156_I333@MSTR_DISCRETE.RES(CHIPS)':
 'A': CDS_PINID='A';
NET_NAME
'FM_CPU0_STL_BRD_OSC_EN'
 '@BASEBOARD_FAB2_LIB.BASEBOARD_FAB2(SCH_1):FM_CPU0_STL_BRD_OSC_EN':
 C_SIGNAL='@baseboard_fab2_lib.baseboard_fab2(sch_1):fm_cpu0_stl_brd_osc_en';
NODE_NAME     Y6F1 1
 '@BASEBOARD_FAB2_LIB.BASEBOARD_FAB2(SCH_1):PAGE104_I71@MSTR_DISCRETE.OSC_C(CHIPS)':
 'ENABLE_DISABLE': CDS_PINID='ENABLE_DISABLE';
NODE_NAME     R8D43 2
 '@BASEBOARD_FAB2_LIB.BASEBOARD_FAB2(SCH_1):PAGE104_I93@MSTR_DISCRETE.RES(CHIPS)':
 'B': CDS_PINID='B';
NODE_NAME     R7D40 2
 '@BASEBOARD_FAB2_LIB.BASEBOARD_FAB2(SCH_1):PAGE104_I94@MSTR_DISCRETE.RES(CHIPS)':
 'B': CDS_PINID='B';
NET_NAME
'FM_CPU0_THERMTRIP_LATCH_LVT3_N'
 '@BASEBOARD_FAB2_LIB.BASEBOARD_FAB2(SCH_1):FM_CPU0_THERMTRIP_LATCH_LVT3_N':
 C_SIGNAL='@baseboard_fab2_lib.baseboard_fab2(sch_1):fm_cpu0_thermtrip_latch_lvt~
3_n';
NODE_NAME     U7C1 BN44
 '@BASEBOARD_FAB2_LIB.BASEBOARD_FAB2(SCH_1):PAGE119_I115@MSTR_U_PROC.LBG_CORE_QAT_EXT_D(CHIPS)':
 'GPP_D23': CDS_PINID='GPP_D23';
NODE_NAME     U8D7 G12
 '@BASEBOARD_FAB2_LIB.BASEBOARD_FAB2(SCH_1):PAGE191_I59@MSTR_MEMORY.LCMXO2_A(CHIPS)':
 'PR3D': CDS_PINID='PR3D';
NODE_NAME     U25W4 AA2
 '@BASEBOARD_FAB2_LIB.BASEBOARD_FAB2(SCH_1):PAGE145_I117@W_HDL.AST2520A1-GP-GP(CHIPS)':
 'GPIOM4_NDTR2_VPIB6': CDS_PINID='GPIOM4_NDTR2_VPIB6';
NET_NAME
'FM_CPU0_THERMTRIP_LVT3_N'
 '@BASEBOARD_FAB2_LIB.BASEBOARD_FAB2(SCH_1):FM_CPU0_THERMTRIP_LVT3_N':
 C_SIGNAL='@baseboard_fab2_lib.baseboard_fab2(sch_1):fm_cpu0_thermtrip_lvt3_n';
NODE_NAME     R7D34 2
 '@BASEBOARD_FAB2_LIB.BASEBOARD_FAB2(SCH_1):PAGE92_I24@MSTR_DISCRETE.RES(CHIPS)':
 'B': CDS_PINID='B';
NODE_NAME     U8D7 N15
 '@BASEBOARD_FAB2_LIB.BASEBOARD_FAB2(SCH_1):PAGE191_I59@MSTR_MEMORY.LCMXO2_A(CHIPS)':
 'PR13C': CDS_PINID='PR13C';
NET_NAME
'FM_CPU0_THERMTRIP_LVT3_R_N'
 '@BASEBOARD_FAB2_LIB.BASEBOARD_FAB2(SCH_1):FM_CPU0_THERMTRIP_LVT3_R_N':
 C_SIGNAL='@baseboard_fab2_lib.baseboard_fab2(sch_1):fm_cpu0_thermtrip_lvt3_r_n';
NODE_NAME     R7D34 1
 '@BASEBOARD_FAB2_LIB.BASEBOARD_FAB2(SCH_1):PAGE92_I24@MSTR_DISCRETE.RES(CHIPS)':
 'A': CDS_PINID='A';
NODE_NAME     U7D2 9
 '@BASEBOARD_FAB2_LIB.BASEBOARD_FAB2(SCH_1):PAGE92_I32@MSTR_DIGITAL.GTL2014(CHIPS)':
 'A3': CDS_PINID='A3';
NET_NAME
'FM_CPU0_VRM_322M_156M_OSC_EN'
 '@BASEBOARD_FAB2_LIB.BASEBOARD_FAB2(SCH_1):FM_CPU0_VRM_322M_156M_OSC_EN':
 C_SIGNAL='@baseboard_fab2_lib.baseboard_fab2(sch_1):fm_cpu0_vrm_322m_156m_osc_e~
n';
NODE_NAME     J6B1 E1
 '@BASEBOARD_FAB2_LIB.BASEBOARD_FAB2(SCH_1):PAGE194_I56@MSTR_SCONN.SCONN120_H61426002(CHIPS)':
 'IOE1': CDS_PINID='IOE1';
NODE_NAME     R7D39 2
 '@BASEBOARD_FAB2_LIB.BASEBOARD_FAB2(SCH_1):PAGE104_I103@MSTR_DISCRETE.RES(CHIPS)':
 'B': CDS_PINID='B';
NET_NAME
'FM_CPU0_VRM_OSC_EN'
 '@BASEBOARD_FAB2_LIB.BASEBOARD_FAB2(SCH_1):FM_CPU0_VRM_OSC_EN':
 C_SIGNAL='@baseboard_fab2_lib.baseboard_fab2(sch_1):fm_cpu0_vrm_osc_en';
NODE_NAME     R7D40 1
 '@BASEBOARD_FAB2_LIB.BASEBOARD_FAB2(SCH_1):PAGE104_I94@MSTR_DISCRETE.RES(CHIPS)':
 'A': CDS_PINID='A';
NODE_NAME     U8D7 R13
 '@BASEBOARD_FAB2_LIB.BASEBOARD_FAB2(SCH_1):PAGE190_I179@MSTR_MEMORY.LCMXO2_A(CHIPS)':
 'PB22C': CDS_PINID='PB22C';
NODE_NAME     R7D39 1
 '@BASEBOARD_FAB2_LIB.BASEBOARD_FAB2(SCH_1):PAGE104_I103@MSTR_DISCRETE.RES(CHIPS)':
 'A': CDS_PINID='A';
NET_NAME
'FM_CPU1_CD_PRES_N'
 '@BASEBOARD_FAB2_LIB.BASEBOARD_FAB2(SCH_1):FM_CPU1_CD_PRES_N':
 C_SIGNAL='@baseboard_fab2_lib.baseboard_fab2(sch_1):fm_cpu1_cd_pres_n';
NODE_NAME     U1M2 6
 '@BASEBOARD_FAB2_LIB.BASEBOARD_FAB2(SCH_1):PAGE113_I107@MSTR_ANALOG.NC7SB3157(CHIPS)':
 'S': CDS_PINID='S';
NODE_NAME     U8D7 F10
 '@BASEBOARD_FAB2_LIB.BASEBOARD_FAB2(SCH_1):PAGE191_I59@MSTR_MEMORY.LCMXO2_A(CHIPS)':
 'PT21C': CDS_PINID='PT21C';
NET_NAME
'FM_CPU1_FIVR_FAULT_LVT3'
 '@BASEBOARD_FAB2_LIB.BASEBOARD_FAB2(SCH_1):FM_CPU1_FIVR_FAULT_LVT3':
 C_SIGNAL='@baseboard_fab2_lib.baseboard_fab2(sch_1):fm_cpu1_fivr_fault_lvt3';
NODE_NAME     R3P46 2
 '@BASEBOARD_FAB2_LIB.BASEBOARD_FAB2(SCH_1):PAGE92_I12@MSTR_DISCRETE.RES(CHIPS)':
 'B': CDS_PINID='B';
NODE_NAME     U8D7 G13
 '@BASEBOARD_FAB2_LIB.BASEBOARD_FAB2(SCH_1):PAGE191_I59@MSTR_MEMORY.LCMXO2_A(CHIPS)':
 'PR4D': CDS_PINID='PR4D';
NET_NAME
'FM_CPU1_FIVR_FAULT_LVT3_N'
 '@BASEBOARD_FAB2_LIB.BASEBOARD_FAB2(SCH_1):FM_CPU1_FIVR_FAULT_LVT3_N':
 C_SIGNAL='@baseboard_fab2_lib.baseboard_fab2(sch_1):fm_cpu1_fivr_fault_lvt3_n';
NODE_NAME     U8D7 E6
 '@BASEBOARD_FAB2_LIB.BASEBOARD_FAB2(SCH_1):PAGE191_I59@MSTR_MEMORY.LCMXO2_A(CHIPS)':
 'PT13C': CDS_PINID='PT13C';
NODE_NAME     R25W75 2
 '@BASEBOARD_FAB2_LIB.BASEBOARD_FAB2(SCH_1):PAGE144_I118@MSTR_DISCRETE.RES(CHIPS)':
 'B': CDS_PINID='B';
NET_NAME
'FM_CPU1_FIVR_FAULT_LVT3_R_N'
 '@BASEBOARD_FAB2_LIB.BASEBOARD_FAB2(SCH_1):FM_CPU1_FIVR_FAULT_LVT3_R_N':
 C_SIGNAL='@baseboard_fab2_lib.baseboard_fab2(sch_1):fm_cpu1_fivr_fault_lvt3_r_n~
';
NODE_NAME     U25W4 E15
 '@BASEBOARD_FAB2_LIB.BASEBOARD_FAB2(SCH_1):PAGE144_I95@W_HDL.AST2520A1-GP-GP(CHIPS)':
 'GPIOI1_SYSCK': CDS_PINID='GPIOI1_SYSCK';
NODE_NAME     R25W75 1
 '@BASEBOARD_FAB2_LIB.BASEBOARD_FAB2(SCH_1):PAGE144_I118@MSTR_DISCRETE.RES(CHIPS)':
 'A': CDS_PINID='A';
NET_NAME
'FM_CPU1_FIVR_FAULT_R_LVT3'
 '@BASEBOARD_FAB2_LIB.BASEBOARD_FAB2(SCH_1):FM_CPU1_FIVR_FAULT_R_LVT3':
 C_SIGNAL='@baseboard_fab2_lib.baseboard_fab2(sch_1):fm_cpu1_fivr_fault_r_lvt3';
NODE_NAME     U3P2 12
 '@BASEBOARD_FAB2_LIB.BASEBOARD_FAB2(SCH_1):PAGE92_I1@MSTR_DIGITAL.GTL2014(CHIPS)':
 'A1': CDS_PINID='A1';
NODE_NAME     R3P46 1
 '@BASEBOARD_FAB2_LIB.BASEBOARD_FAB2(SCH_1):PAGE92_I12@MSTR_DISCRETE.RES(CHIPS)':
 'A': CDS_PINID='A';
NET_NAME
'FM_CPU1_MCP_CLK_EN_N'
 '@BASEBOARD_FAB2_LIB.BASEBOARD_FAB2(SCH_1):FM_CPU1_MCP_CLK_EN_N':
 C_SIGNAL='@baseboard_fab2_lib.baseboard_fab2(sch_1):fm_cpu1_mcp_clk_en_n';
NODE_NAME     EU4D2 53
 '@BASEBOARD_FAB2_LIB.BASEBOARD_FAB2(SCH_1):PAGE102_I1@MSTR_CLOCK.NB3W1200L(CHIPS)':
 'OE_9_N': CDS_PINID='OE_9_N';
NODE_NAME     EU4D2 61
 '@BASEBOARD_FAB2_LIB.BASEBOARD_FAB2(SCH_1):PAGE102_I1@MSTR_CLOCK.NB3W1200L(CHIPS)':
 'OE_10_N': CDS_PINID='OE_10_N';
NODE_NAME     EU4D2 62
 '@BASEBOARD_FAB2_LIB.BASEBOARD_FAB2(SCH_1):PAGE102_I1@MSTR_CLOCK.NB3W1200L(CHIPS)':
 'OE_11_N': CDS_PINID='OE_11_N';
NODE_NAME     R4D69 2
 '@BASEBOARD_FAB2_LIB.BASEBOARD_FAB2(SCH_1):PAGE102_I93@MSTR_DISCRETE.RES(CHIPS)':
 'B': CDS_PINID='B';
NODE_NAME     U8D7 F16
 '@BASEBOARD_FAB2_LIB.BASEBOARD_FAB2(SCH_1):PAGE191_I59@MSTR_MEMORY.LCMXO2_A(CHIPS)':
 'PR4B': CDS_PINID='PR4B';
NET_NAME
'FM_CPU1_PKGID0'
 '@BASEBOARD_FAB2_LIB.BASEBOARD_FAB2(SCH_1):FM_CPU1_PKGID0':
 C_SIGNAL='@baseboard_fab2_lib.baseboard_fab2(sch_1):fm_cpu1_pkgid0';
NODE_NAME     R8N2 2
 '@BASEBOARD_FAB2_LIB.BASEBOARD_FAB2(SCH_1):PAGE55_I161@MSTR_DISCRETE.RES(CHIPS)':
 'B': CDS_PINID='B';
NODE_NAME     U2D1 DC72
 '@BASEBOARD_FAB2_LIB.BASEBOARD_FAB2(SCH_1):PAGE55_I172@CHPSET_LIB.SKX_EXT_B(CHIPS)':
 'PKGID'<0>: CDS_PINID='PKGID(0)';
NODE_NAME     U8D7 R12
 '@BASEBOARD_FAB2_LIB.BASEBOARD_FAB2(SCH_1):PAGE190_I179@MSTR_MEMORY.LCMXO2_A(CHIPS)':
 'PB25A_SN': CDS_PINID='PB25A_SN';
NET_NAME
'FM_CPU1_PKGID1'
 '@BASEBOARD_FAB2_LIB.BASEBOARD_FAB2(SCH_1):FM_CPU1_PKGID1':
 C_SIGNAL='@baseboard_fab2_lib.baseboard_fab2(sch_1):fm_cpu1_pkgid1';
NODE_NAME     R8N5 2
 '@BASEBOARD_FAB2_LIB.BASEBOARD_FAB2(SCH_1):PAGE55_I160@MSTR_DISCRETE.RES(CHIPS)':
 'B': CDS_PINID='B';
NODE_NAME     U2D1 CW72
 '@BASEBOARD_FAB2_LIB.BASEBOARD_FAB2(SCH_1):PAGE55_I172@CHPSET_LIB.SKX_EXT_B(CHIPS)':
 'PKGID'<1>: CDS_PINID='PKGID(1)';
NODE_NAME     U6M1 1
 '@BASEBOARD_FAB2_LIB.BASEBOARD_FAB2(SCH_1):PAGE113_I190@MSTR_TTL.74CBTLV1G125(CHIPS)':
 'OE_N': CDS_PINID='OE_N';
NODE_NAME     U8D7 P12
 '@BASEBOARD_FAB2_LIB.BASEBOARD_FAB2(SCH_1):PAGE190_I179@MSTR_MEMORY.LCMXO2_A(CHIPS)':
 'PB24A': CDS_PINID='PB24A';
NET_NAME
'FM_CPU1_PKGID2'
 '@BASEBOARD_FAB2_LIB.BASEBOARD_FAB2(SCH_1):FM_CPU1_PKGID2':
 C_SIGNAL='@baseboard_fab2_lib.baseboard_fab2(sch_1):fm_cpu1_pkgid2';
NODE_NAME     R8N3 2
 '@BASEBOARD_FAB2_LIB.BASEBOARD_FAB2(SCH_1):PAGE55_I159@MSTR_DISCRETE.RES(CHIPS)':
 'B': CDS_PINID='B';
NODE_NAME     U2D1 DA72
 '@BASEBOARD_FAB2_LIB.BASEBOARD_FAB2(SCH_1):PAGE55_I172@CHPSET_LIB.SKX_EXT_B(CHIPS)':
 'PKGID'<2>: CDS_PINID='PKGID(2)';
NODE_NAME     U8D7 T11
 '@BASEBOARD_FAB2_LIB.BASEBOARD_FAB2(SCH_1):PAGE190_I179@MSTR_MEMORY.LCMXO2_A(CHIPS)':
 'PB21A': CDS_PINID='PB21A';
NET_NAME
'FM_CPU1_PROCHOT_LVT3_BMC_N'
 '@BASEBOARD_FAB2_LIB.BASEBOARD_FAB2(SCH_1):FM_CPU1_PROCHOT_LVT3_BMC_N':
 C_SIGNAL='@baseboard_fab2_lib.baseboard_fab2(sch_1):fm_cpu1_prochot_lvt3_bmc_n';
NODE_NAME     R1T37 2
 '@BASEBOARD_FAB2_LIB.BASEBOARD_FAB2(SCH_1):PAGE93_I123@MSTR_DISCRETE.RES(CHIPS)':
 'B': CDS_PINID='B';
NODE_NAME     U25W4 B19
 '@BASEBOARD_FAB2_LIB.BASEBOARD_FAB2(SCH_1):PAGE145_I117@W_HDL.AST2520A1-GP-GP(CHIPS)':
 'GPIOE7_RXD3': CDS_PINID='GPIOE7_RXD3';
NET_NAME
'FM_CPU1_PROCHOT_LVT3_K_N'
 '@BASEBOARD_FAB2_LIB.BASEBOARD_FAB2(SCH_1):FM_CPU1_PROCHOT_LVT3_K_N':
 C_SIGNAL='@baseboard_fab2_lib.baseboard_fab2(sch_1):fm_cpu1_prochot_lvt3_k_n';
NODE_NAME     R7D24 1
 '@BASEBOARD_FAB2_LIB.BASEBOARD_FAB2(SCH_1):PAGE93_I62@MSTR_DISCRETE.RES(CHIPS)':
 'A': CDS_PINID='A';
NODE_NAME     R7D43 1
 '@BASEBOARD_FAB2_LIB.BASEBOARD_FAB2(SCH_1):PAGE93_I110@MSTR_DISCRETE.RES(CHIPS)':
 'A': CDS_PINID='A';
NODE_NAME     R7D41 2
 '@BASEBOARD_FAB2_LIB.BASEBOARD_FAB2(SCH_1):PAGE93_I114@MSTR_DISCRETE.RES(CHIPS)':
 'B': CDS_PINID='B';
NET_NAME
'FM_CPU1_PROCHOT_LVT3_N'
 '@BASEBOARD_FAB2_LIB.BASEBOARD_FAB2(SCH_1):FM_CPU1_PROCHOT_LVT3_N':
 C_SIGNAL='@baseboard_fab2_lib.baseboard_fab2(sch_1):fm_cpu1_prochot_lvt3_n';
NODE_NAME     R7D24 2
 '@BASEBOARD_FAB2_LIB.BASEBOARD_FAB2(SCH_1):PAGE93_I62@MSTR_DISCRETE.RES(CHIPS)':
 'B': CDS_PINID='B';
NODE_NAME     R1T37 1
 '@BASEBOARD_FAB2_LIB.BASEBOARD_FAB2(SCH_1):PAGE93_I123@MSTR_DISCRETE.RES(CHIPS)':
 'A': CDS_PINID='A';
NODE_NAME     R1T38 1
 '@BASEBOARD_FAB2_LIB.BASEBOARD_FAB2(SCH_1):PAGE93_I137@MSTR_DISCRETE.RES(CHIPS)':
 'A': CDS_PINID='A';
NET_NAME
'FM_CPU1_PROCHOT_LVT3_R_N'
 '@BASEBOARD_FAB2_LIB.BASEBOARD_FAB2(SCH_1):FM_CPU1_PROCHOT_LVT3_R_N':
 C_SIGNAL='@baseboard_fab2_lib.baseboard_fab2(sch_1):fm_cpu1_prochot_lvt3_r_n';
NODE_NAME     U2T4 13
 '@BASEBOARD_FAB2_LIB.BASEBOARD_FAB2(SCH_1):PAGE93_I30@MSTR_DIGITAL.GTL2014(CHIPS)':
 'A0': CDS_PINID='A0';
NODE_NAME     R7D41 1
 '@BASEBOARD_FAB2_LIB.BASEBOARD_FAB2(SCH_1):PAGE93_I114@MSTR_DISCRETE.RES(CHIPS)':
 'A': CDS_PINID='A';
NET_NAME
'FM_CPU1_PROCHOT_PCH_N'
 '@BASEBOARD_FAB2_LIB.BASEBOARD_FAB2(SCH_1):FM_CPU1_PROCHOT_PCH_N':
 C_SIGNAL='@baseboard_fab2_lib.baseboard_fab2(sch_1):fm_cpu1_prochot_pch_n';
NODE_NAME     R1T38 2
 '@BASEBOARD_FAB2_LIB.BASEBOARD_FAB2(SCH_1):PAGE93_I137@MSTR_DISCRETE.RES(CHIPS)':
 'B': CDS_PINID='B';
NODE_NAME     U7C1 AA9
 '@BASEBOARD_FAB2_LIB.BASEBOARD_FAB2(SCH_1):PAGE121_I34@MSTR_U_PROC.LBG_CORE_QAT_EXT_D(CHIPS)':
 'GPP_L17_TESTCH1_D6': CDS_PINID='GPP_L17_TESTCH1_D6';
NET_NAME
'FM_CPU1_PROC_ID0'
 '@BASEBOARD_FAB2_LIB.BASEBOARD_FAB2(SCH_1):FM_CPU1_PROC_ID0':
 C_SIGNAL='@baseboard_fab2_lib.baseboard_fab2(sch_1):fm_cpu1_proc_id0';
NODE_NAME     R8N4 2
 '@BASEBOARD_FAB2_LIB.BASEBOARD_FAB2(SCH_1):PAGE55_I158@MSTR_DISCRETE.RES(CHIPS)':
 'B': CDS_PINID='B';
NODE_NAME     U2D1 CY71
 '@BASEBOARD_FAB2_LIB.BASEBOARD_FAB2(SCH_1):PAGE55_I172@CHPSET_LIB.SKX_EXT_B(CHIPS)':
 'PROC_ID'<0>: CDS_PINID='PROC_ID(0)';
NODE_NAME     U8D7 M15
 '@BASEBOARD_FAB2_LIB.BASEBOARD_FAB2(SCH_1):PAGE191_I59@MSTR_MEMORY.LCMXO2_A(CHIPS)':
 'PR13B': CDS_PINID='PR13B';
NET_NAME
'FM_CPU1_PROC_ID1'
 '@BASEBOARD_FAB2_LIB.BASEBOARD_FAB2(SCH_1):FM_CPU1_PROC_ID1':
 C_SIGNAL='@baseboard_fab2_lib.baseboard_fab2(sch_1):fm_cpu1_proc_id1';
NODE_NAME     R8N1 2
 '@BASEBOARD_FAB2_LIB.BASEBOARD_FAB2(SCH_1):PAGE55_I157@MSTR_DISCRETE.RES(CHIPS)':
 'B': CDS_PINID='B';
NODE_NAME     U2D1 DB71
 '@BASEBOARD_FAB2_LIB.BASEBOARD_FAB2(SCH_1):PAGE55_I172@CHPSET_LIB.SKX_EXT_B(CHIPS)':
 'PROC_ID'<1>: CDS_PINID='PROC_ID(1)';
NODE_NAME     U8D7 M14
 '@BASEBOARD_FAB2_LIB.BASEBOARD_FAB2(SCH_1):PAGE191_I59@MSTR_MEMORY.LCMXO2_A(CHIPS)':
 'PR13A': CDS_PINID='PR13A';
NET_NAME
'FM_CPU1_RC_EN'
 '@BASEBOARD_FAB2_LIB.BASEBOARD_FAB2(SCH_1):FM_CPU1_RC_EN':
 C_SIGNAL='@baseboard_fab2_lib.baseboard_fab2(sch_1):fm_cpu1_rc_en';
NODE_NAME     U7C1 BY29
 '@BASEBOARD_FAB2_LIB.BASEBOARD_FAB2(SCH_1):PAGE119_I115@MSTR_U_PROC.LBG_CORE_QAT_EXT_D(CHIPS)':
 'GPP_C9': CDS_PINID='GPP_C9';
NODE_NAME     R2P22 2
 '@BASEBOARD_FAB2_LIB.BASEBOARD_FAB2(SCH_1):PAGE133_I360@MSTR_DISCRETE.RES(CHIPS)':
 'B': CDS_PINID='B';
NODE_NAME     U8D7 P4
 '@BASEBOARD_FAB2_LIB.BASEBOARD_FAB2(SCH_1):PAGE190_I179@MSTR_MEMORY.LCMXO2_A(CHIPS)':
 'PB3A': CDS_PINID='PB3A';
NET_NAME
'FM_CPU1_RC_ERROR_N'
 '@BASEBOARD_FAB2_LIB.BASEBOARD_FAB2(SCH_1):FM_CPU1_RC_ERROR_N':
 C_SIGNAL='@baseboard_fab2_lib.baseboard_fab2(sch_1):fm_cpu1_rc_error_n',
 PHYS_NET_NAME='FM_CPU1_RC_ERROR_N';
NODE_NAME     U2D1 Y23
 '@BASEBOARD_FAB2_LIB.BASEBOARD_FAB2(SCH_1):PAGE56_I169@CHPSET_LIB.SKX_EXT_B(CHIPS)':
 'RSVD'<257>: CDS_PINID='RSVD(257)';
NODE_NAME     R2N29 2
 '@BASEBOARD_FAB2_LIB.BASEBOARD_FAB2(SCH_1):PAGE133_I352@MSTR_DISCRETE.RES(CHIPS)':
 'B': CDS_PINID='B';
NODE_NAME     U25W4 AB2
 '@BASEBOARD_FAB2_LIB.BASEBOARD_FAB2(SCH_1):PAGE145_I117@W_HDL.AST2520A1-GP-GP(CHIPS)':
 'GPIOM1_NDCD2_VPIB3': CDS_PINID='GPIOM1_NDCD2_VPIB3';
NODE_NAME     R7W12 1
 '@BASEBOARD_FAB2_LIB.BASEBOARD_FAB2(SCH_1):PAGE120_I271@MSTR_DISCRETE.RES(CHIPS)':
 'A': CDS_PINID='A';
NODE_NAME     R7W11 2
 '@BASEBOARD_FAB2_LIB.BASEBOARD_FAB2(SCH_1):PAGE120_I273@MSTR_DISCRETE.RES(CHIPS)':
 'B': CDS_PINID='B';
NET_NAME
'FM_CPU1_RC_ERROR_R1_N'
 '@BASEBOARD_FAB2_LIB.BASEBOARD_FAB2(SCH_1):FM_CPU1_RC_ERROR_R1_N':
 C_SIGNAL='@baseboard_fab2_lib.baseboard_fab2(sch_1):fm_cpu1_rc_error_r1_n';
NODE_NAME     U7C1 AY52
 '@BASEBOARD_FAB2_LIB.BASEBOARD_FAB2(SCH_1):PAGE120_I147@MSTR_U_PROC.LBG_CORE_QAT_EXT_D(CHIPS)':
 'GPP_E1_SATAXPCIE1_SATAGP1': CDS_PINID='GPP_E1_SATAXPCIE1_SATAGP1';
NODE_NAME     R7W12 2
 '@BASEBOARD_FAB2_LIB.BASEBOARD_FAB2(SCH_1):PAGE120_I271@MSTR_DISCRETE.RES(CHIPS)':
 'B': CDS_PINID='B';
NET_NAME
'FM_CPU1_RC_ERROR_R_N'
 '@BASEBOARD_FAB2_LIB.BASEBOARD_FAB2(SCH_1):FM_CPU1_RC_ERROR_R_N':
 C_SIGNAL='@baseboard_fab2_lib.baseboard_fab2(sch_1):fm_cpu1_rc_error_r_n';
NODE_NAME     U7C1 BV23
 '@BASEBOARD_FAB2_LIB.BASEBOARD_FAB2(SCH_1):PAGE120_I147@MSTR_U_PROC.LBG_CORE_QAT_EXT_D(CHIPS)':
 'GPP_I6_RESET_DONE': CDS_PINID='GPP_I6_RESET_DONE';
NODE_NAME     R7W11 1
 '@BASEBOARD_FAB2_LIB.BASEBOARD_FAB2(SCH_1):PAGE120_I273@MSTR_DISCRETE.RES(CHIPS)':
 'A': CDS_PINID='A';
NET_NAME
'FM_CPU1_SKTOCC_LVT3_N'
 '@BASEBOARD_FAB2_LIB.BASEBOARD_FAB2(SCH_1):FM_CPU1_SKTOCC_LVT3_N':
 C_SIGNAL='@baseboard_fab2_lib.baseboard_fab2(sch_1):fm_cpu1_sktocc_lvt3_n';
NODE_NAME     U2D1 AB13
 '@BASEBOARD_FAB2_LIB.BASEBOARD_FAB2(SCH_1):PAGE55_I172@CHPSET_LIB.SKX_EXT_B(CHIPS)':
 'SKTOCC_N': CDS_PINID='SKTOCC_N';
NODE_NAME     R6P39 2
 '@BASEBOARD_FAB2_LIB.BASEBOARD_FAB2(SCH_1):PAGE55_I181@MSTR_DISCRETE.RES(CHIPS)':
 'B': CDS_PINID='B';
NODE_NAME     U1M7 6
 '@BASEBOARD_FAB2_LIB.BASEBOARD_FAB2(SCH_1):PAGE112_I40@MSTR_ANALOG.NC7SB3157(CHIPS)':
 'S': CDS_PINID='S';
NODE_NAME     U1M4 1
 '@BASEBOARD_FAB2_LIB.BASEBOARD_FAB2(SCH_1):PAGE112_I127@MSTR_TTL.74CBTLV1G125(CHIPS)':
 'OE_N': CDS_PINID='OE_N';
NODE_NAME     U7C1 H13
 '@BASEBOARD_FAB2_LIB.BASEBOARD_FAB2(SCH_1):PAGE118_I73@MSTR_U_PROC.LBG_CORE_QAT_EXT_D(CHIPS)':
 'GPD1_ACPRESENT': CDS_PINID='GPD1_ACPRESENT';
NODE_NAME     U8D7 T12
 '@BASEBOARD_FAB2_LIB.BASEBOARD_FAB2(SCH_1):PAGE190_I179@MSTR_MEMORY.LCMXO2_A(CHIPS)':
 'PB22B': CDS_PINID='PB22B';
NODE_NAME     U25W4 Y21
 '@BASEBOARD_FAB2_LIB.BASEBOARD_FAB2(SCH_1):PAGE146_I104@W_HDL.AST2520A1-GP-GP(CHIPS)':
 'GPIOAA0_VPOR2_NORD0_SALT7': CDS_PINID='GPIOAA0_VPOR2_NORD0_SALT7';
NET_NAME
'FM_CPU1_SM_WP'
 '@BASEBOARD_FAB2_LIB.BASEBOARD_FAB2(SCH_1):FM_CPU1_SM_WP':
 C_SIGNAL='@baseboard_fab2_lib.baseboard_fab2(sch_1):fm_cpu1_sm_wp';
NODE_NAME     U2D1 CV59
 '@BASEBOARD_FAB2_LIB.BASEBOARD_FAB2(SCH_1):PAGE55_I172@CHPSET_LIB.SKX_EXT_B(CHIPS)':
 'SM_WP': CDS_PINID='SM_WP';
NODE_NAME     R1C35 2
 '@BASEBOARD_FAB2_LIB.BASEBOARD_FAB2(SCH_1):PAGE156_I336@MSTR_DISCRETE.RES(CHIPS)':
 'B': CDS_PINID='B';
NODE_NAME     R1C36 1
 '@BASEBOARD_FAB2_LIB.BASEBOARD_FAB2(SCH_1):PAGE156_I337@MSTR_DISCRETE.RES(CHIPS)':
 'A': CDS_PINID='A';
NET_NAME
'FM_CPU1_STL_BRD_OSC_EN'
 '@BASEBOARD_FAB2_LIB.BASEBOARD_FAB2(SCH_1):FM_CPU1_STL_BRD_OSC_EN':
 C_SIGNAL='@baseboard_fab2_lib.baseboard_fab2(sch_1):fm_cpu1_stl_brd_osc_en';
NODE_NAME     Y3F1 1
 '@BASEBOARD_FAB2_LIB.BASEBOARD_FAB2(SCH_1):PAGE104_I72@MSTR_DISCRETE.OSC_C(CHIPS)':
 'ENABLE_DISABLE': CDS_PINID='ENABLE_DISABLE';
NODE_NAME     R7D36 2
 '@BASEBOARD_FAB2_LIB.BASEBOARD_FAB2(SCH_1):PAGE104_I96@MSTR_DISCRETE.RES(CHIPS)':
 'B': CDS_PINID='B';
NODE_NAME     R7D38 2
 '@BASEBOARD_FAB2_LIB.BASEBOARD_FAB2(SCH_1):PAGE104_I97@MSTR_DISCRETE.RES(CHIPS)':
 'B': CDS_PINID='B';
NET_NAME
'FM_CPU1_THERMTRIP_LATCH_LVT3_N'
 '@BASEBOARD_FAB2_LIB.BASEBOARD_FAB2(SCH_1):FM_CPU1_THERMTRIP_LATCH_LVT3_N':
 C_SIGNAL='@baseboard_fab2_lib.baseboard_fab2(sch_1):fm_cpu1_thermtrip_latch_lvt~
3_n';
NODE_NAME     U7C1 AV18
 '@BASEBOARD_FAB2_LIB.BASEBOARD_FAB2(SCH_1):PAGE120_I147@MSTR_U_PROC.LBG_CORE_QAT_EXT_D(CHIPS)':
 'GPP_G6_FANTACH6_FANTACH6IE': CDS_PINID='GPP_G6_FANTACH6_FANTACH6IE';
NODE_NAME     U8D7 C5
 '@BASEBOARD_FAB2_LIB.BASEBOARD_FAB2(SCH_1):PAGE191_I59@MSTR_MEMORY.LCMXO2_A(CHIPS)':
 'PT10B': CDS_PINID='PT10B';
NODE_NAME     U25W4 P5
 '@BASEBOARD_FAB2_LIB.BASEBOARD_FAB2(SCH_1):PAGE145_I117@W_HDL.AST2520A1-GP-GP(CHIPS)':
 'GPIOM5_NRTS2_VPIB7': CDS_PINID='GPIOM5_NRTS2_VPIB7';
NET_NAME
'FM_CPU1_THERMTRIP_LVT3_N'
 '@BASEBOARD_FAB2_LIB.BASEBOARD_FAB2(SCH_1):FM_CPU1_THERMTRIP_LVT3_N':
 C_SIGNAL='@baseboard_fab2_lib.baseboard_fab2(sch_1):fm_cpu1_thermtrip_lvt3_n';
NODE_NAME     R3P42 2
 '@BASEBOARD_FAB2_LIB.BASEBOARD_FAB2(SCH_1):PAGE92_I14@MSTR_DISCRETE.RES(CHIPS)':
 'B': CDS_PINID='B';
NODE_NAME     U8D7 G14
 '@BASEBOARD_FAB2_LIB.BASEBOARD_FAB2(SCH_1):PAGE191_I59@MSTR_MEMORY.LCMXO2_A(CHIPS)':
 'PR5B': CDS_PINID='PR5B';
NET_NAME
'FM_CPU1_THERMTRIP_LVT3_R_N'
 '@BASEBOARD_FAB2_LIB.BASEBOARD_FAB2(SCH_1):FM_CPU1_THERMTRIP_LVT3_R_N':
 C_SIGNAL='@baseboard_fab2_lib.baseboard_fab2(sch_1):fm_cpu1_thermtrip_lvt3_r_n';
NODE_NAME     U3P2 9
 '@BASEBOARD_FAB2_LIB.BASEBOARD_FAB2(SCH_1):PAGE92_I1@MSTR_DIGITAL.GTL2014(CHIPS)':
 'A3': CDS_PINID='A3';
NODE_NAME     R3P42 1
 '@BASEBOARD_FAB2_LIB.BASEBOARD_FAB2(SCH_1):PAGE92_I14@MSTR_DISCRETE.RES(CHIPS)':
 'A': CDS_PINID='A';
NET_NAME
'FM_CPU1_VRM_322M_156M_OSC_EN'
 '@BASEBOARD_FAB2_LIB.BASEBOARD_FAB2(SCH_1):FM_CPU1_VRM_322M_156M_OSC_EN':
 C_SIGNAL='@baseboard_fab2_lib.baseboard_fab2(sch_1):fm_cpu1_vrm_322m_156m_osc_e~
n';
NODE_NAME     J4B2 E1
 '@BASEBOARD_FAB2_LIB.BASEBOARD_FAB2(SCH_1):PAGE193_I46@MSTR_SCONN.SCONN120_H61426002(CHIPS)':
 'IOE1': CDS_PINID='IOE1';
NODE_NAME     R7D37 2
 '@BASEBOARD_FAB2_LIB.BASEBOARD_FAB2(SCH_1):PAGE104_I104@MSTR_DISCRETE.RES(CHIPS)':
 'B': CDS_PINID='B';
NET_NAME
'FM_CPU1_VRM_OSC_EN'
 '@BASEBOARD_FAB2_LIB.BASEBOARD_FAB2(SCH_1):FM_CPU1_VRM_OSC_EN':
 C_SIGNAL='@baseboard_fab2_lib.baseboard_fab2(sch_1):fm_cpu1_vrm_osc_en';
NODE_NAME     R7D38 1
 '@BASEBOARD_FAB2_LIB.BASEBOARD_FAB2(SCH_1):PAGE104_I97@MSTR_DISCRETE.RES(CHIPS)':
 'A': CDS_PINID='A';
NODE_NAME     U8D7 N14
 '@BASEBOARD_FAB2_LIB.BASEBOARD_FAB2(SCH_1):PAGE191_I59@MSTR_MEMORY.LCMXO2_A(CHIPS)':
 'PR14B': CDS_PINID='PR14B';
NODE_NAME     R7D37 1
 '@BASEBOARD_FAB2_LIB.BASEBOARD_FAB2(SCH_1):PAGE104_I104@MSTR_DISCRETE.RES(CHIPS)':
 'A': CDS_PINID='A';
NET_NAME
'FM_CPU_BMC_INIT'
 '@BASEBOARD_FAB2_LIB.BASEBOARD_FAB2(SCH_1):FM_CPU_BMC_INIT':
 C_SIGNAL='@baseboard_fab2_lib.baseboard_fab2(sch_1):fm_cpu_bmc_init';
NODE_NAME     U7C1 AD1
 '@BASEBOARD_FAB2_LIB.BASEBOARD_FAB2(SCH_1):PAGE119_I115@MSTR_U_PROC.LBG_CORE_QAT_EXT_D(CHIPS)':
 'GPP_A17': CDS_PINID='GPP_A17';
NODE_NAME     R6D16 1
 '@BASEBOARD_FAB2_LIB.BASEBOARD_FAB2(SCH_1):PAGE156_I299@MSTR_DISCRETE.RES(CHIPS)':
 'A': CDS_PINID='A';
NODE_NAME     R3D31 1
 '@BASEBOARD_FAB2_LIB.BASEBOARD_FAB2(SCH_1):PAGE156_I300@MSTR_DISCRETE.RES(CHIPS)':
 'A': CDS_PINID='A';
NODE_NAME     U6W11 7
 '@BASEBOARD_FAB2_LIB.BASEBOARD_FAB2(SCH_1):PAGE164_I97@W_HDL.PCA9554PWR-GP(CHIPS)':
 'P3': CDS_PINID='P3';
NET_NAME
'FM_CPU_CATERR_DLY_LVT3_N'
 '@BASEBOARD_FAB2_LIB.BASEBOARD_FAB2(SCH_1):FM_CPU_CATERR_DLY_LVT3_N':
 C_SIGNAL='@baseboard_fab2_lib.baseboard_fab2(sch_1):fm_cpu_caterr_dly_lvt3_n';
NODE_NAME     R2N1 2
 '@BASEBOARD_FAB2_LIB.BASEBOARD_FAB2(SCH_1):PAGE119_I173@MSTR_DISCRETE.RES(CHIPS)':
 'B': CDS_PINID='B';
NODE_NAME     U8D7 E2
 '@BASEBOARD_FAB2_LIB.BASEBOARD_FAB2(SCH_1):PAGE190_I179@MSTR_MEMORY.LCMXO2_A(CHIPS)':
 'PL2A_L_GPLLT_IN': CDS_PINID='PL2A_L_GPLLT_IN';
NET_NAME
'FM_CPU_CATERR_DLY_LVT3_R_N'
 '@BASEBOARD_FAB2_LIB.BASEBOARD_FAB2(SCH_1):FM_CPU_CATERR_DLY_LVT3_R_N':
 C_SIGNAL='@baseboard_fab2_lib.baseboard_fab2(sch_1):fm_cpu_caterr_dly_lvt3_r_n';
NODE_NAME     U7C1 CA37
 '@BASEBOARD_FAB2_LIB.BASEBOARD_FAB2(SCH_1):PAGE119_I115@MSTR_U_PROC.LBG_CORE_QAT_EXT_D(CHIPS)':
 'GPP_C23': CDS_PINID='GPP_C23';
NODE_NAME     R2N1 1
 '@BASEBOARD_FAB2_LIB.BASEBOARD_FAB2(SCH_1):PAGE119_I173@MSTR_DISCRETE.RES(CHIPS)':
 'A': CDS_PINID='A';
NET_NAME
'FM_CPU_CATERR_LVT3_N'
 '@BASEBOARD_FAB2_LIB.BASEBOARD_FAB2(SCH_1):FM_CPU_CATERR_LVT3_N':
 C_SIGNAL='@baseboard_fab2_lib.baseboard_fab2(sch_1):fm_cpu_caterr_lvt3_n';
NODE_NAME     R3P43 2
 '@BASEBOARD_FAB2_LIB.BASEBOARD_FAB2(SCH_1):PAGE92_I13@MSTR_DISCRETE.RES(CHIPS)':
 'B': CDS_PINID='B';
NODE_NAME     U8D7 R14
 '@BASEBOARD_FAB2_LIB.BASEBOARD_FAB2(SCH_1):PAGE190_I179@MSTR_MEMORY.LCMXO2_A(CHIPS)':
 'PB25D': CDS_PINID='PB25D';
NODE_NAME     U25W4 E19
 '@BASEBOARD_FAB2_LIB.BASEBOARD_FAB2(SCH_1):PAGE144_I95@W_HDL.AST2520A1-GP-GP(CHIPS)':
 'GPIOG1_SGPS1LD': CDS_PINID='GPIOG1_SGPS1LD';
NODE_NAME     CR6W1 1
 '@BASEBOARD_FAB2_LIB.BASEBOARD_FAB2(SCH_1):PAGE247_I157@MSTR_DISCRETE.DIODE(CHIPS)':
 'C': CDS_PINID='C';
NET_NAME
'FM_CPU_CATERR_LVT3_R2_N'
 '@BASEBOARD_FAB2_LIB.BASEBOARD_FAB2(SCH_1):FM_CPU_CATERR_LVT3_R2_N':
 C_SIGNAL='@baseboard_fab2_lib.baseboard_fab2(sch_1):fm_cpu_caterr_lvt3_r2_n';
NODE_NAME     U3P2 10
 '@BASEBOARD_FAB2_LIB.BASEBOARD_FAB2(SCH_1):PAGE92_I1@MSTR_DIGITAL.GTL2014(CHIPS)':
 'A2': CDS_PINID='A2';
NODE_NAME     R3P43 1
 '@BASEBOARD_FAB2_LIB.BASEBOARD_FAB2(SCH_1):PAGE92_I13@MSTR_DISCRETE.RES(CHIPS)':
 'A': CDS_PINID='A';
NET_NAME
'FM_CPU_CATERR_MSMI_LVT3_N'
 '@BASEBOARD_FAB2_LIB.BASEBOARD_FAB2(SCH_1):FM_CPU_CATERR_MSMI_LVT3_N':
 C_SIGNAL='@baseboard_fab2_lib.baseboard_fab2(sch_1):fm_cpu_caterr_msmi_lvt3_n';
NODE_NAME     U6W1 18
 '@BASEBOARD_FAB2_LIB.BASEBOARD_FAB2(SCH_1):PAGE247_I120@W_HDL.TCA9555PWR-GP(CHIPS)':
 'P15': CDS_PINID='P15';
NODE_NAME     CR6W1 2
 '@BASEBOARD_FAB2_LIB.BASEBOARD_FAB2(SCH_1):PAGE247_I157@MSTR_DISCRETE.DIODE(CHIPS)':
 'A': CDS_PINID='A';
NODE_NAME     CR6W2 2
 '@BASEBOARD_FAB2_LIB.BASEBOARD_FAB2(SCH_1):PAGE247_I158@MSTR_DISCRETE.DIODE(CHIPS)':
 'A': CDS_PINID='A';
NODE_NAME     R6W35 2
 '@BASEBOARD_FAB2_LIB.BASEBOARD_FAB2(SCH_1):PAGE247_I165@MSTR_DISCRETE.RES(CHIPS)':
 'B': CDS_PINID='B';
NET_NAME
'FM_CPU_ERR0_LVT3_BMC_N'
 '@BASEBOARD_FAB2_LIB.BASEBOARD_FAB2(SCH_1):FM_CPU_ERR0_LVT3_BMC_N':
 C_SIGNAL='@baseboard_fab2_lib.baseboard_fab2(sch_1):fm_cpu_err0_lvt3_bmc_n';
NODE_NAME     R8F38 2
 '@BASEBOARD_FAB2_LIB.BASEBOARD_FAB2(SCH_1):PAGE93_I119@MSTR_DISCRETE.RES(CHIPS)':
 'B': CDS_PINID='B';
NODE_NAME     U25W4 G18
 '@BASEBOARD_FAB2_LIB.BASEBOARD_FAB2(SCH_1):PAGE145_I117@W_HDL.AST2520A1-GP-GP(CHIPS)':
 'GPIOD6_SD2CD#': CDS_PINID='\gpiod6_sd2cd#\';
NET_NAME
'FM_CPU_ERR0_LVT3_K_N'
 '@BASEBOARD_FAB2_LIB.BASEBOARD_FAB2(SCH_1):FM_CPU_ERR0_LVT3_K_N':
 C_SIGNAL='@baseboard_fab2_lib.baseboard_fab2(sch_1):fm_cpu_err0_lvt3_k_n';
NODE_NAME     R2T30 1
 '@BASEBOARD_FAB2_LIB.BASEBOARD_FAB2(SCH_1):PAGE93_I42@MSTR_DISCRETE.RES(CHIPS)':
 'A': CDS_PINID='A';
NODE_NAME     R2T58 2
 '@BASEBOARD_FAB2_LIB.BASEBOARD_FAB2(SCH_1):PAGE93_I94@MSTR_DISCRETE.RES(CHIPS)':
 'B': CDS_PINID='B';
NODE_NAME     R2T65 2
 '@BASEBOARD_FAB2_LIB.BASEBOARD_FAB2(SCH_1):PAGE93_I111@MSTR_DISCRETE.RES(CHIPS)':
 'B': CDS_PINID='B';
NET_NAME
'FM_CPU_ERR0_LVT3_N'
 '@BASEBOARD_FAB2_LIB.BASEBOARD_FAB2(SCH_1):FM_CPU_ERR0_LVT3_N':
 C_SIGNAL='@baseboard_fab2_lib.baseboard_fab2(sch_1):fm_cpu_err0_lvt3_n';
NODE_NAME     R2T30 2
 '@BASEBOARD_FAB2_LIB.BASEBOARD_FAB2(SCH_1):PAGE93_I42@MSTR_DISCRETE.RES(CHIPS)':
 'B': CDS_PINID='B';
NODE_NAME     R8F38 1
 '@BASEBOARD_FAB2_LIB.BASEBOARD_FAB2(SCH_1):PAGE93_I119@MSTR_DISCRETE.RES(CHIPS)':
 'A': CDS_PINID='A';
NODE_NAME     R8F37 1
 '@BASEBOARD_FAB2_LIB.BASEBOARD_FAB2(SCH_1):PAGE93_I131@MSTR_DISCRETE.RES(CHIPS)':
 'A': CDS_PINID='A';
NET_NAME
'FM_CPU_ERR0_LVT3_R_N'
 '@BASEBOARD_FAB2_LIB.BASEBOARD_FAB2(SCH_1):FM_CPU_ERR0_LVT3_R_N':
 C_SIGNAL='@baseboard_fab2_lib.baseboard_fab2(sch_1):fm_cpu_err0_lvt3_r_n';
NODE_NAME     U2T4 9
 '@BASEBOARD_FAB2_LIB.BASEBOARD_FAB2(SCH_1):PAGE93_I30@MSTR_DIGITAL.GTL2014(CHIPS)':
 'A3': CDS_PINID='A3';
NODE_NAME     R2T65 1
 '@BASEBOARD_FAB2_LIB.BASEBOARD_FAB2(SCH_1):PAGE93_I111@MSTR_DISCRETE.RES(CHIPS)':
 'A': CDS_PINID='A';
NET_NAME
'FM_CPU_ERR0_PCH_N'
 '@BASEBOARD_FAB2_LIB.BASEBOARD_FAB2(SCH_1):FM_CPU_ERR0_PCH_N':
 C_SIGNAL='@baseboard_fab2_lib.baseboard_fab2(sch_1):fm_cpu_err0_pch_n';
NODE_NAME     R8F37 2
 '@BASEBOARD_FAB2_LIB.BASEBOARD_FAB2(SCH_1):PAGE93_I131@MSTR_DISCRETE.RES(CHIPS)':
 'B': CDS_PINID='B';
NODE_NAME     U7C1 AE7
 '@BASEBOARD_FAB2_LIB.BASEBOARD_FAB2(SCH_1):PAGE121_I34@MSTR_U_PROC.LBG_CORE_QAT_EXT_D(CHIPS)':
 'GPP_L18_TESTCH1_D7': CDS_PINID='GPP_L18_TESTCH1_D7';
NET_NAME
'FM_CPU_ERR1_LVT3_BMC_N'
 '@BASEBOARD_FAB2_LIB.BASEBOARD_FAB2(SCH_1):FM_CPU_ERR1_LVT3_BMC_N':
 C_SIGNAL='@baseboard_fab2_lib.baseboard_fab2(sch_1):fm_cpu_err1_lvt3_bmc_n';
NODE_NAME     R2T64 2
 '@BASEBOARD_FAB2_LIB.BASEBOARD_FAB2(SCH_1):PAGE93_I121@MSTR_DISCRETE.RES(CHIPS)':
 'B': CDS_PINID='B';
NODE_NAME     U25W4 C21
 '@BASEBOARD_FAB2_LIB.BASEBOARD_FAB2(SCH_1):PAGE145_I117@W_HDL.AST2520A1-GP-GP(CHIPS)':
 'GPIOD7_SD2WP#': CDS_PINID='\gpiod7_sd2wp#\';
NET_NAME
'FM_CPU_ERR1_LVT3_K_N'
 '@BASEBOARD_FAB2_LIB.BASEBOARD_FAB2(SCH_1):FM_CPU_ERR1_LVT3_K_N':
 C_SIGNAL='@baseboard_fab2_lib.baseboard_fab2(sch_1):fm_cpu_err1_lvt3_k_n';
NODE_NAME     R2T33 1
 '@BASEBOARD_FAB2_LIB.BASEBOARD_FAB2(SCH_1):PAGE93_I40@MSTR_DISCRETE.RES(CHIPS)':
 'A': CDS_PINID='A';
NODE_NAME     R2T62 2
 '@BASEBOARD_FAB2_LIB.BASEBOARD_FAB2(SCH_1):PAGE93_I93@MSTR_DISCRETE.RES(CHIPS)':
 'B': CDS_PINID='B';
NODE_NAME     R2T66 2
 '@BASEBOARD_FAB2_LIB.BASEBOARD_FAB2(SCH_1):PAGE93_I112@MSTR_DISCRETE.RES(CHIPS)':
 'B': CDS_PINID='B';
NET_NAME
'FM_CPU_ERR1_LVT3_N'
 '@BASEBOARD_FAB2_LIB.BASEBOARD_FAB2(SCH_1):FM_CPU_ERR1_LVT3_N':
 C_SIGNAL='@baseboard_fab2_lib.baseboard_fab2(sch_1):fm_cpu_err1_lvt3_n';
NODE_NAME     R2T33 2
 '@BASEBOARD_FAB2_LIB.BASEBOARD_FAB2(SCH_1):PAGE93_I40@MSTR_DISCRETE.RES(CHIPS)':
 'B': CDS_PINID='B';
NODE_NAME     R2T64 1
 '@BASEBOARD_FAB2_LIB.BASEBOARD_FAB2(SCH_1):PAGE93_I121@MSTR_DISCRETE.RES(CHIPS)':
 'A': CDS_PINID='A';
NODE_NAME     R2T63 1
 '@BASEBOARD_FAB2_LIB.BASEBOARD_FAB2(SCH_1):PAGE93_I133@MSTR_DISCRETE.RES(CHIPS)':
 'A': CDS_PINID='A';
NET_NAME
'FM_CPU_ERR1_LVT3_R_N'
 '@BASEBOARD_FAB2_LIB.BASEBOARD_FAB2(SCH_1):FM_CPU_ERR1_LVT3_R_N':
 C_SIGNAL='@baseboard_fab2_lib.baseboard_fab2(sch_1):fm_cpu_err1_lvt3_r_n';
NODE_NAME     U2T4 10
 '@BASEBOARD_FAB2_LIB.BASEBOARD_FAB2(SCH_1):PAGE93_I30@MSTR_DIGITAL.GTL2014(CHIPS)':
 'A2': CDS_PINID='A2';
NODE_NAME     R2T66 1
 '@BASEBOARD_FAB2_LIB.BASEBOARD_FAB2(SCH_1):PAGE93_I112@MSTR_DISCRETE.RES(CHIPS)':
 'A': CDS_PINID='A';
NET_NAME
'FM_CPU_ERR1_PCH_N'
 '@BASEBOARD_FAB2_LIB.BASEBOARD_FAB2(SCH_1):FM_CPU_ERR1_PCH_N':
 C_SIGNAL='@baseboard_fab2_lib.baseboard_fab2(sch_1):fm_cpu_err1_pch_n';
NODE_NAME     R2T63 2
 '@BASEBOARD_FAB2_LIB.BASEBOARD_FAB2(SCH_1):PAGE93_I133@MSTR_DISCRETE.RES(CHIPS)':
 'B': CDS_PINID='B';
NODE_NAME     U7C1 AG11
 '@BASEBOARD_FAB2_LIB.BASEBOARD_FAB2(SCH_1):PAGE121_I34@MSTR_U_PROC.LBG_CORE_QAT_EXT_D(CHIPS)':
 'GPP_L19_TESTCH1_CLK': CDS_PINID='GPP_L19_TESTCH1_CLK';
NET_NAME
'FM_CPU_ERR2_LVT3_N'
 '@BASEBOARD_FAB2_LIB.BASEBOARD_FAB2(SCH_1):FM_CPU_ERR2_LVT3_N':
 C_SIGNAL='@baseboard_fab2_lib.baseboard_fab2(sch_1):fm_cpu_err2_lvt3_n';
NODE_NAME     R7D31 2
 '@BASEBOARD_FAB2_LIB.BASEBOARD_FAB2(SCH_1):PAGE92_I29@MSTR_DISCRETE.RES(CHIPS)':
 'B': CDS_PINID='B';
NODE_NAME     U7C1 AV52
 '@BASEBOARD_FAB2_LIB.BASEBOARD_FAB2(SCH_1):PAGE120_I147@MSTR_U_PROC.LBG_CORE_QAT_EXT_D(CHIPS)':
 'GPP_E4_SATA_DEVSLP0': CDS_PINID='GPP_E4_SATA_DEVSLP0';
NODE_NAME     U25W4 A19
 '@BASEBOARD_FAB2_LIB.BASEBOARD_FAB2(SCH_1):PAGE144_I95@W_HDL.AST2520A1-GP-GP(CHIPS)':
 'GPIOG0_SGPS1CK': CDS_PINID='GPIOG0_SGPS1CK';
NET_NAME
'FM_CPU_ERR2_LVT3_R_N'
 '@BASEBOARD_FAB2_LIB.BASEBOARD_FAB2(SCH_1):FM_CPU_ERR2_LVT3_R_N':
 C_SIGNAL='@baseboard_fab2_lib.baseboard_fab2(sch_1):fm_cpu_err2_lvt3_r_n';
NODE_NAME     R7D31 1
 '@BASEBOARD_FAB2_LIB.BASEBOARD_FAB2(SCH_1):PAGE92_I29@MSTR_DISCRETE.RES(CHIPS)':
 'A': CDS_PINID='A';
NODE_NAME     U7D2 10
 '@BASEBOARD_FAB2_LIB.BASEBOARD_FAB2(SCH_1):PAGE92_I32@MSTR_DIGITAL.GTL2014(CHIPS)':
 'A2': CDS_PINID='A2';
NET_NAME
'FM_CPU_MSMI_LVT3_N'
 '@BASEBOARD_FAB2_LIB.BASEBOARD_FAB2(SCH_1):FM_CPU_MSMI_LVT3_N':
 C_SIGNAL='@baseboard_fab2_lib.baseboard_fab2(sch_1):fm_cpu_msmi_lvt3_n';
NODE_NAME     R7D25 2
 '@BASEBOARD_FAB2_LIB.BASEBOARD_FAB2(SCH_1):PAGE92_I70@MSTR_DISCRETE.RES(CHIPS)':
 'B': CDS_PINID='B';
NODE_NAME     U7C1 AT52
 '@BASEBOARD_FAB2_LIB.BASEBOARD_FAB2(SCH_1):PAGE120_I147@MSTR_U_PROC.LBG_CORE_QAT_EXT_D(CHIPS)':
 'GPP_E5_SATA_DEVSLP1': CDS_PINID='GPP_E5_SATA_DEVSLP1';
NODE_NAME     U8D7 T13
 '@BASEBOARD_FAB2_LIB.BASEBOARD_FAB2(SCH_1):PAGE190_I179@MSTR_MEMORY.LCMXO2_A(CHIPS)':
 'PB24B': CDS_PINID='PB24B';
NODE_NAME     U25W4 U3
 '@BASEBOARD_FAB2_LIB.BASEBOARD_FAB2(SCH_1):PAGE147_I106@W_HDL.AST2520A1-GP-GP(CHIPS)':
 'GPION3_PWM3_VPIG3': CDS_PINID='GPION3_PWM3_VPIG3';
NODE_NAME     CR6W2 1
 '@BASEBOARD_FAB2_LIB.BASEBOARD_FAB2(SCH_1):PAGE247_I158@MSTR_DISCRETE.DIODE(CHIPS)':
 'C': CDS_PINID='C';
NET_NAME
'FM_CPU_MSMI_LVT3_R_N'
 '@BASEBOARD_FAB2_LIB.BASEBOARD_FAB2(SCH_1):FM_CPU_MSMI_LVT3_R_N':
 C_SIGNAL='@baseboard_fab2_lib.baseboard_fab2(sch_1):fm_cpu_msmi_lvt3_r_n';
NODE_NAME     U7D2 13
 '@BASEBOARD_FAB2_LIB.BASEBOARD_FAB2(SCH_1):PAGE92_I32@MSTR_DIGITAL.GTL2014(CHIPS)':
 'A0': CDS_PINID='A0';
NODE_NAME     R7D25 1
 '@BASEBOARD_FAB2_LIB.BASEBOARD_FAB2(SCH_1):PAGE92_I70@MSTR_DISCRETE.RES(CHIPS)':
 'A': CDS_PINID='A';
NET_NAME
'FM_CTNR_PS_ON'
 '@BASEBOARD_FAB2_LIB.BASEBOARD_FAB2(SCH_1):FM_CTNR_PS_ON':
 C_SIGNAL='@baseboard_fab2_lib.baseboard_fab2(sch_1):fm_ctnr_ps_on';
NODE_NAME     U1E2 1
 '@BASEBOARD_FAB2_LIB.BASEBOARD_FAB2(SCH_1):PAGE161_I121@MSTR_TTL.TTL1G08(CHIPS)':
 'A'<0>: CDS_PINID='A(0)';
NODE_NAME     U8D7 B3
 '@BASEBOARD_FAB2_LIB.BASEBOARD_FAB2(SCH_1):PAGE191_I59@MSTR_MEMORY.LCMXO2_A(CHIPS)':
 'PT9C': CDS_PINID='PT9C';
NODE_NAME     EU8B1 2
 '@BASEBOARD_FAB2_LIB.BASEBOARD_FAB2(SCH_1):PAGE198_I13@MSTR_VREG.SLG55021(CHIPS)':
 'ON': CDS_PINID='\on\';
NODE_NAME     R8E12 2
 '@BASEBOARD_FAB2_LIB.BASEBOARD_FAB2(SCH_1):PAGE198_I78@MSTR_DISCRETE.RES(CHIPS)':
 'B': CDS_PINID='B';
NODE_NAME     R8B4 1
 '@BASEBOARD_FAB2_LIB.BASEBOARD_FAB2(SCH_1):PAGE198_I83@MSTR_DISCRETE.RES(CHIPS)':
 'A': CDS_PINID='A';
NODE_NAME     R8E5 2
 '@BASEBOARD_FAB2_LIB.BASEBOARD_FAB2(SCH_1):PAGE181_I63@MSTR_DISCRETE.RES(CHIPS)':
 'B': CDS_PINID='B';
NET_NAME
'FM_CTNR_PS_ON_R'
 '@BASEBOARD_FAB2_LIB.BASEBOARD_FAB2(SCH_1):FM_CTNR_PS_ON_R':
 C_SIGNAL='@baseboard_fab2_lib.baseboard_fab2(sch_1):fm_ctnr_ps_on_r';
NODE_NAME     U8E1 8
 '@BASEBOARD_FAB2_LIB.BASEBOARD_FAB2(SCH_1):PAGE181_I60@MSTR_TTL.TTL08(CHIPS)':
 'Y'<0>: CDS_PINID='Y(0)';
NODE_NAME     R8E5 1
 '@BASEBOARD_FAB2_LIB.BASEBOARD_FAB2(SCH_1):PAGE181_I63@MSTR_DISCRETE.RES(CHIPS)':
 'A': CDS_PINID='A';
NET_NAME
'FM_DB1200ZL_BCLKS_EN_N'
 '@BASEBOARD_FAB2_LIB.BASEBOARD_FAB2(SCH_1):FM_DB1200ZL_BCLKS_EN_N':
 C_SIGNAL='@baseboard_fab2_lib.baseboard_fab2(sch_1):fm_db1200zl_bclks_en_n';
NODE_NAME     EU4D2 19
 '@BASEBOARD_FAB2_LIB.BASEBOARD_FAB2(SCH_1):PAGE102_I1@MSTR_CLOCK.NB3W1200L(CHIPS)':
 'OE_0_N': CDS_PINID='OE_0_N';
NODE_NAME     EU4D2 20
 '@BASEBOARD_FAB2_LIB.BASEBOARD_FAB2(SCH_1):PAGE102_I1@MSTR_CLOCK.NB3W1200L(CHIPS)':
 'OE_1_N': CDS_PINID='OE_1_N';
NODE_NAME     EU4D2 28
 '@BASEBOARD_FAB2_LIB.BASEBOARD_FAB2(SCH_1):PAGE102_I1@MSTR_CLOCK.NB3W1200L(CHIPS)':
 'OE_2_N': CDS_PINID='OE_2_N';
NODE_NAME     EU4D2 44
 '@BASEBOARD_FAB2_LIB.BASEBOARD_FAB2(SCH_1):PAGE102_I1@MSTR_CLOCK.NB3W1200L(CHIPS)':
 'OE_6_N': CDS_PINID='OE_6_N';
NODE_NAME     EU4D2 45
 '@BASEBOARD_FAB2_LIB.BASEBOARD_FAB2(SCH_1):PAGE102_I1@MSTR_CLOCK.NB3W1200L(CHIPS)':
 'OE_7_N': CDS_PINID='OE_7_N';
NODE_NAME     EU4D2 52
 '@BASEBOARD_FAB2_LIB.BASEBOARD_FAB2(SCH_1):PAGE102_I1@MSTR_CLOCK.NB3W1200L(CHIPS)':
 'OE_8_N': CDS_PINID='OE_8_N';
NODE_NAME     U8D7 R11
 '@BASEBOARD_FAB2_LIB.BASEBOARD_FAB2(SCH_1):PAGE190_I179@MSTR_MEMORY.LCMXO2_A(CHIPS)':
 'PB22A': CDS_PINID='PB22A';
NODE_NAME     R6P48 2
 '@BASEBOARD_FAB2_LIB.BASEBOARD_FAB2(SCH_1):PAGE102_I115@MSTR_DISCRETE.RES(CHIPS)':
 'B': CDS_PINID='B';
NET_NAME
'FM_DB1200_PWRGD'
 '@BASEBOARD_FAB2_LIB.BASEBOARD_FAB2(SCH_1):FM_DB1200_PWRGD':
 C_SIGNAL='@baseboard_fab2_lib.baseboard_fab2(sch_1):fm_db1200_pwrgd';
NODE_NAME     U8D7 C15
 '@BASEBOARD_FAB2_LIB.BASEBOARD_FAB2(SCH_1):PAGE191_I59@MSTR_MEMORY.LCMXO2_A(CHIPS)':
 'PR1C': CDS_PINID='PR1C';
NODE_NAME     Q4W2 1
 '@BASEBOARD_FAB2_LIB.BASEBOARD_FAB2(SCH_1):PAGE102_I112@MSTR_DISCRETE.FET_N(CHIPS)':
 'GATE': CDS_PINID='GATE';
NODE_NAME     R4W5 1
 '@BASEBOARD_FAB2_LIB.BASEBOARD_FAB2(SCH_1):PAGE102_I114@MSTR_DISCRETE.RES(CHIPS)':
 'A': CDS_PINID='A';
NET_NAME
'FM_DB1200_PWRGD_R'
 '@BASEBOARD_FAB2_LIB.BASEBOARD_FAB2(SCH_1):FM_DB1200_PWRGD_R':
 C_SIGNAL='@baseboard_fab2_lib.baseboard_fab2(sch_1):fm_db1200_pwrgd_r';
NODE_NAME     EU4D2 6
 '@BASEBOARD_FAB2_LIB.BASEBOARD_FAB2(SCH_1):PAGE102_I1@MSTR_CLOCK.NB3W1200L(CHIPS)':
 'PWRGD_PWRDN_N': CDS_PINID='PWRGD_PWRDN_N';
NODE_NAME     R4W6 2
 '@BASEBOARD_FAB2_LIB.BASEBOARD_FAB2(SCH_1):PAGE102_I109@MSTR_DISCRETE.RES(CHIPS)':
 'B': CDS_PINID='B';
NODE_NAME     Q4W2 3
 '@BASEBOARD_FAB2_LIB.BASEBOARD_FAB2(SCH_1):PAGE102_I112@MSTR_DISCRETE.FET_N(CHIPS)':
 'DRN': CDS_PINID='DRN';
NODE_NAME     R4W5 2
 '@BASEBOARD_FAB2_LIB.BASEBOARD_FAB2(SCH_1):PAGE102_I114@MSTR_DISCRETE.RES(CHIPS)':
 'B': CDS_PINID='B';
NET_NAME
'FM_DB1200_SMB_SA0'
 '@BASEBOARD_FAB2_LIB.BASEBOARD_FAB2(SCH_1):FM_DB1200_SMB_SA0':
 C_SIGNAL='@baseboard_fab2_lib.baseboard_fab2(sch_1):fm_db1200_smb_sa0';
NODE_NAME     EU4D2 11
 '@BASEBOARD_FAB2_LIB.BASEBOARD_FAB2(SCH_1):PAGE102_I1@MSTR_CLOCK.NB3W1200L(CHIPS)':
 'SA_0': CDS_PINID='SA_0';
NODE_NAME     R4D35 2
 '@BASEBOARD_FAB2_LIB.BASEBOARD_FAB2(SCH_1):PAGE102_I38@MSTR_DISCRETE.RES(CHIPS)':
 'B': CDS_PINID='B';
NODE_NAME     R6P21 1
 '@BASEBOARD_FAB2_LIB.BASEBOARD_FAB2(SCH_1):PAGE102_I80@MSTR_DISCRETE.RES(CHIPS)':
 'A': CDS_PINID='A';
NET_NAME
'FM_DB1200_SMB_SA1'
 '@BASEBOARD_FAB2_LIB.BASEBOARD_FAB2(SCH_1):FM_DB1200_SMB_SA1':
 C_SIGNAL='@baseboard_fab2_lib.baseboard_fab2(sch_1):fm_db1200_smb_sa1';
NODE_NAME     EU4D2 14
 '@BASEBOARD_FAB2_LIB.BASEBOARD_FAB2(SCH_1):PAGE102_I1@MSTR_CLOCK.NB3W1200L(CHIPS)':
 'SA_1': CDS_PINID='SA_1';
NODE_NAME     R4D38 2
 '@BASEBOARD_FAB2_LIB.BASEBOARD_FAB2(SCH_1):PAGE102_I37@MSTR_DISCRETE.RES(CHIPS)':
 'B': CDS_PINID='B';
NODE_NAME     R6P20 1
 '@BASEBOARD_FAB2_LIB.BASEBOARD_FAB2(SCH_1):PAGE102_I81@MSTR_DISCRETE.RES(CHIPS)':
 'A': CDS_PINID='A';
NET_NAME
'FM_DB_PRESENT'
 '@BASEBOARD_FAB2_LIB.BASEBOARD_FAB2(SCH_1):FM_DB_PRESENT':
 C_SIGNAL='@baseboard_fab2_lib.baseboard_fab2(sch_1):fm_db_present';
NODE_NAME     Q1L3 3
 '@BASEBOARD_FAB2_LIB.BASEBOARD_FAB2(SCH_1):PAGE168_I8@MSTR_DISCRETE.NPN(CHIPS)':
 'C': CDS_PINID='C';
NODE_NAME     R1L36 2
 '@BASEBOARD_FAB2_LIB.BASEBOARD_FAB2(SCH_1):PAGE168_I11@MSTR_DISCRETE.RES(CHIPS)':
 'B': CDS_PINID='B';
NODE_NAME     Q1L4 2
 '@BASEBOARD_FAB2_LIB.BASEBOARD_FAB2(SCH_1):PAGE168_I19@MSTR_DISCRETE.FET_N_DUAL(CHIPS)':
 'GATE'<0>: CDS_PINID='GATE(0)';
NET_NAME
'FM_DB_UART_SEL0_N'
 '@BASEBOARD_FAB2_LIB.BASEBOARD_FAB2(SCH_1):FM_DB_UART_SEL0_N':
 C_SIGNAL='@baseboard_fab2_lib.baseboard_fab2(sch_1):fm_db_uart_sel0_n';
NODE_NAME     CR1L1 2
 '@BASEBOARD_FAB2_LIB.BASEBOARD_FAB2(SCH_1):PAGE168_I2@MSTR_DISCRETE.DIODE(CHIPS)':
 'A': CDS_PINID='A';
NODE_NAME     R1L6 2
 '@BASEBOARD_FAB2_LIB.BASEBOARD_FAB2(SCH_1):PAGE168_I6@MSTR_DISCRETE.RES(CHIPS)':
 'B': CDS_PINID='B';
NET_NAME
'FM_DB_UART_SEL1_N'
 '@BASEBOARD_FAB2_LIB.BASEBOARD_FAB2(SCH_1):FM_DB_UART_SEL1_N':
 C_SIGNAL='@baseboard_fab2_lib.baseboard_fab2(sch_1):fm_db_uart_sel1_n';
NODE_NAME     CR1L1 1
 '@BASEBOARD_FAB2_LIB.BASEBOARD_FAB2(SCH_1):PAGE168_I2@MSTR_DISCRETE.DIODE(CHIPS)':
 'C': CDS_PINID='C';
NODE_NAME     CR1L2 2
 '@BASEBOARD_FAB2_LIB.BASEBOARD_FAB2(SCH_1):PAGE168_I3@MSTR_DISCRETE.DIODE(CHIPS)':
 'A': CDS_PINID='A';
NET_NAME
'FM_DB_UART_SEL2_N'
 '@BASEBOARD_FAB2_LIB.BASEBOARD_FAB2(SCH_1):FM_DB_UART_SEL2_N':
 C_SIGNAL='@baseboard_fab2_lib.baseboard_fab2(sch_1):fm_db_uart_sel2_n';
NODE_NAME     CR1L2 1
 '@BASEBOARD_FAB2_LIB.BASEBOARD_FAB2(SCH_1):PAGE168_I3@MSTR_DISCRETE.DIODE(CHIPS)':
 'C': CDS_PINID='C';
NODE_NAME     CR1L3 2
 '@BASEBOARD_FAB2_LIB.BASEBOARD_FAB2(SCH_1):PAGE168_I4@MSTR_DISCRETE.DIODE(CHIPS)':
 'A': CDS_PINID='A';
NET_NAME
'FM_DB_UART_SEL3_N'
 '@BASEBOARD_FAB2_LIB.BASEBOARD_FAB2(SCH_1):FM_DB_UART_SEL3_N':
 C_SIGNAL='@baseboard_fab2_lib.baseboard_fab2(sch_1):fm_db_uart_sel3_n';
NODE_NAME     CR1L3 1
 '@BASEBOARD_FAB2_LIB.BASEBOARD_FAB2(SCH_1):PAGE168_I4@MSTR_DISCRETE.DIODE(CHIPS)':
 'C': CDS_PINID='C';
NODE_NAME     CR1L4 2
 '@BASEBOARD_FAB2_LIB.BASEBOARD_FAB2(SCH_1):PAGE168_I5@MSTR_DISCRETE.DIODE(CHIPS)':
 'A': CDS_PINID='A';
NET_NAME
'FM_DB_UART_SEL4_N'
 '@BASEBOARD_FAB2_LIB.BASEBOARD_FAB2(SCH_1):FM_DB_UART_SEL4_N':
 C_SIGNAL='@baseboard_fab2_lib.baseboard_fab2(sch_1):fm_db_uart_sel4_n';
NODE_NAME     CR1L4 1
 '@BASEBOARD_FAB2_LIB.BASEBOARD_FAB2(SCH_1):PAGE168_I5@MSTR_DISCRETE.DIODE(CHIPS)':
 'C': CDS_PINID='C';
NODE_NAME     Q1L3 1
 '@BASEBOARD_FAB2_LIB.BASEBOARD_FAB2(SCH_1):PAGE168_I8@MSTR_DISCRETE.NPN(CHIPS)':
 'B': CDS_PINID='B';
NET_NAME
'FM_DEBUG_RST_BTN_N'
 '@BASEBOARD_FAB2_LIB.BASEBOARD_FAB2(SCH_1):FM_DEBUG_RST_BTN_N':
 C_SIGNAL='@baseboard_fab2_lib.baseboard_fab2(sch_1):fm_debug_rst_btn_n';
NODE_NAME     R1L29 2
 '@BASEBOARD_FAB2_LIB.BASEBOARD_FAB2(SCH_1):PAGE111_I68@MSTR_DISCRETE.RES(CHIPS)':
 'B': CDS_PINID='B';
NODE_NAME     J9A2 11
 '@BASEBOARD_FAB2_LIB.BASEBOARD_FAB2(SCH_1):PAGE155_I171@MSTR_CONN.CONN14_H54902001(CHIPS)':
 'IO11': CDS_PINID='IO11';
NODE_NAME     R1L22 1
 '@BASEBOARD_FAB2_LIB.BASEBOARD_FAB2(SCH_1):PAGE175_I22@MSTR_DISCRETE.RES(CHIPS)':
 'A': CDS_PINID='A';
NODE_NAME     S9A1 1
 '@BASEBOARD_FAB2_LIB.BASEBOARD_FAB2(SCH_1):PAGE175_I78@MSTR_MISC.SWITCH_D37771002(CHIPS)':
 'PIN1': CDS_PINID='PIN1';
NODE_NAME     S9A1 2
 '@BASEBOARD_FAB2_LIB.BASEBOARD_FAB2(SCH_1):PAGE175_I78@MSTR_MISC.SWITCH_D37771002(CHIPS)':
 'PIN2': CDS_PINID='PIN2';
NODE_NAME     U8D7 G5
 '@BASEBOARD_FAB2_LIB.BASEBOARD_FAB2(SCH_1):PAGE190_I179@MSTR_MEMORY.LCMXO2_A(CHIPS)':
 'PL4C': CDS_PINID='PL4C';
NODE_NAME     U6W1 13
 '@BASEBOARD_FAB2_LIB.BASEBOARD_FAB2(SCH_1):PAGE247_I120@W_HDL.TCA9555PWR-GP(CHIPS)':
 'P10': CDS_PINID='P10';
NODE_NAME     R1L19 2
 '@BASEBOARD_FAB2_LIB.BASEBOARD_FAB2(SCH_1):PAGE175_I99@MSTR_DISCRETE.RES(CHIPS)':
 'B': CDS_PINID='B';
NET_NAME
'FM_DEBUG_RST_BTN_R1_N'
 '@BASEBOARD_FAB2_LIB.BASEBOARD_FAB2(SCH_1):FM_DEBUG_RST_BTN_R1_N':
 C_SIGNAL='@baseboard_fab2_lib.baseboard_fab2(sch_1):fm_debug_rst_btn_r1_n';
NODE_NAME     R1L29 1
 '@BASEBOARD_FAB2_LIB.BASEBOARD_FAB2(SCH_1):PAGE111_I68@MSTR_DISCRETE.RES(CHIPS)':
 'A': CDS_PINID='A';
NODE_NAME     U1L4 4
 '@BASEBOARD_FAB2_LIB.BASEBOARD_FAB2(SCH_1):PAGE111_I85@MSTR_TTL.TTL1G07_A(CHIPS)':
 'Y': CDS_PINID='Y';
NODE_NAME     R1L28 2
 '@BASEBOARD_FAB2_LIB.BASEBOARD_FAB2(SCH_1):PAGE111_I97@MSTR_DISCRETE.RES(CHIPS)':
 'B': CDS_PINID='B';
NET_NAME
'FM_DIMM_EVENT_COD_N'
 '@BASEBOARD_FAB2_LIB.BASEBOARD_FAB2(SCH_1):FM_DIMM_EVENT_COD_N':
 C_SIGNAL='@baseboard_fab2_lib.baseboard_fab2(sch_1):fm_dimm_event_cod_n';
NODE_NAME     J4G1 78
 '@BASEBOARD_FAB2_LIB.BASEBOARD_FAB2(SCH_1):PAGE43_I1@MSTR_SCONN.SCONN288_H44441004(CHIPS)':
 'EVENT_N': CDS_PINID='EVENT_N';
NODE_NAME     J6T1 78
 '@BASEBOARD_FAB2_LIB.BASEBOARD_FAB2(SCH_1):PAGE44_I13@MSTR_SCONN.SCONN288_H44441003(CHIPS)':
 'EVENT_N': CDS_PINID='EVENT_N';
NODE_NAME     J4G2 78
 '@BASEBOARD_FAB2_LIB.BASEBOARD_FAB2(SCH_1):PAGE45_I111@MSTR_SCONN.SCONN288_H44441004(CHIPS)':
 'EVENT_N': CDS_PINID='EVENT_N';
NODE_NAME     J6U1 78
 '@BASEBOARD_FAB2_LIB.BASEBOARD_FAB2(SCH_1):PAGE46_I14@MSTR_SCONN.SCONN288_H44441003(CHIPS)':
 'EVENT_N': CDS_PINID='EVENT_N';
NODE_NAME     J4G3 78
 '@BASEBOARD_FAB2_LIB.BASEBOARD_FAB2(SCH_1):PAGE47_I111@MSTR_SCONN.SCONN288_H44441004(CHIPS)':
 'EVENT_N': CDS_PINID='EVENT_N';
NODE_NAME     J6U2 78
 '@BASEBOARD_FAB2_LIB.BASEBOARD_FAB2(SCH_1):PAGE48_I111@MSTR_SCONN.SCONN288_H44441003(CHIPS)':
 'EVENT_N': CDS_PINID='EVENT_N';
NODE_NAME     J4B1 78
 '@BASEBOARD_FAB2_LIB.BASEBOARD_FAB2(SCH_1):PAGE49_I111@MSTR_SCONN.SCONN288_H44441004(CHIPS)':
 'EVENT_N': CDS_PINID='EVENT_N';
NODE_NAME     J6M1 78
 '@BASEBOARD_FAB2_LIB.BASEBOARD_FAB2(SCH_1):PAGE50_I158@MSTR_SCONN.SCONN288_H44441003(CHIPS)':
 'EVENT_N': CDS_PINID='EVENT_N';
NODE_NAME     J4A2 78
 '@BASEBOARD_FAB2_LIB.BASEBOARD_FAB2(SCH_1):PAGE51_I111@MSTR_SCONN.SCONN288_H44441004(CHIPS)':
 'EVENT_N': CDS_PINID='EVENT_N';
NODE_NAME     J6L2 78
 '@BASEBOARD_FAB2_LIB.BASEBOARD_FAB2(SCH_1):PAGE52_I12@MSTR_SCONN.SCONN288_H44441003(CHIPS)':
 'EVENT_N': CDS_PINID='EVENT_N';
NODE_NAME     J4A1 78
 '@BASEBOARD_FAB2_LIB.BASEBOARD_FAB2(SCH_1):PAGE53_I111@MSTR_SCONN.SCONN288_H44441004(CHIPS)':
 'EVENT_N': CDS_PINID='EVENT_N';
NODE_NAME     J6L1 78
 '@BASEBOARD_FAB2_LIB.BASEBOARD_FAB2(SCH_1):PAGE54_I111@MSTR_SCONN.SCONN288_H44441003(CHIPS)':
 'EVENT_N': CDS_PINID='EVENT_N';
NODE_NAME     J1G1 78
 '@BASEBOARD_FAB2_LIB.BASEBOARD_FAB2(SCH_1):PAGE77_I111@MSTR_SCONN.SCONN288_H44441004(CHIPS)':
 'EVENT_N': CDS_PINID='EVENT_N';
NODE_NAME     J9T1 78
 '@BASEBOARD_FAB2_LIB.BASEBOARD_FAB2(SCH_1):PAGE78_I13@MSTR_SCONN.SCONN288_H44441003(CHIPS)':
 'EVENT_N': CDS_PINID='EVENT_N';
NODE_NAME     J1G2 78
 '@BASEBOARD_FAB2_LIB.BASEBOARD_FAB2(SCH_1):PAGE79_I111@MSTR_SCONN.SCONN288_H44441004(CHIPS)':
 'EVENT_N': CDS_PINID='EVENT_N';
NODE_NAME     J9U1 78
 '@BASEBOARD_FAB2_LIB.BASEBOARD_FAB2(SCH_1):PAGE80_I24@MSTR_SCONN.SCONN288_H44441003(CHIPS)':
 'EVENT_N': CDS_PINID='EVENT_N';
NODE_NAME     J1G3 78
 '@BASEBOARD_FAB2_LIB.BASEBOARD_FAB2(SCH_1):PAGE81_I186@MSTR_SCONN.SCONN288_H44441004(CHIPS)':
 'EVENT_N': CDS_PINID='EVENT_N';
NODE_NAME     J9U2 78
 '@BASEBOARD_FAB2_LIB.BASEBOARD_FAB2(SCH_1):PAGE82_I187@MSTR_SCONN.SCONN288_H44441003(CHIPS)':
 'EVENT_N': CDS_PINID='EVENT_N';
NODE_NAME     J1B1 78
 '@BASEBOARD_FAB2_LIB.BASEBOARD_FAB2(SCH_1):PAGE83_I111@MSTR_SCONN.SCONN288_H44441004(CHIPS)':
 'EVENT_N': CDS_PINID='EVENT_N';
NODE_NAME     J9M1 78
 '@BASEBOARD_FAB2_LIB.BASEBOARD_FAB2(SCH_1):PAGE84_I14@MSTR_SCONN.SCONN288_H44441003(CHIPS)':
 'EVENT_N': CDS_PINID='EVENT_N';
NODE_NAME     J1A2 78
 '@BASEBOARD_FAB2_LIB.BASEBOARD_FAB2(SCH_1):PAGE85_I111@MSTR_SCONN.SCONN288_H44441004(CHIPS)':
 'EVENT_N': CDS_PINID='EVENT_N';
NODE_NAME     J9L2 78
 '@BASEBOARD_FAB2_LIB.BASEBOARD_FAB2(SCH_1):PAGE86_I12@MSTR_SCONN.SCONN288_H44441003(CHIPS)':
 'EVENT_N': CDS_PINID='EVENT_N';
NODE_NAME     J1A1 78
 '@BASEBOARD_FAB2_LIB.BASEBOARD_FAB2(SCH_1):PAGE87_I186@MSTR_SCONN.SCONN288_H44441004(CHIPS)':
 'EVENT_N': CDS_PINID='EVENT_N';
NODE_NAME     J9L1 78
 '@BASEBOARD_FAB2_LIB.BASEBOARD_FAB2(SCH_1):PAGE88_I111@MSTR_SCONN.SCONN288_H44441003(CHIPS)':
 'EVENT_N': CDS_PINID='EVENT_N';
NODE_NAME     Q4U1 2
 '@BASEBOARD_FAB2_LIB.BASEBOARD_FAB2(SCH_1):PAGE94_I98@MSTR_DISCRETE.FET_N_DUAL(CHIPS)':
 'GATE'<0>: CDS_PINID='GATE(0)';
NODE_NAME     R4U2 2
 '@BASEBOARD_FAB2_LIB.BASEBOARD_FAB2(SCH_1):PAGE94_I100@MSTR_DISCRETE.RES(CHIPS)':
 'B': CDS_PINID='B';
NET_NAME
'FM_DIMM_EVENT_FET'
 '@BASEBOARD_FAB2_LIB.BASEBOARD_FAB2(SCH_1):FM_DIMM_EVENT_FET':
 C_SIGNAL='@baseboard_fab2_lib.baseboard_fab2(sch_1):fm_dimm_event_fet';
NODE_NAME     R4U3 2
 '@BASEBOARD_FAB2_LIB.BASEBOARD_FAB2(SCH_1):PAGE94_I94@MSTR_DISCRETE.RES(CHIPS)':
 'B': CDS_PINID='B';
NODE_NAME     Q4U1 6
 '@BASEBOARD_FAB2_LIB.BASEBOARD_FAB2(SCH_1):PAGE94_I98@MSTR_DISCRETE.FET_N_DUAL(CHIPS)':
 'DRAIN'<0>: CDS_PINID='DRAIN(0)';
NODE_NAME     Q4U1 5
 '@BASEBOARD_FAB2_LIB.BASEBOARD_FAB2(SCH_1):PAGE94_I102@MSTR_DISCRETE.FET_N_DUAL(CHIPS)':
 'GATE'<0>: CDS_PINID='GATE(0)';
NODE_NAME     R4U4 1
 '@BASEBOARD_FAB2_LIB.BASEBOARD_FAB2(SCH_1):PAGE94_I104@MSTR_DISCRETE.RES(CHIPS)':
 'A': CDS_PINID='A';
NET_NAME
'FM_DISABLE_FAN_N'
 '@BASEBOARD_FAB2_LIB.BASEBOARD_FAB2(SCH_1):FM_DISABLE_FAN_N':
 C_SIGNAL='@baseboard_fab2_lib.baseboard_fab2(sch_1):fm_disable_fan_n';
NODE_NAME     U1E2 2
 '@BASEBOARD_FAB2_LIB.BASEBOARD_FAB2(SCH_1):PAGE161_I121@MSTR_TTL.TTL1G08(CHIPS)':
 'B'<0>: CDS_PINID='B(0)';
NODE_NAME     CR9P2 2
 '@BASEBOARD_FAB2_LIB.BASEBOARD_FAB2(SCH_1):PAGE200_I213@MSTR_DISCRETE.DIODE(CHIPS)':
 'A': CDS_PINID='A';
NODE_NAME     CR9P1 2
 '@BASEBOARD_FAB2_LIB.BASEBOARD_FAB2(SCH_1):PAGE200_I214@MSTR_DISCRETE.DIODE(CHIPS)':
 'A': CDS_PINID='A';
NODE_NAME     R9P5 2
 '@BASEBOARD_FAB2_LIB.BASEBOARD_FAB2(SCH_1):PAGE200_I215@MSTR_DISCRETE.RES(CHIPS)':
 'B': CDS_PINID='B';
NET_NAME
'FM_DIS_ADR_DLY'
 '@BASEBOARD_FAB2_LIB.BASEBOARD_FAB2(SCH_1):FM_DIS_ADR_DLY':
 C_SIGNAL='@baseboard_fab2_lib.baseboard_fab2(sch_1):fm_dis_adr_dly';
NODE_NAME     R2P19 2
 '@BASEBOARD_FAB2_LIB.BASEBOARD_FAB2(SCH_1):PAGE135_I107@MSTR_DISCRETE.RES(CHIPS)':
 'B': CDS_PINID='B';
NODE_NAME     J8G2 10
 '@BASEBOARD_FAB2_LIB.BASEBOARD_FAB2(SCH_1):PAGE135_I124@MSTR_CONN.CONN12_C73564003(CHIPS)':
 'IO10': CDS_PINID='IO10';
NODE_NAME     U8D7 T3
 '@BASEBOARD_FAB2_LIB.BASEBOARD_FAB2(SCH_1):PAGE190_I179@MSTR_MEMORY.LCMXO2_A(CHIPS)':
 'PB6C': CDS_PINID='PB6C';
NET_NAME
'FM_DUAL_BIOS_SEL_N'
 '@BASEBOARD_FAB2_LIB.BASEBOARD_FAB2(SCH_1):FM_DUAL_BIOS_SEL_N':
 C_SIGNAL='@baseboard_fab2_lib.baseboard_fab2(sch_1):fm_dual_bios_sel_n';
NODE_NAME     U2T3 1
 '@BASEBOARD_FAB2_LIB.BASEBOARD_FAB2(SCH_1):PAGE154_I99@MSTR_TTL.TTL1G32_A(CHIPS)':
 'A': CDS_PINID='A';
NODE_NAME     R2T11 2
 '@BASEBOARD_FAB2_LIB.BASEBOARD_FAB2(SCH_1):PAGE154_I105@MSTR_DISCRETE.RES(CHIPS)':
 'B': CDS_PINID='B';
NODE_NAME     Q8F1 3
 '@BASEBOARD_FAB2_LIB.BASEBOARD_FAB2(SCH_1):PAGE154_I126@MSTR_DISCRETE.FET_N(CHIPS)':
 'DRN': CDS_PINID='DRN';
NET_NAME
'FM_ENABLE_FAN_POWER'
 '@BASEBOARD_FAB2_LIB.BASEBOARD_FAB2(SCH_1):FM_ENABLE_FAN_POWER':
 C_SIGNAL='@baseboard_fab2_lib.baseboard_fab2(sch_1):fm_enable_fan_power';
NODE_NAME     R1E11 2
 '@BASEBOARD_FAB2_LIB.BASEBOARD_FAB2(SCH_1):PAGE161_I120@MSTR_DISCRETE.RES(CHIPS)':
 'B': CDS_PINID='B';
NODE_NAME     U1E2 4
 '@BASEBOARD_FAB2_LIB.BASEBOARD_FAB2(SCH_1):PAGE161_I121@MSTR_TTL.TTL1G08(CHIPS)':
 'Y'<0>: CDS_PINID='Y(0)';
NODE_NAME     EU9M1 2
 '@BASEBOARD_FAB2_LIB.BASEBOARD_FAB2(SCH_1):PAGE198_I69@MSTR_VREG.SLG55021(CHIPS)':
 'ON': CDS_PINID='\on\';
NODE_NAME     J1F1 I3
 '@BASEBOARD_FAB2_LIB.BASEBOARD_FAB2(SCH_1):PAGE181_I134@W_HDL.DM-FCI-CONN76-8R-GP-U-01(CHIPS)':
 'MB_ON#': CDS_PINID='\mb_on#\';
NET_NAME
'FM_FAST_PROCHOT_AND_OUT_0_N'
 '@BASEBOARD_FAB2_LIB.BASEBOARD_FAB2(SCH_1):FM_FAST_PROCHOT_AND_OUT_0_N':
 C_SIGNAL='@baseboard_fab2_lib.baseboard_fab2(sch_1):fm_fast_prochot_and_out_0_n~
';
NODE_NAME     U8E1 3
 '@BASEBOARD_FAB2_LIB.BASEBOARD_FAB2(SCH_1):PAGE170_I10@MSTR_TTL.TTL08(CHIPS)':
 'Y'<0>: CDS_PINID='Y(0)';
NODE_NAME     U8E1 12
 '@BASEBOARD_FAB2_LIB.BASEBOARD_FAB2(SCH_1):PAGE170_I12@MSTR_TTL.TTL08(CHIPS)':
 'A'<0>: CDS_PINID='A(0)';
NET_NAME
'FM_FAST_PROCHOT_AND_OUT_1_N'
 '@BASEBOARD_FAB2_LIB.BASEBOARD_FAB2(SCH_1):FM_FAST_PROCHOT_AND_OUT_1_N':
 C_SIGNAL='@baseboard_fab2_lib.baseboard_fab2(sch_1):fm_fast_prochot_and_out_1_n~
';
NODE_NAME     U8E1 6
 '@BASEBOARD_FAB2_LIB.BASEBOARD_FAB2(SCH_1):PAGE170_I11@MSTR_TTL.TTL08(CHIPS)':
 'Y'<0>: CDS_PINID='Y(0)';
NODE_NAME     U8E1 13
 '@BASEBOARD_FAB2_LIB.BASEBOARD_FAB2(SCH_1):PAGE170_I12@MSTR_TTL.TTL08(CHIPS)':
 'B'<0>: CDS_PINID='B(0)';
NET_NAME
'FM_FAST_PROCHOT_EN'
 '@BASEBOARD_FAB2_LIB.BASEBOARD_FAB2(SCH_1):FM_FAST_PROCHOT_EN':
 C_SIGNAL='@baseboard_fab2_lib.baseboard_fab2(sch_1):fm_fast_prochot_en';
NODE_NAME     U1R2 1
 '@BASEBOARD_FAB2_LIB.BASEBOARD_FAB2(SCH_1):PAGE170_I20@MSTR_TTL.TTL1G126_A(CHIPS)':
 'OE': CDS_PINID='OE';
NODE_NAME     R9F3 2
 '@BASEBOARD_FAB2_LIB.BASEBOARD_FAB2(SCH_1):PAGE170_I65@MSTR_DISCRETE.RES(CHIPS)':
 'B': CDS_PINID='B';
NODE_NAME     Q8F2 3
 '@BASEBOARD_FAB2_LIB.BASEBOARD_FAB2(SCH_1):PAGE170_I67@MSTR_DISCRETE.FET_N(CHIPS)':
 'DRN': CDS_PINID='DRN';
NET_NAME
'FM_FAST_PROCHOT_EN_N'
 '@BASEBOARD_FAB2_LIB.BASEBOARD_FAB2(SCH_1):FM_FAST_PROCHOT_EN_N':
 C_SIGNAL='@baseboard_fab2_lib.baseboard_fab2(sch_1):fm_fast_prochot_en_n';
NODE_NAME     U7C1 BH17
 '@BASEBOARD_FAB2_LIB.BASEBOARD_FAB2(SCH_1):PAGE119_I115@MSTR_U_PROC.LBG_CORE_QAT_EXT_D(CHIPS)':
 'GPP_B21': CDS_PINID='GPP_B21';
NODE_NAME     R2T3 2
 '@BASEBOARD_FAB2_LIB.BASEBOARD_FAB2(SCH_1):PAGE170_I54@MSTR_DISCRETE.RES(CHIPS)':
 'B': CDS_PINID='B';
NODE_NAME     Q8F2 1
 '@BASEBOARD_FAB2_LIB.BASEBOARD_FAB2(SCH_1):PAGE170_I67@MSTR_DISCRETE.FET_N(CHIPS)':
 'GATE': CDS_PINID='GATE';
NODE_NAME     U25W4 C1
 '@BASEBOARD_FAB2_LIB.BASEBOARD_FAB2(SCH_1):PAGE147_I106@W_HDL.AST2520A1-GP-GP(CHIPS)':
 'RGMII2RXCTL_GPIOV3': CDS_PINID='RGMII2RXCTL_GPIOV3';
NET_NAME
'FM_FAST_PROCHOT_THROTTLE_DLY_BU'
 '@BASEBOARD_FAB2_LIB.BASEBOARD_FAB2(SCH_1):FM_FAST_PROCHOT_THROTTLE_DLY_BUF_N':
 C_SIGNAL='@baseboard_fab2_lib.baseboard_fab2(sch_1):fm_fast_prochot_throttle_dl~
y_buf_n';
NODE_NAME     U1R2 4
 '@BASEBOARD_FAB2_LIB.BASEBOARD_FAB2(SCH_1):PAGE170_I20@MSTR_TTL.TTL1G126_A(CHIPS)':
 'Y': CDS_PINID='Y';
NODE_NAME     U1R1 2
 '@BASEBOARD_FAB2_LIB.BASEBOARD_FAB2(SCH_1):PAGE170_I46@MSTR_TTL.TTL1G07_A(CHIPS)':
 'A': CDS_PINID='A';
NODE_NAME     R1R5 2
 '@BASEBOARD_FAB2_LIB.BASEBOARD_FAB2(SCH_1):PAGE170_I73@MSTR_DISCRETE.RES(CHIPS)':
 'B': CDS_PINID='B';
NET_NAME
'FM_FAST_PROCHOT_THROTTLE_DLY_N'
 '@BASEBOARD_FAB2_LIB.BASEBOARD_FAB2(SCH_1):FM_FAST_PROCHOT_THROTTLE_DLY_N':
 C_SIGNAL='@baseboard_fab2_lib.baseboard_fab2(sch_1):fm_fast_prochot_throttle_dl~
y_n';
NODE_NAME     U1R2 2
 '@BASEBOARD_FAB2_LIB.BASEBOARD_FAB2(SCH_1):PAGE170_I20@MSTR_TTL.TTL1G126_A(CHIPS)':
 'A': CDS_PINID='A';
NODE_NAME     U8D7 J12
 '@BASEBOARD_FAB2_LIB.BASEBOARD_FAB2(SCH_1):PAGE191_I59@MSTR_MEMORY.LCMXO2_A(CHIPS)':
 'PR6D': CDS_PINID='PR6D';
NET_NAME
'FM_FAST_PROCHOT_THROTTLE_IN_N'
 '@BASEBOARD_FAB2_LIB.BASEBOARD_FAB2(SCH_1):FM_FAST_PROCHOT_THROTTLE_IN_N':
 C_SIGNAL='@baseboard_fab2_lib.baseboard_fab2(sch_1):fm_fast_prochot_throttle_in~
_n';
NODE_NAME     U8E1 11
 '@BASEBOARD_FAB2_LIB.BASEBOARD_FAB2(SCH_1):PAGE170_I12@MSTR_TTL.TTL08(CHIPS)':
 'Y'<0>: CDS_PINID='Y(0)';
NODE_NAME     U8D7 G16
 '@BASEBOARD_FAB2_LIB.BASEBOARD_FAB2(SCH_1):PAGE191_I59@MSTR_MEMORY.LCMXO2_A(CHIPS)':
 'PR6A': CDS_PINID='PR6A';
NET_NAME
'FM_FLASH_ATTACH_CFG_STRAP'
 '@BASEBOARD_FAB2_LIB.BASEBOARD_FAB2(SCH_1):FM_FLASH_ATTACH_CFG_STRAP':
 C_SIGNAL='@baseboard_fab2_lib.baseboard_fab2(sch_1):fm_flash_attach_cfg_strap';
NODE_NAME     U7C1 BB1
 '@BASEBOARD_FAB2_LIB.BASEBOARD_FAB2(SCH_1):PAGE120_I147@MSTR_U_PROC.LBG_CORE_QAT_EXT_D(CHIPS)':
 'GPP_H12_SML2ALERT_N_IE_N': CDS_PINID='GPP_H12_SML2ALERT_N_IE_N';
NODE_NAME     R3P62 2
 '@BASEBOARD_FAB2_LIB.BASEBOARD_FAB2(SCH_1):PAGE126_I22@MSTR_DISCRETE.RES(CHIPS)':
 'B': CDS_PINID='B';
NODE_NAME     R3P64 1
 '@BASEBOARD_FAB2_LIB.BASEBOARD_FAB2(SCH_1):PAGE126_I23@MSTR_DISCRETE.RES(CHIPS)':
 'A': CDS_PINID='A';
NET_NAME
'FM_FLASH_DESC_OVERRIDE'
 '@BASEBOARD_FAB2_LIB.BASEBOARD_FAB2(SCH_1):FM_FLASH_DESC_OVERRIDE':
 C_SIGNAL='@baseboard_fab2_lib.baseboard_fab2(sch_1):fm_flash_desc_override';
NODE_NAME     U7C1 U24
 '@BASEBOARD_FAB2_LIB.BASEBOARD_FAB2(SCH_1):PAGE121_I34@MSTR_U_PROC.LBG_CORE_QAT_EXT_D(CHIPS)':
 'HDA_SDO': CDS_PINID='HDA_SDO';
NODE_NAME     R3N2 2
 '@BASEBOARD_FAB2_LIB.BASEBOARD_FAB2(SCH_1):PAGE125_I72@MSTR_DISCRETE.RES(CHIPS)':
 'B': CDS_PINID='B';
NODE_NAME     R1T24 2
 '@BASEBOARD_FAB2_LIB.BASEBOARD_FAB2(SCH_1):PAGE147_I129@MSTR_DISCRETE.RES(CHIPS)':
 'B': CDS_PINID='B';
NET_NAME
'FM_FORCE_ADR_N'
 '@BASEBOARD_FAB2_LIB.BASEBOARD_FAB2(SCH_1):FM_FORCE_ADR_N':
 C_SIGNAL='@baseboard_fab2_lib.baseboard_fab2(sch_1):fm_force_adr_n';
NODE_NAME     U7C1 AR13
 '@BASEBOARD_FAB2_LIB.BASEBOARD_FAB2(SCH_1):PAGE120_I147@MSTR_U_PROC.LBG_CORE_QAT_EXT_D(CHIPS)':
 'GPP_F15_USB2_OC4_N': CDS_PINID='GPP_F15_USB2_OC4_N';
NODE_NAME     U8D7 D7
 '@BASEBOARD_FAB2_LIB.BASEBOARD_FAB2(SCH_1):PAGE191_I59@MSTR_MEMORY.LCMXO2_A(CHIPS)':
 'PT13D': CDS_PINID='PT13D';
NODE_NAME     R2R7 2
 '@BASEBOARD_FAB2_LIB.BASEBOARD_FAB2(SCH_1):PAGE191_I172@MSTR_DISCRETE.RES(CHIPS)':
 'B': CDS_PINID='B';
NODE_NAME     U25W4 B16
 '@BASEBOARD_FAB2_LIB.BASEBOARD_FAB2(SCH_1):PAGE144_I95@W_HDL.AST2520A1-GP-GP(CHIPS)':
 'GPIOI2_SYSMOSI': CDS_PINID='GPIOI2_SYSMOSI';
NET_NAME
'FM_GBE0_LVC3_MOD_ABS'
 '@BASEBOARD_FAB2_LIB.BASEBOARD_FAB2(SCH_1):FM_GBE0_LVC3_MOD_ABS':
 C_SIGNAL='@baseboard_fab2_lib.baseboard_fab2(sch_1):fm_gbe0_lvc3_mod_abs';
NODE_NAME     U7C1 BV10
 '@BASEBOARD_FAB2_LIB.BASEBOARD_FAB2(SCH_1):PAGE120_I147@MSTR_U_PROC.LBG_CORE_QAT_EXT_D(CHIPS)':
 'GPP_J16_LAN_SDP_P0_0': CDS_PINID='GPP_J16_LAN_SDP_P0_0';
NODE_NAME     J8E4 37
 '@BASEBOARD_FAB2_LIB.BASEBOARD_FAB2(SCH_1):PAGE188_I27@MSTR_SCONN.SCONN64_H87568002_A(CHIPS)':
 'IO37': CDS_PINID='IO37';
NODE_NAME     R1W42 2
 '@BASEBOARD_FAB2_LIB.BASEBOARD_FAB2(SCH_1):PAGE188_I131@MSTR_DISCRETE.RES(CHIPS)':
 'B': CDS_PINID='B';
NET_NAME
'FM_GBE1_LVC3_MOD_ABS'
 '@BASEBOARD_FAB2_LIB.BASEBOARD_FAB2(SCH_1):FM_GBE1_LVC3_MOD_ABS':
 C_SIGNAL='@baseboard_fab2_lib.baseboard_fab2(sch_1):fm_gbe1_lvc3_mod_abs';
NODE_NAME     U7C1 BY10
 '@BASEBOARD_FAB2_LIB.BASEBOARD_FAB2(SCH_1):PAGE120_I147@MSTR_U_PROC.LBG_CORE_QAT_EXT_D(CHIPS)':
 'GPP_J18_LAN_SDP_P1_0': CDS_PINID='GPP_J18_LAN_SDP_P1_0';
NODE_NAME     J8E4 38
 '@BASEBOARD_FAB2_LIB.BASEBOARD_FAB2(SCH_1):PAGE188_I27@MSTR_SCONN.SCONN64_H87568002_A(CHIPS)':
 'IO38': CDS_PINID='IO38';
NODE_NAME     R1W43 2
 '@BASEBOARD_FAB2_LIB.BASEBOARD_FAB2(SCH_1):PAGE188_I132@MSTR_DISCRETE.RES(CHIPS)':
 'B': CDS_PINID='B';
NET_NAME
'FM_GBE2_LVC3_MOD_ABS'
 '@BASEBOARD_FAB2_LIB.BASEBOARD_FAB2(SCH_1):FM_GBE2_LVC3_MOD_ABS':
 C_SIGNAL='@baseboard_fab2_lib.baseboard_fab2(sch_1):fm_gbe2_lvc3_mod_abs';
NODE_NAME     U7C1 BW13
 '@BASEBOARD_FAB2_LIB.BASEBOARD_FAB2(SCH_1):PAGE120_I147@MSTR_U_PROC.LBG_CORE_QAT_EXT_D(CHIPS)':
 'GPP_J20_LAN_SDP_P2_0': CDS_PINID='GPP_J20_LAN_SDP_P2_0';
NODE_NAME     J8E4 31
 '@BASEBOARD_FAB2_LIB.BASEBOARD_FAB2(SCH_1):PAGE188_I27@MSTR_SCONN.SCONN64_H87568002_A(CHIPS)':
 'IO31': CDS_PINID='IO31';
NODE_NAME     R1W44 2
 '@BASEBOARD_FAB2_LIB.BASEBOARD_FAB2(SCH_1):PAGE188_I133@MSTR_DISCRETE.RES(CHIPS)':
 'B': CDS_PINID='B';
NET_NAME
'FM_GBE3_LVC3_MOD_ABS'
 '@BASEBOARD_FAB2_LIB.BASEBOARD_FAB2(SCH_1):FM_GBE3_LVC3_MOD_ABS':
 C_SIGNAL='@baseboard_fab2_lib.baseboard_fab2(sch_1):fm_gbe3_lvc3_mod_abs';
NODE_NAME     U7C1 BY12
 '@BASEBOARD_FAB2_LIB.BASEBOARD_FAB2(SCH_1):PAGE120_I147@MSTR_U_PROC.LBG_CORE_QAT_EXT_D(CHIPS)':
 'GPP_J22_LAN_SDP_P3_0': CDS_PINID='GPP_J22_LAN_SDP_P3_0';
NODE_NAME     J8E4 32
 '@BASEBOARD_FAB2_LIB.BASEBOARD_FAB2(SCH_1):PAGE188_I27@MSTR_SCONN.SCONN64_H87568002_A(CHIPS)':
 'IO32': CDS_PINID='IO32';
NODE_NAME     R1W45 2
 '@BASEBOARD_FAB2_LIB.BASEBOARD_FAB2(SCH_1):PAGE188_I134@MSTR_DISCRETE.RES(CHIPS)':
 'B': CDS_PINID='B';
NET_NAME
'FM_GBE_LOM_DISABLE_N'
 '@BASEBOARD_FAB2_LIB.BASEBOARD_FAB2(SCH_1):FM_GBE_LOM_DISABLE_N':
 C_SIGNAL='@baseboard_fab2_lib.baseboard_fab2(sch_1):fm_gbe_lom_disable_n';
NODE_NAME     U7C1 A13
 '@BASEBOARD_FAB2_LIB.BASEBOARD_FAB2(SCH_1):PAGE118_I73@MSTR_U_PROC.LBG_CORE_QAT_EXT_D(CHIPS)':
 'GPD11_GBEPHY': CDS_PINID='GPD11_GBEPHY';
NODE_NAME     R8C24 1
 '@BASEBOARD_FAB2_LIB.BASEBOARD_FAB2(SCH_1):PAGE118_I120@MSTR_DISCRETE.RES(CHIPS)':
 'A': CDS_PINID='A';
NODE_NAME     R8C23 1
 '@BASEBOARD_FAB2_LIB.BASEBOARD_FAB2(SCH_1):PAGE118_I125@MSTR_DISCRETE.RES(CHIPS)':
 'A': CDS_PINID='A';
NODE_NAME     R2N6 2
 '@BASEBOARD_FAB2_LIB.BASEBOARD_FAB2(SCH_1):PAGE118_I128@MSTR_DISCRETE.RES(CHIPS)':
 'B': CDS_PINID='B';
NET_NAME
'FM_GLOBAL_RST_WARN_N'
 '@BASEBOARD_FAB2_LIB.BASEBOARD_FAB2(SCH_1):FM_GLOBAL_RST_WARN_N':
 C_SIGNAL='@baseboard_fab2_lib.baseboard_fab2(sch_1):fm_global_rst_warn_n';
NODE_NAME     U7C1 BL18
 '@BASEBOARD_FAB2_LIB.BASEBOARD_FAB2(SCH_1):PAGE119_I115@MSTR_U_PROC.LBG_CORE_QAT_EXT_D(CHIPS)':
 'GPP_B12_GLB_RST_WARN_N': CDS_PINID='GPP_B12_GLB_RST_WARN_N';
NODE_NAME     U8D7 P1
 '@BASEBOARD_FAB2_LIB.BASEBOARD_FAB2(SCH_1):PAGE190_I179@MSTR_MEMORY.LCMXO2_A(CHIPS)':
 'PL13D': CDS_PINID='PL13D';
NODE_NAME     R25W143 2
 '@BASEBOARD_FAB2_LIB.BASEBOARD_FAB2(SCH_1):PAGE147_I159@MSTR_DISCRETE.RES(CHIPS)':
 'B': CDS_PINID='B';
NET_NAME
'FM_GLOBAL_RST_WARN_N_R'
 '@BASEBOARD_FAB2_LIB.BASEBOARD_FAB2(SCH_1):FM_GLOBAL_RST_WARN_N_R':
 C_SIGNAL='@baseboard_fab2_lib.baseboard_fab2(sch_1):fm_global_rst_warn_n_r';
NODE_NAME     U25W4 F1
 '@BASEBOARD_FAB2_LIB.BASEBOARD_FAB2(SCH_1):PAGE147_I106@W_HDL.AST2520A1-GP-GP(CHIPS)':
 'ADC11_GPIX3': CDS_PINID='ADC11_GPIX3';
NODE_NAME     R25W143 1
 '@BASEBOARD_FAB2_LIB.BASEBOARD_FAB2(SCH_1):PAGE147_I159@MSTR_DISCRETE.RES(CHIPS)':
 'A': CDS_PINID='A';
NET_NAME
'FM_HBW_BYPASS_LOWBW_N'
 '@BASEBOARD_FAB2_LIB.BASEBOARD_FAB2(SCH_1):FM_HBW_BYPASS_LOWBW_N':
 C_SIGNAL='@baseboard_fab2_lib.baseboard_fab2(sch_1):fm_hbw_bypass_lowbw_n';
NODE_NAME     EU4D2 5
 '@BASEBOARD_FAB2_LIB.BASEBOARD_FAB2(SCH_1):PAGE102_I1@MSTR_CLOCK.NB3W1200L(CHIPS)':
 'HBW_BYPASS_LOBW_N': CDS_PINID='HBW_BYPASS_LOBW_N';
NODE_NAME     R6P22 1
 '@BASEBOARD_FAB2_LIB.BASEBOARD_FAB2(SCH_1):PAGE102_I47@MSTR_DISCRETE.RES(CHIPS)':
 'A': CDS_PINID='A';
NODE_NAME     R4D41 2
 '@BASEBOARD_FAB2_LIB.BASEBOARD_FAB2(SCH_1):PAGE102_I53@MSTR_DISCRETE.RES(CHIPS)':
 'B': CDS_PINID='B';
NET_NAME
'FM_HEARTBEAT_LED'
 '@BASEBOARD_FAB2_LIB.BASEBOARD_FAB2(SCH_1):FM_HEARTBEAT_LED':
 C_SIGNAL='@baseboard_fab2_lib.baseboard_fab2(sch_1):fm_heartbeat_led';
NODE_NAME     Q9E1 5
 '@BASEBOARD_FAB2_LIB.BASEBOARD_FAB2(SCH_1):PAGE151_I145@MSTR_DISCRETE.FET_N_DUAL(CHIPS)':
 'GATE'<0>: CDS_PINID='GATE(0)';
NODE_NAME     R9E21 2
 '@BASEBOARD_FAB2_LIB.BASEBOARD_FAB2(SCH_1):PAGE151_I173@MSTR_DISCRETE.RES(CHIPS)':
 'B': CDS_PINID='B';
NODE_NAME     Q9E1 6
 '@BASEBOARD_FAB2_LIB.BASEBOARD_FAB2(SCH_1):PAGE151_I198@MSTR_DISCRETE.FET_N_DUAL(CHIPS)':
 'DRAIN'<0>: CDS_PINID='DRAIN(0)';
NET_NAME
'FM_HEARTBEAT_LED_A'
 '@BASEBOARD_FAB2_LIB.BASEBOARD_FAB2(SCH_1):FM_HEARTBEAT_LED_A':
 C_SIGNAL='@baseboard_fab2_lib.baseboard_fab2(sch_1):fm_heartbeat_led_a';
NODE_NAME     R9E24 1
 '@BASEBOARD_FAB2_LIB.BASEBOARD_FAB2(SCH_1):PAGE151_I138@MSTR_DISCRETE.RES(CHIPS)':
 'A': CDS_PINID='A';
NODE_NAME     DS9E1 1
 '@BASEBOARD_FAB2_LIB.BASEBOARD_FAB2(SCH_1):PAGE151_I144@MSTR_DISCRETE.LED(CHIPS)':
 'A': CDS_PINID='A';
NET_NAME
'FM_HEARTBEAT_LED_K'
 '@BASEBOARD_FAB2_LIB.BASEBOARD_FAB2(SCH_1):FM_HEARTBEAT_LED_K':
 C_SIGNAL='@baseboard_fab2_lib.baseboard_fab2(sch_1):fm_heartbeat_led_k';
NODE_NAME     DS9E1 2
 '@BASEBOARD_FAB2_LIB.BASEBOARD_FAB2(SCH_1):PAGE151_I144@MSTR_DISCRETE.LED(CHIPS)':
 'C': CDS_PINID='C';
NODE_NAME     Q9E1 3
 '@BASEBOARD_FAB2_LIB.BASEBOARD_FAB2(SCH_1):PAGE151_I145@MSTR_DISCRETE.FET_N_DUAL(CHIPS)':
 'DRAIN'<0>: CDS_PINID='DRAIN(0)';
NET_NAME
'FM_HSC_TIMER_EXP_N'
 '@BASEBOARD_FAB2_LIB.BASEBOARD_FAB2(SCH_1):FM_HSC_TIMER_EXP_N':
 C_SIGNAL='@baseboard_fab2_lib.baseboard_fab2(sch_1):fm_hsc_timer_exp_n';
NODE_NAME     U7C1 AK9
 '@BASEBOARD_FAB2_LIB.BASEBOARD_FAB2(SCH_1):PAGE120_I147@MSTR_U_PROC.LBG_CORE_QAT_EXT_D(CHIPS)':
 'GPP_F1_SATAXPCIE4_SATAGP4': CDS_PINID='GPP_F1_SATAXPCIE4_SATAGP4';
NODE_NAME     U8E1 5
 '@BASEBOARD_FAB2_LIB.BASEBOARD_FAB2(SCH_1):PAGE170_I11@MSTR_TTL.TTL08(CHIPS)':
 'B'<0>: CDS_PINID='B(0)';
NODE_NAME     R9P20 2
 '@BASEBOARD_FAB2_LIB.BASEBOARD_FAB2(SCH_1):PAGE200_I86@MSTR_DISCRETE.RES(CHIPS)':
 'B': CDS_PINID='B';
NODE_NAME     U9P2 1
 '@BASEBOARD_FAB2_LIB.BASEBOARD_FAB2(SCH_1):PAGE200_I200@MSTR_VREG.TPS3700(CHIPS)':
 'OUTB': CDS_PINID='OUTB';
NODE_NAME     U25W4 U1
 '@BASEBOARD_FAB2_LIB.BASEBOARD_FAB2(SCH_1):PAGE145_I117@W_HDL.AST2520A1-GP-GP(CHIPS)':
 'GPIOL2_NDSR1': CDS_PINID='GPIOL2_NDSR1';
NET_NAME
'FM_IE_DISABLE_N'
 '@BASEBOARD_FAB2_LIB.BASEBOARD_FAB2(SCH_1):FM_IE_DISABLE_N':
 C_SIGNAL='@baseboard_fab2_lib.baseboard_fab2(sch_1):fm_ie_disable_n';
NODE_NAME     U7C1 AU13
 '@BASEBOARD_FAB2_LIB.BASEBOARD_FAB2(SCH_1):PAGE120_I147@MSTR_U_PROC.LBG_CORE_QAT_EXT_D(CHIPS)':
 'GPP_F16_USB2_OC5_N': CDS_PINID='GPP_F16_USB2_OC5_N';
NODE_NAME     R8D21 2
 '@BASEBOARD_FAB2_LIB.BASEBOARD_FAB2(SCH_1):PAGE135_I120@MSTR_DISCRETE.RES(CHIPS)':
 'B': CDS_PINID='B';
NODE_NAME     J8G2 4
 '@BASEBOARD_FAB2_LIB.BASEBOARD_FAB2(SCH_1):PAGE135_I124@MSTR_CONN.CONN12_C73564003(CHIPS)':
 'IO4': CDS_PINID='IO4';
NODE_NAME     U8D7 L9
 '@BASEBOARD_FAB2_LIB.BASEBOARD_FAB2(SCH_1):PAGE190_I179@MSTR_MEMORY.LCMXO2_A(CHIPS)':
 'PB12D': CDS_PINID='PB12D';
NET_NAME
'FM_INTRUDER_HDR_PCH_N'
 '@BASEBOARD_FAB2_LIB.BASEBOARD_FAB2(SCH_1):FM_INTRUDER_HDR_PCH_N':
 C_SIGNAL='@baseboard_fab2_lib.baseboard_fab2(sch_1):fm_intruder_hdr_pch_n';
NODE_NAME     U7C1 AG18
 '@BASEBOARD_FAB2_LIB.BASEBOARD_FAB2(SCH_1):PAGE121_I34@MSTR_U_PROC.LBG_CORE_QAT_EXT_D(CHIPS)':
 'INTRUDER_N': CDS_PINID='INTRUDER_N';
NODE_NAME     R3N10 2
 '@BASEBOARD_FAB2_LIB.BASEBOARD_FAB2(SCH_1):PAGE121_I37@MSTR_DISCRETE.RES(CHIPS)':
 'B': CDS_PINID='B';
NET_NAME
'FM_JTAG_PLD_EN_DEBUG'
 '@BASEBOARD_FAB2_LIB.BASEBOARD_FAB2(SCH_1):FM_JTAG_PLD_EN_DEBUG':
 C_SIGNAL='@baseboard_fab2_lib.baseboard_fab2(sch_1):fm_jtag_pld_en_debug';
NODE_NAME     R3R15 2
 '@BASEBOARD_FAB2_LIB.BASEBOARD_FAB2(SCH_1):PAGE189_I44@MSTR_DISCRETE.RES(CHIPS)':
 'B': CDS_PINID='B';
NODE_NAME     R3R11 1
 '@BASEBOARD_FAB2_LIB.BASEBOARD_FAB2(SCH_1):PAGE189_I45@MSTR_DISCRETE.RES(CHIPS)':
 'A': CDS_PINID='A';
NODE_NAME     U8D7 C10
 '@BASEBOARD_FAB2_LIB.BASEBOARD_FAB2(SCH_1):PAGE191_I59@MSTR_MEMORY.LCMXO2_A(CHIPS)':
 'PT20C_JTAGENB': CDS_PINID='PT20C_JTAGENB';
NODE_NAME     R25W186 2
 '@BASEBOARD_FAB2_LIB.BASEBOARD_FAB2(SCH_1):PAGE189_I77@MSTR_DISCRETE.RES(CHIPS)':
 'B': CDS_PINID='B';
NET_NAME
'FM_M2_DET_LVC3'
 '@BASEBOARD_FAB2_LIB.BASEBOARD_FAB2(SCH_1):FM_M2_DET_LVC3':
 C_SIGNAL='@baseboard_fab2_lib.baseboard_fab2(sch_1):fm_m2_det_lvc3';
NODE_NAME     U2P1 4
 '@BASEBOARD_FAB2_LIB.BASEBOARD_FAB2(SCH_1):PAGE185_I110@MSTR_TTL.TTL1G07_A(CHIPS)':
 'Y': CDS_PINID='Y';
NODE_NAME     R2P16 2
 '@BASEBOARD_FAB2_LIB.BASEBOARD_FAB2(SCH_1):PAGE185_I113@MSTR_DISCRETE.RES(CHIPS)':
 'B': CDS_PINID='B';
NODE_NAME     R2P14 1
 '@BASEBOARD_FAB2_LIB.BASEBOARD_FAB2(SCH_1):PAGE185_I115@MSTR_DISCRETE.RES(CHIPS)':
 'A': CDS_PINID='A';
NET_NAME
'FM_M2_SSD_PEDET'
 '@BASEBOARD_FAB2_LIB.BASEBOARD_FAB2(SCH_1):FM_M2_SSD_PEDET':
 C_SIGNAL='@baseboard_fab2_lib.baseboard_fab2(sch_1):fm_m2_ssd_pedet';
NODE_NAME     U2P1 2
 '@BASEBOARD_FAB2_LIB.BASEBOARD_FAB2(SCH_1):PAGE185_I110@MSTR_TTL.TTL1G07_A(CHIPS)':
 'A': CDS_PINID='A';
NODE_NAME     R2P15 2
 '@BASEBOARD_FAB2_LIB.BASEBOARD_FAB2(SCH_1):PAGE185_I111@MSTR_DISCRETE.RES(CHIPS)':
 'B': CDS_PINID='B';
NODE_NAME     J8F1 69
 '@BASEBOARD_FAB2_LIB.BASEBOARD_FAB2(SCH_1):PAGE185_I143@W_HDL.SKT-MINI67P-41-GP(CHIPS)':
 '69': CDS_PINID='\69\';
NET_NAME
'FM_MATED_IN_D1_N'
 '@BASEBOARD_FAB2_LIB.BASEBOARD_FAB2(SCH_1):FM_MATED_IN_D1_N':
 C_SIGNAL='@baseboard_fab2_lib.baseboard_fab2(sch_1):fm_mated_in_d1_n';
NODE_NAME     CR1F4 1
 '@BASEBOARD_FAB2_LIB.BASEBOARD_FAB2(SCH_1):PAGE181_I5@MSTR_DISCRETE.DIODE(CHIPS)':
 'C': CDS_PINID='C';
NODE_NAME     CR1F3 2
 '@BASEBOARD_FAB2_LIB.BASEBOARD_FAB2(SCH_1):PAGE181_I37@MSTR_DISCRETE.DIODE(CHIPS)':
 'A': CDS_PINID='A';
NET_NAME
'FM_MATED_IN_D2_N'
 '@BASEBOARD_FAB2_LIB.BASEBOARD_FAB2(SCH_1):FM_MATED_IN_D2_N':
 C_SIGNAL='@baseboard_fab2_lib.baseboard_fab2(sch_1):fm_mated_in_d2_n';
NODE_NAME     CR1F3 1
 '@BASEBOARD_FAB2_LIB.BASEBOARD_FAB2(SCH_1):PAGE181_I37@MSTR_DISCRETE.DIODE(CHIPS)':
 'C': CDS_PINID='C';
NODE_NAME     Q9T1 1
 '@BASEBOARD_FAB2_LIB.BASEBOARD_FAB2(SCH_1):PAGE181_I42@MSTR_DISCRETE.NPN(CHIPS)':
 'B': CDS_PINID='B';
NET_NAME
'FM_MATED_IN_N'
 '@BASEBOARD_FAB2_LIB.BASEBOARD_FAB2(SCH_1):FM_MATED_IN_N':
 C_SIGNAL='@baseboard_fab2_lib.baseboard_fab2(sch_1):fm_mated_in_n';
NODE_NAME     R9T9 2
 '@BASEBOARD_FAB2_LIB.BASEBOARD_FAB2(SCH_1):PAGE181_I4@MSTR_DISCRETE.RES(CHIPS)':
 'B': CDS_PINID='B';
NODE_NAME     CR1F4 2
 '@BASEBOARD_FAB2_LIB.BASEBOARD_FAB2(SCH_1):PAGE181_I5@MSTR_DISCRETE.DIODE(CHIPS)':
 'A': CDS_PINID='A';
NODE_NAME     J1F3 4
 '@BASEBOARD_FAB2_LIB.BASEBOARD_FAB2(SCH_1):PAGE181_I106@MSTR_CONN.CONN8_H62179001(CHIPS)':
 'IO4': CDS_PINID='IO4';
NODE_NAME     J1F1 E4
 '@BASEBOARD_FAB2_LIB.BASEBOARD_FAB2(SCH_1):PAGE181_I134@W_HDL.DM-FCI-CONN76-8R-GP-U-01(CHIPS)':
 'MATED_IN#': CDS_PINID='\mated_in#\';
NODE_NAME     R9T8 1
 '@BASEBOARD_FAB2_LIB.BASEBOARD_FAB2(SCH_1):PAGE181_I137@MSTR_DISCRETE.RES(CHIPS)':
 'A': CDS_PINID='A';
NET_NAME
'FM_MB_SLOT_ID0'
 '@BASEBOARD_FAB2_LIB.BASEBOARD_FAB2(SCH_1):FM_MB_SLOT_ID0':
 C_SIGNAL='@baseboard_fab2_lib.baseboard_fab2(sch_1):fm_mb_slot_id0';
NODE_NAME     U7C1 T4
 '@BASEBOARD_FAB2_LIB.BASEBOARD_FAB2(SCH_1):PAGE119_I115@MSTR_U_PROC.LBG_CORE_QAT_EXT_D(CHIPS)':
 'GPP_A13_SUSWARN_N_SUSPWRDNACK': CDS_PINID='GPP_A13_SUSWARN_N_SUSPWRDNACK';
NODE_NAME     R7D5 2
 '@BASEBOARD_FAB2_LIB.BASEBOARD_FAB2(SCH_1):PAGE181_I82@MSTR_DISCRETE.RES(CHIPS)':
 'B': CDS_PINID='B';
NODE_NAME     J1F1 F5
 '@BASEBOARD_FAB2_LIB.BASEBOARD_FAB2(SCH_1):PAGE181_I134@W_HDL.DM-FCI-CONN76-8R-GP-U-01(CHIPS)':
 'MB_SLOT_ID0': CDS_PINID='MB_SLOT_ID0';
NODE_NAME     U6W11 4
 '@BASEBOARD_FAB2_LIB.BASEBOARD_FAB2(SCH_1):PAGE164_I97@W_HDL.PCA9554PWR-GP(CHIPS)':
 'P0': CDS_PINID='P0';
NET_NAME
'FM_MB_SLOT_ID1'
 '@BASEBOARD_FAB2_LIB.BASEBOARD_FAB2(SCH_1):FM_MB_SLOT_ID1':
 C_SIGNAL='@baseboard_fab2_lib.baseboard_fab2(sch_1):fm_mb_slot_id1';
NODE_NAME     U7C1 AB3
 '@BASEBOARD_FAB2_LIB.BASEBOARD_FAB2(SCH_1):PAGE119_I115@MSTR_U_PROC.LBG_CORE_QAT_EXT_D(CHIPS)':
 'GPP_A14_ESPI_RESET_N': CDS_PINID='GPP_A14_ESPI_RESET_N';
NODE_NAME     R7D9 2
 '@BASEBOARD_FAB2_LIB.BASEBOARD_FAB2(SCH_1):PAGE181_I80@MSTR_DISCRETE.RES(CHIPS)':
 'B': CDS_PINID='B';
NODE_NAME     J1F1 G5
 '@BASEBOARD_FAB2_LIB.BASEBOARD_FAB2(SCH_1):PAGE181_I134@W_HDL.DM-FCI-CONN76-8R-GP-U-01(CHIPS)':
 'MB_SLOT_ID1': CDS_PINID='MB_SLOT_ID1';
NODE_NAME     U6W11 5
 '@BASEBOARD_FAB2_LIB.BASEBOARD_FAB2(SCH_1):PAGE164_I97@W_HDL.PCA9554PWR-GP(CHIPS)':
 'P1': CDS_PINID='P1';
NET_NAME
'FM_MB_SLOT_ID2'
 '@BASEBOARD_FAB2_LIB.BASEBOARD_FAB2(SCH_1):FM_MB_SLOT_ID2':
 C_SIGNAL='@baseboard_fab2_lib.baseboard_fab2(sch_1):fm_mb_slot_id2';
NODE_NAME     U7C1 AC4
 '@BASEBOARD_FAB2_LIB.BASEBOARD_FAB2(SCH_1):PAGE119_I115@MSTR_U_PROC.LBG_CORE_QAT_EXT_D(CHIPS)':
 'GPP_A15_SUSACK_N': CDS_PINID='GPP_A15_SUSACK_N';
NODE_NAME     R3P61 2
 '@BASEBOARD_FAB2_LIB.BASEBOARD_FAB2(SCH_1):PAGE181_I81@MSTR_DISCRETE.RES(CHIPS)':
 'B': CDS_PINID='B';
NODE_NAME     J1F1 H5
 '@BASEBOARD_FAB2_LIB.BASEBOARD_FAB2(SCH_1):PAGE181_I134@W_HDL.DM-FCI-CONN76-8R-GP-U-01(CHIPS)':
 'MB_SLOT_ID2': CDS_PINID='MB_SLOT_ID2';
NODE_NAME     U6W11 6
 '@BASEBOARD_FAB2_LIB.BASEBOARD_FAB2(SCH_1):PAGE164_I97@W_HDL.PCA9554PWR-GP(CHIPS)':
 'P2': CDS_PINID='P2';
NET_NAME
'FM_MEM_EVENT_FUNC'
 '@BASEBOARD_FAB2_LIB.BASEBOARD_FAB2(SCH_1):FM_MEM_EVENT_FUNC':
 C_SIGNAL='@baseboard_fab2_lib.baseboard_fab2(sch_1):fm_mem_event_func';
NODE_NAME     U8D7 D2
 '@BASEBOARD_FAB2_LIB.BASEBOARD_FAB2(SCH_1):PAGE190_I179@MSTR_MEMORY.LCMXO2_A(CHIPS)':
 'PL2D': CDS_PINID='PL2D';
NODE_NAME     R7E19 2
 '@BASEBOARD_FAB2_LIB.BASEBOARD_FAB2(SCH_1):PAGE192_I57@MSTR_DISCRETE.RES(CHIPS)':
 'B': CDS_PINID='B';
NODE_NAME     R7E20 1
 '@BASEBOARD_FAB2_LIB.BASEBOARD_FAB2(SCH_1):PAGE192_I59@MSTR_DISCRETE.RES(CHIPS)':
 'A': CDS_PINID='A';
NET_NAME
'FM_MEM_THERM_EVENT_LVT3_N'
 '@BASEBOARD_FAB2_LIB.BASEBOARD_FAB2(SCH_1):FM_MEM_THERM_EVENT_LVT3_N':
 C_SIGNAL='@baseboard_fab2_lib.baseboard_fab2(sch_1):fm_mem_therm_event_lvt3_n';
NODE_NAME     R4U1 2
 '@BASEBOARD_FAB2_LIB.BASEBOARD_FAB2(SCH_1):PAGE94_I91@MSTR_DISCRETE.RES(CHIPS)':
 'B': CDS_PINID='B';
NODE_NAME     Q4U1 3
 '@BASEBOARD_FAB2_LIB.BASEBOARD_FAB2(SCH_1):PAGE94_I102@MSTR_DISCRETE.FET_N_DUAL(CHIPS)':
 'DRAIN'<0>: CDS_PINID='DRAIN(0)';
NODE_NAME     R8E11 1
 '@BASEBOARD_FAB2_LIB.BASEBOARD_FAB2(SCH_1):PAGE156_I279@MSTR_DISCRETE.RES(CHIPS)':
 'A': CDS_PINID='A';
NODE_NAME     U8D7 K13
 '@BASEBOARD_FAB2_LIB.BASEBOARD_FAB2(SCH_1):PAGE191_I59@MSTR_MEMORY.LCMXO2_A(CHIPS)':
 'PR11C': CDS_PINID='PR11C';
NET_NAME
'FM_MEM_THERM_EVENT_PCH_N'
 '@BASEBOARD_FAB2_LIB.BASEBOARD_FAB2(SCH_1):FM_MEM_THERM_EVENT_PCH_N':
 C_SIGNAL='@baseboard_fab2_lib.baseboard_fab2(sch_1):fm_mem_therm_event_pch_n';
NODE_NAME     U7C1 AL15
 '@BASEBOARD_FAB2_LIB.BASEBOARD_FAB2(SCH_1):PAGE120_I147@MSTR_U_PROC.LBG_CORE_QAT_EXT_D(CHIPS)':
 'GPP_F18_USB2_OC7_N': CDS_PINID='GPP_F18_USB2_OC7_N';
NODE_NAME     U8D7 K12
 '@BASEBOARD_FAB2_LIB.BASEBOARD_FAB2(SCH_1):PAGE191_I59@MSTR_MEMORY.LCMXO2_A(CHIPS)':
 'PR11D': CDS_PINID='PR11D';
NODE_NAME     U25W4 P4
 '@BASEBOARD_FAB2_LIB.BASEBOARD_FAB2(SCH_1):PAGE145_I117@W_HDL.AST2520A1-GP-GP(CHIPS)':
 'GPIOL4_NDTR1_VPIVS': CDS_PINID='GPIOL4_NDTR1_VPIVS';
NET_NAME
'FM_MEZZA_PRSNT1_N'
 '@BASEBOARD_FAB2_LIB.BASEBOARD_FAB2(SCH_1):FM_MEZZA_PRSNT1_N':
 C_SIGNAL='@baseboard_fab2_lib.baseboard_fab2(sch_1):fm_mezza_prsnt1_n';
NODE_NAME     J9B3 1
 '@BASEBOARD_FAB2_LIB.BASEBOARD_FAB2(SCH_1):PAGE186_I336@MSTR_SCONN.SCONN120_A28699018(CHIPS)':
 'IO1': CDS_PINID='IO1';
NODE_NAME     R9W1 2
 '@BASEBOARD_FAB2_LIB.BASEBOARD_FAB2(SCH_1):PAGE186_I356@MSTR_DISCRETE.RES(CHIPS)':
 'B': CDS_PINID='B';
NODE_NAME     R9B7 1
 '@BASEBOARD_FAB2_LIB.BASEBOARD_FAB2(SCH_1):PAGE186_I358@W_HDL.887R2F-L-GP(CHIPS)':
 '1': CDS_PINID='\1\';
NET_NAME
'FM_MEZZB_PRSNT1_N'
 '@BASEBOARD_FAB2_LIB.BASEBOARD_FAB2(SCH_1):FM_MEZZB_PRSNT1_N':
 C_SIGNAL='@baseboard_fab2_lib.baseboard_fab2(sch_1):fm_mezzb_prsnt1_n';
NODE_NAME     J8E3 1
 '@BASEBOARD_FAB2_LIB.BASEBOARD_FAB2(SCH_1):PAGE187_I119@MSTR_SCONN.SCONN80_E67482007(CHIPS)':
 'IO1': CDS_PINID='IO1';
NODE_NAME     R2W1 2
 '@BASEBOARD_FAB2_LIB.BASEBOARD_FAB2(SCH_1):PAGE187_I174@MSTR_DISCRETE.RES(CHIPS)':
 'B': CDS_PINID='B';
NODE_NAME     R2R8 1
 '@BASEBOARD_FAB2_LIB.BASEBOARD_FAB2(SCH_1):PAGE187_I175@W_HDL.887R2F-L-GP(CHIPS)':
 '1': CDS_PINID='\1\';
NET_NAME
'FM_ME_RECOVER_N'
 '@BASEBOARD_FAB2_LIB.BASEBOARD_FAB2(SCH_1):FM_ME_RECOVER_N':
 C_SIGNAL='@baseboard_fab2_lib.baseboard_fab2(sch_1):fm_me_recover_n';
NODE_NAME     U7C1 V3
 '@BASEBOARD_FAB2_LIB.BASEBOARD_FAB2(SCH_1):PAGE119_I115@MSTR_U_PROC.LBG_CORE_QAT_EXT_D(CHIPS)':
 'GPP_A19': CDS_PINID='GPP_A19';
NODE_NAME     R7G26 2
 '@BASEBOARD_FAB2_LIB.BASEBOARD_FAB2(SCH_1):PAGE136_I101@MSTR_DISCRETE.RES(CHIPS)':
 'B': CDS_PINID='B';
NODE_NAME     J7G3 3
 '@BASEBOARD_FAB2_LIB.BASEBOARD_FAB2(SCH_1):PAGE136_I174@MSTR_CONN.CONN12_C73564003(CHIPS)':
 'IO3': CDS_PINID='IO3';
NET_NAME
'FM_MODPRST_HFI0_CPU0_LVT2_N'
 '@BASEBOARD_FAB2_LIB.BASEBOARD_FAB2(SCH_1):FM_MODPRST_HFI0_CPU0_LVT2_N':
 C_SIGNAL='@baseboard_fab2_lib.baseboard_fab2(sch_1):fm_modprst_hfi0_cpu0_lvt2_n~
';
NODE_NAME     U5D1 BR20
 '@BASEBOARD_FAB2_LIB.BASEBOARD_FAB2(SCH_1):PAGE29_I61@CHPSET_LIB.SKX_EXT_B(CHIPS)':
 'CD_HFI0_MODPRST_N': CDS_PINID='CD_HFI0_MODPRST_N';
NODE_NAME     J8B1 3
 '@BASEBOARD_FAB2_LIB.BASEBOARD_FAB2(SCH_1):PAGE91_I1@MSTR_SCONN.SCONN24_H46321001(CHIPS)':
 'IO3': CDS_PINID='IO3';
NODE_NAME     R8B3 2
 '@BASEBOARD_FAB2_LIB.BASEBOARD_FAB2(SCH_1):PAGE91_I24@MSTR_DISCRETE.RES(CHIPS)':
 'B': CDS_PINID='B';
NET_NAME
'FM_MODPRST_HFI1_CPU0_LVT2_N'
 '@BASEBOARD_FAB2_LIB.BASEBOARD_FAB2(SCH_1):FM_MODPRST_HFI1_CPU0_LVT2_N':
 C_SIGNAL='@baseboard_fab2_lib.baseboard_fab2(sch_1):fm_modprst_hfi1_cpu0_lvt2_n~
';
NODE_NAME     U5D1 BT19
 '@BASEBOARD_FAB2_LIB.BASEBOARD_FAB2(SCH_1):PAGE29_I61@CHPSET_LIB.SKX_EXT_B(CHIPS)':
 'CD_HFI1_MODPRST_N': CDS_PINID='CD_HFI1_MODPRST_N';
NODE_NAME     J8B1 11
 '@BASEBOARD_FAB2_LIB.BASEBOARD_FAB2(SCH_1):PAGE91_I1@MSTR_SCONN.SCONN24_H46321001(CHIPS)':
 'IO11': CDS_PINID='IO11';
NODE_NAME     R8B19 2
 '@BASEBOARD_FAB2_LIB.BASEBOARD_FAB2(SCH_1):PAGE91_I21@MSTR_DISCRETE.RES(CHIPS)':
 'B': CDS_PINID='B';
NET_NAME
'FM_MP_PS_FAIL_N'
 '@BASEBOARD_FAB2_LIB.BASEBOARD_FAB2(SCH_1):FM_MP_PS_FAIL_N':
 C_SIGNAL='@baseboard_fab2_lib.baseboard_fab2(sch_1):fm_mp_ps_fail_n',
 PHYS_NET_NAME='H_CPU0_FAST_WAKE_LVT3_N';
NODE_NAME     U7C1 AK20
 '@BASEBOARD_FAB2_LIB.BASEBOARD_FAB2(SCH_1):PAGE120_I147@MSTR_U_PROC.LBG_CORE_QAT_EXT_D(CHIPS)':
 'GPP_F2_SATAXPCIE5_SATAGP5': CDS_PINID='GPP_F2_SATAXPCIE5_SATAGP5';
NODE_NAME     R3N12 2
 '@BASEBOARD_FAB2_LIB.BASEBOARD_FAB2(SCH_1):PAGE157_I342@MSTR_DISCRETE.RES(CHIPS)':
 'B': CDS_PINID='B';
NODE_NAME     U8D7 H4
 '@BASEBOARD_FAB2_LIB.BASEBOARD_FAB2(SCH_1):PAGE190_I179@MSTR_MEMORY.LCMXO2_A(CHIPS)':
 'PL6C': CDS_PINID='PL6C';
NODE_NAME     U25W4 L18
 '@BASEBOARD_FAB2_LIB.BASEBOARD_FAB2(SCH_1):PAGE144_I95@W_HDL.AST2520A1-GP-GP(CHIPS)':
 'GPIOB2': CDS_PINID='GPIOB2';
NODE_NAME     J1F3 3
 '@BASEBOARD_FAB2_LIB.BASEBOARD_FAB2(SCH_1):PAGE181_I106@MSTR_CONN.CONN8_H62179001(CHIPS)':
 'IO3': CDS_PINID='IO3';
NET_NAME
'FM_MP_PS_REDUNDANT_LOST_N'
 '@BASEBOARD_FAB2_LIB.BASEBOARD_FAB2(SCH_1):FM_MP_PS_REDUNDANT_LOST_N':
 C_SIGNAL='@baseboard_fab2_lib.baseboard_fab2(sch_1):fm_mp_ps_redundant_lost_n';
NODE_NAME     U7C1 AK13
 '@BASEBOARD_FAB2_LIB.BASEBOARD_FAB2(SCH_1):PAGE120_I147@MSTR_U_PROC.LBG_CORE_QAT_EXT_D(CHIPS)':
 'GPP_F3_SATAXPCIE6_SATAGP6': CDS_PINID='GPP_F3_SATAXPCIE6_SATAGP6';
NODE_NAME     R3N11 2
 '@BASEBOARD_FAB2_LIB.BASEBOARD_FAB2(SCH_1):PAGE157_I344@MSTR_DISCRETE.RES(CHIPS)':
 'B': CDS_PINID='B';
NODE_NAME     U25W4 T19
 '@BASEBOARD_FAB2_LIB.BASEBOARD_FAB2(SCH_1):PAGE146_I105@W_HDL.AST2520A1-GP-GP(CHIPS)':
 'GPIOR1_FWSPICS2#': CDS_PINID='\gpior1_fwspics2#\';
NODE_NAME     J1F3 2
 '@BASEBOARD_FAB2_LIB.BASEBOARD_FAB2(SCH_1):PAGE181_I106@MSTR_CONN.CONN8_H62179001(CHIPS)':
 'IO2': CDS_PINID='IO2';
NET_NAME
'FM_NMI_EVENT_N'
 '@BASEBOARD_FAB2_LIB.BASEBOARD_FAB2(SCH_1):FM_NMI_EVENT_N':
 C_SIGNAL='@baseboard_fab2_lib.baseboard_fab2(sch_1):fm_nmi_event_n';
NODE_NAME     U7C1 BE7
 '@BASEBOARD_FAB2_LIB.BASEBOARD_FAB2(SCH_1):PAGE120_I147@MSTR_U_PROC.LBG_CORE_QAT_EXT_D(CHIPS)':
 'GPP_G18_NMI_N': CDS_PINID='GPP_G18_NMI_N';
NODE_NAME     R2N25 1
 '@BASEBOARD_FAB2_LIB.BASEBOARD_FAB2(SCH_1):PAGE157_I302@MSTR_DISCRETE.RES(CHIPS)':
 'A': CDS_PINID='A';
NET_NAME
'FM_OC0_USB_N'
 '@BASEBOARD_FAB2_LIB.BASEBOARD_FAB2(SCH_1):FM_OC0_USB_N':
 C_SIGNAL='@baseboard_fab2_lib.baseboard_fab2(sch_1):fm_oc0_usb_n';
NODE_NAME     U7C1 BL48
 '@BASEBOARD_FAB2_LIB.BASEBOARD_FAB2(SCH_1):PAGE120_I147@MSTR_U_PROC.LBG_CORE_QAT_EXT_D(CHIPS)':
 'GPP_E9_USB2_OC0_N': CDS_PINID='GPP_E9_USB2_OC0_N';
NODE_NAME     U1M3 3
 '@BASEBOARD_FAB2_LIB.BASEBOARD_FAB2(SCH_1):PAGE176_I100@MSTR_VREG.TPS2061(CHIPS)':
 'OC_N': CDS_PINID='OC_N';
NODE_NAME     R1M24 2
 '@BASEBOARD_FAB2_LIB.BASEBOARD_FAB2(SCH_1):PAGE176_I105@MSTR_DISCRETE.RES(CHIPS)':
 'B': CDS_PINID='B';
NODE_NAME     U8D7 L7
 '@BASEBOARD_FAB2_LIB.BASEBOARD_FAB2(SCH_1):PAGE190_I179@MSTR_MEMORY.LCMXO2_A(CHIPS)':
 'PB8D': CDS_PINID='PB8D';
NET_NAME
'FM_OCP_MEZZA_PRES'
 '@BASEBOARD_FAB2_LIB.BASEBOARD_FAB2(SCH_1):FM_OCP_MEZZA_PRES':
 C_SIGNAL='@baseboard_fab2_lib.baseboard_fab2(sch_1):fm_ocp_mezza_pres';
NODE_NAME     R7D12 2
 '@BASEBOARD_FAB2_LIB.BASEBOARD_FAB2(SCH_1):PAGE133_I237@MSTR_DISCRETE.RES(CHIPS)':
 'B': CDS_PINID='B';
NODE_NAME     U25W4 T21
 '@BASEBOARD_FAB2_LIB.BASEBOARD_FAB2(SCH_1):PAGE146_I105@W_HDL.AST2520A1-GP-GP(CHIPS)':
 'GPIOAB1_VPOHS_NORWE#': CDS_PINID='\gpioab1_vpohs_norwe#\';
NODE_NAME     Q1W1 3
 '@BASEBOARD_FAB2_LIB.BASEBOARD_FAB2(SCH_1):PAGE250_I29@MSTR_DISCRETE.FET_N(CHIPS)':
 'DRN': CDS_PINID='DRN';
NODE_NAME     R7W15 1
 '@BASEBOARD_FAB2_LIB.BASEBOARD_FAB2(SCH_1):PAGE119_I227@MSTR_DISCRETE.RES(CHIPS)':
 'A': CDS_PINID='A';
NET_NAME
'FM_OCP_MEZZA_PRES_N'
 '@BASEBOARD_FAB2_LIB.BASEBOARD_FAB2(SCH_1):FM_OCP_MEZZA_PRES_N':
 C_SIGNAL='@baseboard_fab2_lib.baseboard_fab2(sch_1):fm_ocp_mezza_pres_n';
NODE_NAME     J9B3 120
 '@BASEBOARD_FAB2_LIB.BASEBOARD_FAB2(SCH_1):PAGE186_I336@MSTR_SCONN.SCONN120_A28699018(CHIPS)':
 'IO120': CDS_PINID='IO120';
NODE_NAME     R1W1 2
 '@BASEBOARD_FAB2_LIB.BASEBOARD_FAB2(SCH_1):PAGE250_I18@W_HDL.1MR2F-L-GP(CHIPS)':
 '2': CDS_PINID='\2\';
NODE_NAME     Q1W1 1
 '@BASEBOARD_FAB2_LIB.BASEBOARD_FAB2(SCH_1):PAGE250_I29@MSTR_DISCRETE.FET_N(CHIPS)':
 'GATE': CDS_PINID='GATE';
NET_NAME
'FM_OCP_MEZZA_PRES_R'
 '@BASEBOARD_FAB2_LIB.BASEBOARD_FAB2(SCH_1):FM_OCP_MEZZA_PRES_R':
 C_SIGNAL='@baseboard_fab2_lib.baseboard_fab2(sch_1):fm_ocp_mezza_pres_r';
NODE_NAME     U7C1 AE2
 '@BASEBOARD_FAB2_LIB.BASEBOARD_FAB2(SCH_1):PAGE119_I115@MSTR_U_PROC.LBG_CORE_QAT_EXT_D(CHIPS)':
 'GPP_A21': CDS_PINID='GPP_A21';
NODE_NAME     R7W15 2
 '@BASEBOARD_FAB2_LIB.BASEBOARD_FAB2(SCH_1):PAGE119_I227@MSTR_DISCRETE.RES(CHIPS)':
 'B': CDS_PINID='B';
NET_NAME
'FM_OCP_MEZZB_PRES_1V05_PCH_N'
 '@BASEBOARD_FAB2_LIB.BASEBOARD_FAB2(SCH_1):FM_OCP_MEZZB_PRES_1V05_PCH_N':
 C_SIGNAL='@baseboard_fab2_lib.baseboard_fab2(sch_1):fm_ocp_mezzb_pres_1v05_pch_~
n';
NODE_NAME     U7C1 AD9
 '@BASEBOARD_FAB2_LIB.BASEBOARD_FAB2(SCH_1):PAGE121_I34@MSTR_U_PROC.LBG_CORE_QAT_EXT_D(CHIPS)':
 'GPP_L8_TESTCH0_D6': CDS_PINID='GPP_L8_TESTCH0_D6';
NODE_NAME     R7D44 2
 '@BASEBOARD_FAB2_LIB.BASEBOARD_FAB2(SCH_1):PAGE133_I356@MSTR_DISCRETE.RES(CHIPS)':
 'B': CDS_PINID='B';
NODE_NAME     Q1W2 3
 '@BASEBOARD_FAB2_LIB.BASEBOARD_FAB2(SCH_1):PAGE250_I12@MSTR_DISCRETE.FET_N_DUAL(CHIPS)':
 'DRAIN'<0>: CDS_PINID='DRAIN(0)';
NET_NAME
'FM_OCP_MEZZB_PRES_LVT3_BMC'
 '@BASEBOARD_FAB2_LIB.BASEBOARD_FAB2(SCH_1):FM_OCP_MEZZB_PRES_LVT3_BMC':
 C_SIGNAL='@baseboard_fab2_lib.baseboard_fab2(sch_1):fm_ocp_mezzb_pres_lvt3_bmc';
NODE_NAME     U25W4 H19
 '@BASEBOARD_FAB2_LIB.BASEBOARD_FAB2(SCH_1):PAGE145_I117@W_HDL.AST2520A1-GP-GP(CHIPS)':
 'GPIOF5_NRTS4_LHFRAME#': CDS_PINID='\gpiof5_nrts4_lhframe#\';
NODE_NAME     Q1W2 5
 '@BASEBOARD_FAB2_LIB.BASEBOARD_FAB2(SCH_1):PAGE250_I12@MSTR_DISCRETE.FET_N_DUAL(CHIPS)':
 'GATE'<0>: CDS_PINID='GATE(0)';
NODE_NAME     R1W4 1
 '@BASEBOARD_FAB2_LIB.BASEBOARD_FAB2(SCH_1):PAGE250_I22@MSTR_DISCRETE.RES(CHIPS)':
 'A': CDS_PINID='A';
NODE_NAME     Q1W2 6
 '@BASEBOARD_FAB2_LIB.BASEBOARD_FAB2(SCH_1):PAGE250_I24@MSTR_DISCRETE.FET_N_DUAL(CHIPS)':
 'DRAIN'<0>: CDS_PINID='DRAIN(0)';
NET_NAME
'FM_OCP_MEZZB_PRES_N'
 '@BASEBOARD_FAB2_LIB.BASEBOARD_FAB2(SCH_1):FM_OCP_MEZZB_PRES_N':
 C_SIGNAL='@baseboard_fab2_lib.baseboard_fab2(sch_1):fm_ocp_mezzb_pres_n';
NODE_NAME     J8E3 80
 '@BASEBOARD_FAB2_LIB.BASEBOARD_FAB2(SCH_1):PAGE187_I119@MSTR_SCONN.SCONN80_E67482007(CHIPS)':
 'IO80': CDS_PINID='IO80';
NODE_NAME     Q1W2 2
 '@BASEBOARD_FAB2_LIB.BASEBOARD_FAB2(SCH_1):PAGE250_I24@MSTR_DISCRETE.FET_N_DUAL(CHIPS)':
 'GATE'<0>: CDS_PINID='GATE(0)';
NODE_NAME     R1W3 2
 '@BASEBOARD_FAB2_LIB.BASEBOARD_FAB2(SCH_1):PAGE250_I27@W_HDL.1MR2F-L-GP(CHIPS)':
 '2': CDS_PINID='\2\';
NET_NAME
'FM_OCP_MEZZC_PRES_1V05_PCH_N'
 '@BASEBOARD_FAB2_LIB.BASEBOARD_FAB2(SCH_1):FM_OCP_MEZZC_PRES_1V05_PCH_N':
 C_SIGNAL='@baseboard_fab2_lib.baseboard_fab2(sch_1):fm_ocp_mezzc_pres_1v05_pch_~
n';
NODE_NAME     U7C1 AD17
 '@BASEBOARD_FAB2_LIB.BASEBOARD_FAB2(SCH_1):PAGE121_I34@MSTR_U_PROC.LBG_CORE_QAT_EXT_D(CHIPS)':
 'GPP_L9_TESTCH0_D7': CDS_PINID='GPP_L9_TESTCH0_D7';
NODE_NAME     Q1W4 3
 '@BASEBOARD_FAB2_LIB.BASEBOARD_FAB2(SCH_1):PAGE250_I8@MSTR_DISCRETE.FET_N_DUAL(CHIPS)':
 'DRAIN'<0>: CDS_PINID='DRAIN(0)';
NODE_NAME     R3P53 2
 '@BASEBOARD_FAB2_LIB.BASEBOARD_FAB2(SCH_1):PAGE133_I365@MSTR_DISCRETE.RES(CHIPS)':
 'B': CDS_PINID='B';
NET_NAME
'FM_OCP_MEZZC_PRES_LVT3_BMC'
 '@BASEBOARD_FAB2_LIB.BASEBOARD_FAB2(SCH_1):FM_OCP_MEZZC_PRES_LVT3_BMC':
 C_SIGNAL='@baseboard_fab2_lib.baseboard_fab2(sch_1):fm_ocp_mezzc_pres_lvt3_bmc';
NODE_NAME     U25W4 H18
 '@BASEBOARD_FAB2_LIB.BASEBOARD_FAB2(SCH_1):PAGE145_I117@W_HDL.AST2520A1-GP-GP(CHIPS)':
 'GPIOF7_RXD4_LHRST#': CDS_PINID='\gpiof7_rxd4_lhrst#\';
NODE_NAME     Q1W4 6
 '@BASEBOARD_FAB2_LIB.BASEBOARD_FAB2(SCH_1):PAGE250_I3@MSTR_DISCRETE.FET_N_DUAL(CHIPS)':
 'DRAIN'<0>: CDS_PINID='DRAIN(0)';
NODE_NAME     R1W7 1
 '@BASEBOARD_FAB2_LIB.BASEBOARD_FAB2(SCH_1):PAGE250_I6@MSTR_DISCRETE.RES(CHIPS)':
 'A': CDS_PINID='A';
NODE_NAME     Q1W4 5
 '@BASEBOARD_FAB2_LIB.BASEBOARD_FAB2(SCH_1):PAGE250_I8@MSTR_DISCRETE.FET_N_DUAL(CHIPS)':
 'GATE'<0>: CDS_PINID='GATE(0)';
NET_NAME
'FM_OCP_MEZZC_PRES_N'
 '@BASEBOARD_FAB2_LIB.BASEBOARD_FAB2(SCH_1):FM_OCP_MEZZC_PRES_N':
 C_SIGNAL='@baseboard_fab2_lib.baseboard_fab2(sch_1):fm_ocp_mezzc_pres_n';
NODE_NAME     J8E4 64
 '@BASEBOARD_FAB2_LIB.BASEBOARD_FAB2(SCH_1):PAGE188_I27@MSTR_SCONN.SCONN64_H87568002_A(CHIPS)':
 'IO64': CDS_PINID='IO64';
NODE_NAME     R1W6 2
 '@BASEBOARD_FAB2_LIB.BASEBOARD_FAB2(SCH_1):PAGE250_I2@W_HDL.1MR2F-L-GP(CHIPS)':
 '2': CDS_PINID='\2\';
NODE_NAME     Q1W4 2
 '@BASEBOARD_FAB2_LIB.BASEBOARD_FAB2(SCH_1):PAGE250_I3@MSTR_DISCRETE.FET_N_DUAL(CHIPS)':
 'GATE'<0>: CDS_PINID='GATE(0)';
NET_NAME
'FM_OC_DETECT_EN'
 '@BASEBOARD_FAB2_LIB.BASEBOARD_FAB2(SCH_1):FM_OC_DETECT_EN':
 C_SIGNAL='@baseboard_fab2_lib.baseboard_fab2(sch_1):fm_oc_detect_en';
NODE_NAME     U1D1 1
 '@BASEBOARD_FAB2_LIB.BASEBOARD_FAB2(SCH_1):PAGE200_I103@MSTR_TTL.TTL1G126_A(CHIPS)':
 'OE': CDS_PINID='OE';
NODE_NAME     Q1D2 3
 '@BASEBOARD_FAB2_LIB.BASEBOARD_FAB2(SCH_1):PAGE200_I203@MSTR_DISCRETE.FET_N(CHIPS)':
 'DRN': CDS_PINID='DRN';
NODE_NAME     R1D21 2
 '@BASEBOARD_FAB2_LIB.BASEBOARD_FAB2(SCH_1):PAGE200_I204@MSTR_DISCRETE.RES(CHIPS)':
 'B': CDS_PINID='B';
NET_NAME
'FM_OC_DETECT_EN_N'
 '@BASEBOARD_FAB2_LIB.BASEBOARD_FAB2(SCH_1):FM_OC_DETECT_EN_N':
 C_SIGNAL='@baseboard_fab2_lib.baseboard_fab2(sch_1):fm_oc_detect_en_n',
 PHYS_NET_NAME='FM_OC_DETECT_EN_N';
NODE_NAME     U7C1 BC4
 '@BASEBOARD_FAB2_LIB.BASEBOARD_FAB2(SCH_1):PAGE120_I147@MSTR_U_PROC.LBG_CORE_QAT_EXT_D(CHIPS)':
 'GPP_H18_SML4ALERT_N_IE_N': CDS_PINID='GPP_H18_SML4ALERT_N_IE_N';
NODE_NAME     R7D19 1
 '@BASEBOARD_FAB2_LIB.BASEBOARD_FAB2(SCH_1):PAGE126_I6@MSTR_DISCRETE.RES(CHIPS)':
 'A': CDS_PINID='A';
NODE_NAME     R1D35 2
 '@BASEBOARD_FAB2_LIB.BASEBOARD_FAB2(SCH_1):PAGE126_I12@MSTR_DISCRETE.RES(CHIPS)':
 'B': CDS_PINID='B';
NODE_NAME     Q1D2 1
 '@BASEBOARD_FAB2_LIB.BASEBOARD_FAB2(SCH_1):PAGE200_I203@MSTR_DISCRETE.FET_N(CHIPS)':
 'GATE': CDS_PINID='GATE';
NODE_NAME     U25W4 Y2
 '@BASEBOARD_FAB2_LIB.BASEBOARD_FAB2(SCH_1):PAGE145_I117@W_HDL.AST2520A1-GP-GP(CHIPS)':
 'GPIOM3_NRI2_VPIB5': CDS_PINID='GPIOM3_NRI2_VPIB5';
NET_NAME
'FM_OC_DETECT_N'
 '@BASEBOARD_FAB2_LIB.BASEBOARD_FAB2(SCH_1):FM_OC_DETECT_N':
 C_SIGNAL='@baseboard_fab2_lib.baseboard_fab2(sch_1):fm_oc_detect_n';
NODE_NAME     U8E1 2
 '@BASEBOARD_FAB2_LIB.BASEBOARD_FAB2(SCH_1):PAGE170_I10@MSTR_TTL.TTL08(CHIPS)':
 'B'<0>: CDS_PINID='B(0)';
NODE_NAME     U1D1 4
 '@BASEBOARD_FAB2_LIB.BASEBOARD_FAB2(SCH_1):PAGE200_I103@MSTR_TTL.TTL1G126_A(CHIPS)':
 'Y': CDS_PINID='Y';
NODE_NAME     R1D22 2
 '@BASEBOARD_FAB2_LIB.BASEBOARD_FAB2(SCH_1):PAGE200_I158@MSTR_DISCRETE.RES(CHIPS)':
 'B': CDS_PINID='B';
NET_NAME
'FM_P12V_HOTSWAP0_EN'
 '@BASEBOARD_FAB2_LIB.BASEBOARD_FAB2(SCH_1):FM_P12V_HOTSWAP0_EN':
 C_SIGNAL='@baseboard_fab2_lib.baseboard_fab2(sch_1):fm_p12v_hotswap0_en';
NODE_NAME     EU1D2 12
 '@BASEBOARD_FAB2_LIB.BASEBOARD_FAB2(SCH_1):PAGE199_I10@MSTR_CONTROLLER.ADM1278(CHIPS)':
 'ENABLE': CDS_PINID='ENABLE';
NODE_NAME     C1D11 1
 '@BASEBOARD_FAB2_LIB.BASEBOARD_FAB2(SCH_1):PAGE199_I53@DEV_DISCRETE.CAP_A(CHIPS)':
 'A': CDS_PINID='A';
NODE_NAME     Q9T1 3
 '@BASEBOARD_FAB2_LIB.BASEBOARD_FAB2(SCH_1):PAGE181_I42@MSTR_DISCRETE.NPN(CHIPS)':
 'C': CDS_PINID='C';
NODE_NAME     R9T3 1
 '@BASEBOARD_FAB2_LIB.BASEBOARD_FAB2(SCH_1):PAGE181_I64@MSTR_DISCRETE.RES(CHIPS)':
 'A': CDS_PINID='A';
NODE_NAME     R9T6 2
 '@BASEBOARD_FAB2_LIB.BASEBOARD_FAB2(SCH_1):PAGE181_I68@MSTR_DISCRETE.RES(CHIPS)':
 'B': CDS_PINID='B';
NET_NAME
'FM_P12V_HSC_ADR1'
 '@BASEBOARD_FAB2_LIB.BASEBOARD_FAB2(SCH_1):FM_P12V_HSC_ADR1':
 C_SIGNAL='@baseboard_fab2_lib.baseboard_fab2(sch_1):fm_p12v_hsc_adr1';
NODE_NAME     EU1D2 7
 '@BASEBOARD_FAB2_LIB.BASEBOARD_FAB2(SCH_1):PAGE199_I10@MSTR_CONTROLLER.ADM1278(CHIPS)':
 'ADR1': CDS_PINID='ADR1';
NODE_NAME     R9P17 1
 '@BASEBOARD_FAB2_LIB.BASEBOARD_FAB2(SCH_1):PAGE199_I33@MSTR_DISCRETE.RES(CHIPS)':
 'A': CDS_PINID='A';
NODE_NAME     R1D29 2
 '@BASEBOARD_FAB2_LIB.BASEBOARD_FAB2(SCH_1):PAGE199_I137@MSTR_DISCRETE.RES(CHIPS)':
 'B': CDS_PINID='B';
NET_NAME
'FM_P12V_HSC_ADR2'
 '@BASEBOARD_FAB2_LIB.BASEBOARD_FAB2(SCH_1):FM_P12V_HSC_ADR2':
 C_SIGNAL='@baseboard_fab2_lib.baseboard_fab2(sch_1):fm_p12v_hsc_adr2';
NODE_NAME     EU1D2 8
 '@BASEBOARD_FAB2_LIB.BASEBOARD_FAB2(SCH_1):PAGE199_I10@MSTR_CONTROLLER.ADM1278(CHIPS)':
 'ADR2': CDS_PINID='ADR2';
NODE_NAME     R9P16 1
 '@BASEBOARD_FAB2_LIB.BASEBOARD_FAB2(SCH_1):PAGE199_I36@MSTR_DISCRETE.RES(CHIPS)':
 'A': CDS_PINID='A';
NODE_NAME     R1D27 2
 '@BASEBOARD_FAB2_LIB.BASEBOARD_FAB2(SCH_1):PAGE199_I38@MSTR_DISCRETE.RES(CHIPS)':
 'B': CDS_PINID='B';
NET_NAME
'FM_P12V_MAIN_SW_EN'
 '@BASEBOARD_FAB2_LIB.BASEBOARD_FAB2(SCH_1):FM_P12V_MAIN_SW_EN':
 C_SIGNAL='@baseboard_fab2_lib.baseboard_fab2(sch_1):fm_p12v_main_sw_en';
NODE_NAME     U8D7 R16
 '@BASEBOARD_FAB2_LIB.BASEBOARD_FAB2(SCH_1):PAGE191_I59@MSTR_MEMORY.LCMXO2_A(CHIPS)':
 'PR14D': CDS_PINID='PR14D';
NODE_NAME     EU7E1 2
 '@BASEBOARD_FAB2_LIB.BASEBOARD_FAB2(SCH_1):PAGE198_I19@MSTR_VREG.SLG55021(CHIPS)':
 'ON': CDS_PINID='\on\';
NET_NAME
'FM_P1V8MCP_CPU0_EN'
 '@BASEBOARD_FAB2_LIB.BASEBOARD_FAB2(SCH_1):FM_P1V8MCP_CPU0_EN':
 C_SIGNAL='@baseboard_fab2_lib.baseboard_fab2(sch_1):fm_p1v8mcp_cpu0_en';
NODE_NAME     U8D7 E16
 '@BASEBOARD_FAB2_LIB.BASEBOARD_FAB2(SCH_1):PAGE191_I59@MSTR_MEMORY.LCMXO2_A(CHIPS)':
 'PR3A': CDS_PINID='PR3A';
NODE_NAME     J6B1 A15
 '@BASEBOARD_FAB2_LIB.BASEBOARD_FAB2(SCH_1):PAGE194_I56@MSTR_SCONN.SCONN120_H61426002(CHIPS)':
 'IOA15': CDS_PINID='IOA15';
NET_NAME
'FM_P1V8MCP_CPU1_EN'
 '@BASEBOARD_FAB2_LIB.BASEBOARD_FAB2(SCH_1):FM_P1V8MCP_CPU1_EN':
 C_SIGNAL='@baseboard_fab2_lib.baseboard_fab2(sch_1):fm_p1v8mcp_cpu1_en';
NODE_NAME     U8D7 F12
 '@BASEBOARD_FAB2_LIB.BASEBOARD_FAB2(SCH_1):PAGE191_I59@MSTR_MEMORY.LCMXO2_A(CHIPS)':
 'PR4C': CDS_PINID='PR4C';
NODE_NAME     J4B2 A15
 '@BASEBOARD_FAB2_LIB.BASEBOARD_FAB2(SCH_1):PAGE193_I46@MSTR_SCONN.SCONN120_H61426002(CHIPS)':
 'IOA15': CDS_PINID='IOA15';
NET_NAME
'FM_P3V3_CPLD_EN'
 '@BASEBOARD_FAB2_LIB.BASEBOARD_FAB2(SCH_1):FM_P3V3_CPLD_EN':
 C_SIGNAL='@baseboard_fab2_lib.baseboard_fab2(sch_1):fm_p3v3_cpld_en';
NODE_NAME     U8D7 A4
 '@BASEBOARD_FAB2_LIB.BASEBOARD_FAB2(SCH_1):PAGE191_I59@MSTR_MEMORY.LCMXO2_A(CHIPS)':
 'PT10A': CDS_PINID='PT10A';
NODE_NAME     EU2T1 2
 '@BASEBOARD_FAB2_LIB.BASEBOARD_FAB2(SCH_1):PAGE198_I1@MSTR_VREG.SLG55021(CHIPS)':
 'ON': CDS_PINID='\on\';
NET_NAME
'FM_PASSWORD_CLEAR_N'
 '@BASEBOARD_FAB2_LIB.BASEBOARD_FAB2(SCH_1):FM_PASSWORD_CLEAR_N':
 C_SIGNAL='@baseboard_fab2_lib.baseboard_fab2(sch_1):fm_password_clear_n';
NODE_NAME     U7C1 BW32
 '@BASEBOARD_FAB2_LIB.BASEBOARD_FAB2(SCH_1):PAGE119_I115@MSTR_U_PROC.LBG_CORE_QAT_EXT_D(CHIPS)':
 'GPP_C8': CDS_PINID='GPP_C8';
NODE_NAME     R2N28 2
 '@BASEBOARD_FAB2_LIB.BASEBOARD_FAB2(SCH_1):PAGE136_I147@MSTR_DISCRETE.RES(CHIPS)':
 'B': CDS_PINID='B';
NODE_NAME     J7G3 9
 '@BASEBOARD_FAB2_LIB.BASEBOARD_FAB2(SCH_1):PAGE136_I174@MSTR_CONN.CONN12_C73564003(CHIPS)':
 'IO9': CDS_PINID='IO9';
NET_NAME
'FM_PCH_BMC_THERMTRIP_EXI_STRAP_'
 '@BASEBOARD_FAB2_LIB.BASEBOARD_FAB2(SCH_1):FM_PCH_BMC_THERMTRIP_EXI_STRAP_N':
 C_SIGNAL='@baseboard_fab2_lib.baseboard_fab2(sch_1):fm_pch_bmc_thermtrip_exi_st~
rap_n';
NODE_NAME     U7C1 BM20
 '@BASEBOARD_FAB2_LIB.BASEBOARD_FAB2(SCH_1):PAGE119_I115@MSTR_U_PROC.LBG_CORE_QAT_EXT_D(CHIPS)':
 'GPP_B23_MEIE_SML1ALRT_N_PHOT_N': CDS_PINID='GPP_B23_MEIE_SML1ALRT_N_PHOT_N';
NODE_NAME     Q8D2 2
 '@BASEBOARD_FAB2_LIB.BASEBOARD_FAB2(SCH_1):PAGE134_I15@MSTR_DISCRETE.FET_N(CHIPS)':
 'SRC': CDS_PINID='SRC';
NODE_NAME     R2N10 2
 '@BASEBOARD_FAB2_LIB.BASEBOARD_FAB2(SCH_1):PAGE126_I27@MSTR_DISCRETE.RES(CHIPS)':
 'B': CDS_PINID='B';
NET_NAME
'FM_PCH_BMC_THERMTRIP_N'
 '@BASEBOARD_FAB2_LIB.BASEBOARD_FAB2(SCH_1):FM_PCH_BMC_THERMTRIP_N':
 C_SIGNAL='@baseboard_fab2_lib.baseboard_fab2(sch_1):fm_pch_bmc_thermtrip_n';
NODE_NAME     U7C1 BH2
 '@BASEBOARD_FAB2_LIB.BASEBOARD_FAB2(SCH_1):PAGE120_I147@MSTR_U_PROC.LBG_CORE_QAT_EXT_D(CHIPS)':
 'GPP_H22_SSATAXPCIE4_SSATAGP4': CDS_PINID='GPP_H22_SSATAXPCIE4_SSATAGP4';
NODE_NAME     R2P17 2
 '@BASEBOARD_FAB2_LIB.BASEBOARD_FAB2(SCH_1):PAGE134_I3@MSTR_DISCRETE.RES(CHIPS)':
 'B': CDS_PINID='B';
NODE_NAME     U25W4 C19
 '@BASEBOARD_FAB2_LIB.BASEBOARD_FAB2(SCH_1):PAGE144_I95@W_HDL.AST2520A1-GP-GP(CHIPS)':
 'GPIOG2_SGPS1I0': CDS_PINID='GPIOG2_SGPS1I0';
NODE_NAME     Q8D2 3
 '@BASEBOARD_FAB2_LIB.BASEBOARD_FAB2(SCH_1):PAGE134_I15@MSTR_DISCRETE.FET_N(CHIPS)':
 'DRN': CDS_PINID='DRN';
NET_NAME
'FM_PCH_LVC1_THERMTRIP_N'
 '@BASEBOARD_FAB2_LIB.BASEBOARD_FAB2(SCH_1):FM_PCH_LVC1_THERMTRIP_N':
 C_SIGNAL='@baseboard_fab2_lib.baseboard_fab2(sch_1):fm_pch_lvc1_thermtrip_n';
NODE_NAME     U7C1 V15
 '@BASEBOARD_FAB2_LIB.BASEBOARD_FAB2(SCH_1):PAGE118_I73@MSTR_U_PROC.LBG_CORE_QAT_EXT_D(CHIPS)':
 'THRMTRIP_N': CDS_PINID='THRMTRIP_N';
NODE_NAME     R7C21 2
 '@BASEBOARD_FAB2_LIB.BASEBOARD_FAB2(SCH_1):PAGE134_I9@MSTR_DISCRETE.RES(CHIPS)':
 'B': CDS_PINID='B';
NODE_NAME     Q7D1 3
 '@BASEBOARD_FAB2_LIB.BASEBOARD_FAB2(SCH_1):PAGE134_I14@MSTR_DISCRETE.FET_N(CHIPS)':
 'DRN': CDS_PINID='DRN';
NET_NAME
'FM_PCH_PLD_DATA'
 '@BASEBOARD_FAB2_LIB.BASEBOARD_FAB2(SCH_1):FM_PCH_PLD_DATA':
 C_SIGNAL='@baseboard_fab2_lib.baseboard_fab2(sch_1):fm_pch_pld_data';
NODE_NAME     R2M3 2
 '@BASEBOARD_FAB2_LIB.BASEBOARD_FAB2(SCH_1):PAGE119_I172@MSTR_DISCRETE.RES(CHIPS)':
 'B': CDS_PINID='B';
NODE_NAME     R2R5 2
 '@BASEBOARD_FAB2_LIB.BASEBOARD_FAB2(SCH_1):PAGE133_I258@MSTR_DISCRETE.RES(CHIPS)':
 'B': CDS_PINID='B';
NODE_NAME     U8D7 C2
 '@BASEBOARD_FAB2_LIB.BASEBOARD_FAB2(SCH_1):PAGE190_I179@MSTR_MEMORY.LCMXO2_A(CHIPS)':
 'PL1D': CDS_PINID='PL1D';
NET_NAME
'FM_PCH_PLD_DATA_R'
 '@BASEBOARD_FAB2_LIB.BASEBOARD_FAB2(SCH_1):FM_PCH_PLD_DATA_R':
 C_SIGNAL='@baseboard_fab2_lib.baseboard_fab2(sch_1):fm_pch_pld_data_r';
NODE_NAME     U7C1 BM42
 '@BASEBOARD_FAB2_LIB.BASEBOARD_FAB2(SCH_1):PAGE119_I115@MSTR_U_PROC.LBG_CORE_QAT_EXT_D(CHIPS)':
 'GPP_D4': CDS_PINID='GPP_D4';
NODE_NAME     R2M3 1
 '@BASEBOARD_FAB2_LIB.BASEBOARD_FAB2(SCH_1):PAGE119_I172@MSTR_DISCRETE.RES(CHIPS)':
 'A': CDS_PINID='A';
NET_NAME
'FM_PCH_PRSNT_N'
 '@BASEBOARD_FAB2_LIB.BASEBOARD_FAB2(SCH_1):FM_PCH_PRSNT_N':
 C_SIGNAL='@baseboard_fab2_lib.baseboard_fab2(sch_1):fm_pch_prsnt_n';
NODE_NAME     U7C1 C70
 '@BASEBOARD_FAB2_LIB.BASEBOARD_FAB2(SCH_1):PAGE121_I34@MSTR_U_PROC.LBG_CORE_QAT_EXT_D(CHIPS)':
 'CGC_DUT_DETECT_N': CDS_PINID='CGC_DUT_DETECT_N';
NODE_NAME     R7B6 2
 '@BASEBOARD_FAB2_LIB.BASEBOARD_FAB2(SCH_1):PAGE133_I295@MSTR_DISCRETE.RES(CHIPS)':
 'B': CDS_PINID='B';
NODE_NAME     U8D7 A3
 '@BASEBOARD_FAB2_LIB.BASEBOARD_FAB2(SCH_1):PAGE191_I59@MSTR_MEMORY.LCMXO2_A(CHIPS)':
 'PT11C': CDS_PINID='PT11C';
NET_NAME
'FM_PCH_PWRBTN_N'
 '@BASEBOARD_FAB2_LIB.BASEBOARD_FAB2(SCH_1):FM_PCH_PWRBTN_N':
 C_SIGNAL='@baseboard_fab2_lib.baseboard_fab2(sch_1):fm_pch_pwrbtn_n';
NODE_NAME     U7C1 C15
 '@BASEBOARD_FAB2_LIB.BASEBOARD_FAB2(SCH_1):PAGE118_I73@MSTR_U_PROC.LBG_CORE_QAT_EXT_D(CHIPS)':
 'GPD3_PWRBTN_N': CDS_PINID='GPD3_PWRBTN_N';
NODE_NAME     R2T28 2
 '@BASEBOARD_FAB2_LIB.BASEBOARD_FAB2(SCH_1):PAGE156_I289@MSTR_DISCRETE.RES(CHIPS)':
 'B': CDS_PINID='B';
NODE_NAME     R1W28 2
 '@BASEBOARD_FAB2_LIB.BASEBOARD_FAB2(SCH_1):PAGE191_I197@MSTR_DISCRETE.RES(CHIPS)':
 'B': CDS_PINID='B';
NET_NAME
'FM_PCH_PWRBTN_OUT_N'
 '@BASEBOARD_FAB2_LIB.BASEBOARD_FAB2(SCH_1):FM_PCH_PWRBTN_OUT_N':
 C_SIGNAL='@baseboard_fab2_lib.baseboard_fab2(sch_1):fm_pch_pwrbtn_out_n';
NODE_NAME     U7C1 BG15
 '@BASEBOARD_FAB2_LIB.BASEBOARD_FAB2(SCH_1):PAGE119_I115@MSTR_U_PROC.LBG_CORE_QAT_EXT_D(CHIPS)':
 'GPP_B17': CDS_PINID='GPP_B17';
NODE_NAME     R8G2 2
 '@BASEBOARD_FAB2_LIB.BASEBOARD_FAB2(SCH_1):PAGE156_I267@MSTR_DISCRETE.RES(CHIPS)':
 'B': CDS_PINID='B';
NODE_NAME     U8G1 3
 '@BASEBOARD_FAB2_LIB.BASEBOARD_FAB2(SCH_1):PAGE156_I342@W_HDL.SN74LVC2G07DCKR-GP(CHIPS)':
 '2A': CDS_PINID='\2a\';
NET_NAME
'FM_PCH_PWRBTN_R1_N'
 '@BASEBOARD_FAB2_LIB.BASEBOARD_FAB2(SCH_1):FM_PCH_PWRBTN_R1_N':
 C_SIGNAL='@baseboard_fab2_lib.baseboard_fab2(sch_1):fm_pch_pwrbtn_r1_n';
NODE_NAME     U8D7 B12
 '@BASEBOARD_FAB2_LIB.BASEBOARD_FAB2(SCH_1):PAGE191_I59@MSTR_MEMORY.LCMXO2_A(CHIPS)':
 'PT23B': CDS_PINID='PT23B';
NODE_NAME     R1W28 1
 '@BASEBOARD_FAB2_LIB.BASEBOARD_FAB2(SCH_1):PAGE191_I197@MSTR_DISCRETE.RES(CHIPS)':
 'A': CDS_PINID='A';
NET_NAME
'FM_PCH_PWRBTN_R_N'
 '@BASEBOARD_FAB2_LIB.BASEBOARD_FAB2(SCH_1):FM_PCH_PWRBTN_R_N':
 C_SIGNAL='@baseboard_fab2_lib.baseboard_fab2(sch_1):fm_pch_pwrbtn_r_n';
NODE_NAME     R8F26 2
 '@BASEBOARD_FAB2_LIB.BASEBOARD_FAB2(SCH_1):PAGE156_I211@MSTR_DISCRETE.RES(CHIPS)':
 'B': CDS_PINID='B';
NODE_NAME     R2T28 1
 '@BASEBOARD_FAB2_LIB.BASEBOARD_FAB2(SCH_1):PAGE156_I289@MSTR_DISCRETE.RES(CHIPS)':
 'A': CDS_PINID='A';
NODE_NAME     U8F3 4
 '@BASEBOARD_FAB2_LIB.BASEBOARD_FAB2(SCH_1):PAGE156_I340@W_HDL.SN74LVC2G07DCKR-GP(CHIPS)':
 '2Y': CDS_PINID='\2y\';
NODE_NAME     U8G1 4
 '@BASEBOARD_FAB2_LIB.BASEBOARD_FAB2(SCH_1):PAGE156_I342@W_HDL.SN74LVC2G07DCKR-GP(CHIPS)':
 '2Y': CDS_PINID='\2y\';
NET_NAME
'FM_PCH_SATA_RAID_KEY'
 '@BASEBOARD_FAB2_LIB.BASEBOARD_FAB2(SCH_1):FM_PCH_SATA_RAID_KEY':
 C_SIGNAL='@baseboard_fab2_lib.baseboard_fab2(sch_1):fm_pch_sata_raid_key';
NODE_NAME     U7C1 BV31
 '@BASEBOARD_FAB2_LIB.BASEBOARD_FAB2(SCH_1):PAGE119_I115@MSTR_U_PROC.LBG_CORE_QAT_EXT_D(CHIPS)':
 'GPP_C10': CDS_PINID='GPP_C10';
NODE_NAME     R9A13 2
 '@BASEBOARD_FAB2_LIB.BASEBOARD_FAB2(SCH_1):PAGE135_I118@MSTR_DISCRETE.RES(CHIPS)':
 'B': CDS_PINID='B';
NET_NAME
'FM_PCH_SATA_RAID_KEY_R'
 '@BASEBOARD_FAB2_LIB.BASEBOARD_FAB2(SCH_1):FM_PCH_SATA_RAID_KEY_R':
 C_SIGNAL='@baseboard_fab2_lib.baseboard_fab2(sch_1):fm_pch_sata_raid_key_r';
NODE_NAME     R9A12 1
 '@BASEBOARD_FAB2_LIB.BASEBOARD_FAB2(SCH_1):PAGE135_I117@MSTR_DISCRETE.RES(CHIPS)':
 'A': CDS_PINID='A';
NODE_NAME     R9A13 1
 '@BASEBOARD_FAB2_LIB.BASEBOARD_FAB2(SCH_1):PAGE135_I118@MSTR_DISCRETE.RES(CHIPS)':
 'A': CDS_PINID='A';
NODE_NAME     J9A1 4
 '@BASEBOARD_FAB2_LIB.BASEBOARD_FAB2(SCH_1):PAGE135_I131@MSTR_CONN.CONN4_D42317002(CHIPS)':
 'IO4': CDS_PINID='IO4';
NET_NAME
'FM_PE_BMC_WAKE_N'
 '@BASEBOARD_FAB2_LIB.BASEBOARD_FAB2(SCH_1):FM_PE_BMC_WAKE_N':
 C_SIGNAL='@baseboard_fab2_lib.baseboard_fab2(sch_1):fm_pe_bmc_wake_n';
NODE_NAME     R8E29 1
 '@BASEBOARD_FAB2_LIB.BASEBOARD_FAB2(SCH_1):PAGE142_I18@MSTR_DISCRETE.RES(CHIPS)':
 'A': CDS_PINID='A';
NODE_NAME     R25W63 1
 '@BASEBOARD_FAB2_LIB.BASEBOARD_FAB2(SCH_1):PAGE146_I65@MSTR_DISCRETE.RES(CHIPS)':
 'A': CDS_PINID='A';
NODE_NAME     U25W4 N20
 '@BASEBOARD_FAB2_LIB.BASEBOARD_FAB2(SCH_1):PAGE146_I105@W_HDL.AST2520A1-GP-GP(CHIPS)':
 'GPIOQ7_PEWAKE#': CDS_PINID='\gpioq7_pewake#\';
NET_NAME
'FM_PE_M2_WAKE_N'
 '@BASEBOARD_FAB2_LIB.BASEBOARD_FAB2(SCH_1):FM_PE_M2_WAKE_N':
 C_SIGNAL='@baseboard_fab2_lib.baseboard_fab2(sch_1):fm_pe_m2_wake_n';
NODE_NAME     R8E27 1
 '@BASEBOARD_FAB2_LIB.BASEBOARD_FAB2(SCH_1):PAGE142_I32@MSTR_DISCRETE.RES(CHIPS)':
 'A': CDS_PINID='A';
NODE_NAME     J8F1 54
 '@BASEBOARD_FAB2_LIB.BASEBOARD_FAB2(SCH_1):PAGE185_I143@W_HDL.SKT-MINI67P-41-GP(CHIPS)':
 '54': CDS_PINID='\54\';
NET_NAME
'FM_PE_OCP_WAKE_N'
 '@BASEBOARD_FAB2_LIB.BASEBOARD_FAB2(SCH_1):FM_PE_OCP_WAKE_N':
 C_SIGNAL='@baseboard_fab2_lib.baseboard_fab2(sch_1):fm_pe_ocp_wake_n';
NODE_NAME     R8E26 1
 '@BASEBOARD_FAB2_LIB.BASEBOARD_FAB2(SCH_1):PAGE142_I30@MSTR_DISCRETE.RES(CHIPS)':
 'A': CDS_PINID='A';
NODE_NAME     J9B3 34
 '@BASEBOARD_FAB2_LIB.BASEBOARD_FAB2(SCH_1):PAGE186_I336@MSTR_SCONN.SCONN120_A28699018(CHIPS)':
 'IO34': CDS_PINID='IO34';
NET_NAME
'FM_PE_SLOTX24_WAKE_N'
 '@BASEBOARD_FAB2_LIB.BASEBOARD_FAB2(SCH_1):FM_PE_SLOTX24_WAKE_N':
 C_SIGNAL='@baseboard_fab2_lib.baseboard_fab2(sch_1):fm_pe_slotx24_wake_n';
NODE_NAME     J8G1 28
 '@BASEBOARD_FAB2_LIB.BASEBOARD_FAB2(SCH_1):PAGE108_I258@MSTR_SCONN.SCONN200_H68296001(CHIPS)':
 'IO28': CDS_PINID='IO28';
NODE_NAME     R8E28 1
 '@BASEBOARD_FAB2_LIB.BASEBOARD_FAB2(SCH_1):PAGE142_I31@MSTR_DISCRETE.RES(CHIPS)':
 'A': CDS_PINID='A';
NODE_NAME     R8E36 2
 '@BASEBOARD_FAB2_LIB.BASEBOARD_FAB2(SCH_1):PAGE142_I34@W_HDL.2K15R2F-1-GP(CHIPS)':
 '2': CDS_PINID='\2\';
NET_NAME
'FM_PE_SPRV_WAKE_N'
 '@BASEBOARD_FAB2_LIB.BASEBOARD_FAB2(SCH_1):FM_PE_SPRV_WAKE_N':
 C_SIGNAL='@baseboard_fab2_lib.baseboard_fab2(sch_1):fm_pe_sprv_wake_n';
NODE_NAME     EU9E1 16
 '@BASEBOARD_FAB2_LIB.BASEBOARD_FAB2(SCH_1):PAGE139_I72@MSTR_INTEL.SPRINGVILLE(CHIPS)':
 'PE_WAKE_N': CDS_PINID='PE_WAKE_N';
NODE_NAME     R8E21 1
 '@BASEBOARD_FAB2_LIB.BASEBOARD_FAB2(SCH_1):PAGE142_I33@MSTR_DISCRETE.RES(CHIPS)':
 'A': CDS_PINID='A';
NET_NAME
'FM_PLD_DEBUG_MODE_N'
 '@BASEBOARD_FAB2_LIB.BASEBOARD_FAB2(SCH_1):FM_PLD_DEBUG_MODE_N':
 C_SIGNAL='@baseboard_fab2_lib.baseboard_fab2(sch_1):fm_pld_debug_mode_n';
NODE_NAME     U8D7 F7
 '@BASEBOARD_FAB2_LIB.BASEBOARD_FAB2(SCH_1):PAGE191_I59@MSTR_MEMORY.LCMXO2_A(CHIPS)':
 'PT16A': CDS_PINID='PT16A';
NODE_NAME     R2R3 2
 '@BASEBOARD_FAB2_LIB.BASEBOARD_FAB2(SCH_1):PAGE192_I41@MSTR_DISCRETE.RES(CHIPS)':
 'B': CDS_PINID='B';
NET_NAME
'FM_PMBUS_ALERT_BUF_EN'
 '@BASEBOARD_FAB2_LIB.BASEBOARD_FAB2(SCH_1):FM_PMBUS_ALERT_BUF_EN':
 C_SIGNAL='@baseboard_fab2_lib.baseboard_fab2(sch_1):fm_pmbus_alert_buf_en';
NODE_NAME     U8D5 1
 '@BASEBOARD_FAB2_LIB.BASEBOARD_FAB2(SCH_1):PAGE170_I38@MSTR_TTL.TTL1G126_A(CHIPS)':
 'OE': CDS_PINID='OE';
NODE_NAME     R2P5 2
 '@BASEBOARD_FAB2_LIB.BASEBOARD_FAB2(SCH_1):PAGE170_I56@MSTR_DISCRETE.RES(CHIPS)':
 'B': CDS_PINID='B';
NODE_NAME     Q2P1 3
 '@BASEBOARD_FAB2_LIB.BASEBOARD_FAB2(SCH_1):PAGE170_I58@MSTR_DISCRETE.FET_N(CHIPS)':
 'DRN': CDS_PINID='DRN';
NET_NAME
'FM_PMBUS_ALERT_BUF_EN_N'
 '@BASEBOARD_FAB2_LIB.BASEBOARD_FAB2(SCH_1):FM_PMBUS_ALERT_BUF_EN_N':
 C_SIGNAL='@baseboard_fab2_lib.baseboard_fab2(sch_1):fm_pmbus_alert_buf_en_n';
NODE_NAME     Q2P1 1
 '@BASEBOARD_FAB2_LIB.BASEBOARD_FAB2(SCH_1):PAGE170_I58@MSTR_DISCRETE.FET_N(CHIPS)':
 'GATE': CDS_PINID='GATE';
NODE_NAME     R2P13 2
 '@BASEBOARD_FAB2_LIB.BASEBOARD_FAB2(SCH_1):PAGE170_I61@MSTR_DISCRETE.RES(CHIPS)':
 'B': CDS_PINID='B';
NODE_NAME     R2P11 1
 '@BASEBOARD_FAB2_LIB.BASEBOARD_FAB2(SCH_1):PAGE170_I63@MSTR_DISCRETE.RES(CHIPS)':
 'A': CDS_PINID='A';
NODE_NAME     R2W3 2
 '@BASEBOARD_FAB2_LIB.BASEBOARD_FAB2(SCH_1):PAGE119_I223@MSTR_DISCRETE.RES(CHIPS)':
 'B': CDS_PINID='B';
NODE_NAME     R2W4 1
 '@BASEBOARD_FAB2_LIB.BASEBOARD_FAB2(SCH_1):PAGE119_I224@MSTR_DISCRETE.RES(CHIPS)':
 'A': CDS_PINID='A';
NODE_NAME     R2W5 2
 '@BASEBOARD_FAB2_LIB.BASEBOARD_FAB2(SCH_1):PAGE145_I176@MSTR_DISCRETE.RES(CHIPS)':
 'B': CDS_PINID='B';
NET_NAME
'FM_PMBUS_ALERT_BUF_EN_R2_N'
 '@BASEBOARD_FAB2_LIB.BASEBOARD_FAB2(SCH_1):FM_PMBUS_ALERT_BUF_EN_R2_N':
 C_SIGNAL='@baseboard_fab2_lib.baseboard_fab2(sch_1):fm_pmbus_alert_buf_en_r2_n';
NODE_NAME     U7C1 BK9
 '@BASEBOARD_FAB2_LIB.BASEBOARD_FAB2(SCH_1):PAGE119_I115@MSTR_U_PROC.LBG_CORE_QAT_EXT_D(CHIPS)':
 'GPP_B11': CDS_PINID='GPP_B11';
NODE_NAME     R2W4 2
 '@BASEBOARD_FAB2_LIB.BASEBOARD_FAB2(SCH_1):PAGE119_I224@MSTR_DISCRETE.RES(CHIPS)':
 'B': CDS_PINID='B';
NET_NAME
'FM_PMBUS_ALERT_BUF_EN_R3_N'
 '@BASEBOARD_FAB2_LIB.BASEBOARD_FAB2(SCH_1):FM_PMBUS_ALERT_BUF_EN_R3_N':
 C_SIGNAL='@baseboard_fab2_lib.baseboard_fab2(sch_1):fm_pmbus_alert_buf_en_r3_n';
NODE_NAME     U25W4 P3
 '@BASEBOARD_FAB2_LIB.BASEBOARD_FAB2(SCH_1):PAGE145_I117@W_HDL.AST2520A1-GP-GP(CHIPS)':
 'GPIOL5_NRTS1_VPICLK': CDS_PINID='GPIOL5_NRTS1_VPICLK';
NODE_NAME     R2W5 1
 '@BASEBOARD_FAB2_LIB.BASEBOARD_FAB2(SCH_1):PAGE145_I176@MSTR_DISCRETE.RES(CHIPS)':
 'A': CDS_PINID='A';
NET_NAME
'FM_PMBUS_ALERT_BUF_EN_R_N'
 '@BASEBOARD_FAB2_LIB.BASEBOARD_FAB2(SCH_1):FM_PMBUS_ALERT_BUF_EN_R_N':
 C_SIGNAL='@baseboard_fab2_lib.baseboard_fab2(sch_1):fm_pmbus_alert_buf_en_r_n';
NODE_NAME     U7C1 BY35
 '@BASEBOARD_FAB2_LIB.BASEBOARD_FAB2(SCH_1):PAGE119_I115@MSTR_U_PROC.LBG_CORE_QAT_EXT_D(CHIPS)':
 'GPP_C18': CDS_PINID='GPP_C18';
NODE_NAME     R2W3 1
 '@BASEBOARD_FAB2_LIB.BASEBOARD_FAB2(SCH_1):PAGE119_I223@MSTR_DISCRETE.RES(CHIPS)':
 'A': CDS_PINID='A';
NET_NAME
'FM_POST_CARD_PRES_BMC_N'
 '@BASEBOARD_FAB2_LIB.BASEBOARD_FAB2(SCH_1):FM_POST_CARD_PRES_BMC_N':
 C_SIGNAL='@baseboard_fab2_lib.baseboard_fab2(sch_1):fm_post_card_pres_bmc_n';
NODE_NAME     Q1L4 6
 '@BASEBOARD_FAB2_LIB.BASEBOARD_FAB2(SCH_1):PAGE168_I19@MSTR_DISCRETE.FET_N_DUAL(CHIPS)':
 'DRAIN'<0>: CDS_PINID='DRAIN(0)';
NODE_NAME     R1L38 2
 '@BASEBOARD_FAB2_LIB.BASEBOARD_FAB2(SCH_1):PAGE168_I22@MSTR_DISCRETE.RES(CHIPS)':
 'B': CDS_PINID='B';
NODE_NAME     U25W4 B10
 '@BASEBOARD_FAB2_LIB.BASEBOARD_FAB2(SCH_1):PAGE146_I105@W_HDL.AST2520A1-GP-GP(CHIPS)':
 'GPIOQ6_OSCCLK': CDS_PINID='GPIOQ6_OSCCLK';
NODE_NAME     Q6W4 3
 '@BASEBOARD_FAB2_LIB.BASEBOARD_FAB2(SCH_1):PAGE168_I43@MSTR_DISCRETE.FET_N(CHIPS)':
 'DRN': CDS_PINID='DRN';
NODE_NAME     R7W8 1
 '@BASEBOARD_FAB2_LIB.BASEBOARD_FAB2(SCH_1):PAGE120_I269@MSTR_DISCRETE.RES(CHIPS)':
 'A': CDS_PINID='A';
NET_NAME
'FM_POST_CARD_PRES_BMC_R1_N'
 '@BASEBOARD_FAB2_LIB.BASEBOARD_FAB2(SCH_1):FM_POST_CARD_PRES_BMC_R1_N':
 C_SIGNAL='@baseboard_fab2_lib.baseboard_fab2(sch_1):fm_post_card_pres_bmc_r1_n';
NODE_NAME     U7C1 BG52
 '@BASEBOARD_FAB2_LIB.BASEBOARD_FAB2(SCH_1):PAGE120_I147@MSTR_U_PROC.LBG_CORE_QAT_EXT_D(CHIPS)':
 'GPP_E2_SATAXPCIE2_SATAGP2': CDS_PINID='GPP_E2_SATAXPCIE2_SATAGP2';
NODE_NAME     R7W8 2
 '@BASEBOARD_FAB2_LIB.BASEBOARD_FAB2(SCH_1):PAGE120_I269@MSTR_DISCRETE.RES(CHIPS)':
 'B': CDS_PINID='B';
NODE_NAME     R7W20 2
 '@BASEBOARD_FAB2_LIB.BASEBOARD_FAB2(SCH_1):PAGE120_I278@MSTR_DISCRETE.RES(CHIPS)':
 'B': CDS_PINID='B';
NET_NAME
'FM_PRSNT_2_1_N'
 '@BASEBOARD_FAB2_LIB.BASEBOARD_FAB2(SCH_1):FM_PRSNT_2_1_N':
 C_SIGNAL='@baseboard_fab2_lib.baseboard_fab2(sch_1):fm_prsnt_2_1_n';
NODE_NAME     U7C1 AE18
 '@BASEBOARD_FAB2_LIB.BASEBOARD_FAB2(SCH_1):PAGE121_I34@MSTR_U_PROC.LBG_CORE_QAT_EXT_D(CHIPS)':
 'GPP_L2_TESTCH0_D0': CDS_PINID='GPP_L2_TESTCH0_D0';
NODE_NAME     R3P7 2
 '@BASEBOARD_FAB2_LIB.BASEBOARD_FAB2(SCH_1):PAGE133_I370@MSTR_DISCRETE.RES(CHIPS)':
 'B': CDS_PINID='B';
NET_NAME
'FM_PRSNT_2_2_N'
 '@BASEBOARD_FAB2_LIB.BASEBOARD_FAB2(SCH_1):FM_PRSNT_2_2_N':
 C_SIGNAL='@baseboard_fab2_lib.baseboard_fab2(sch_1):fm_prsnt_2_2_n';
NODE_NAME     U7C1 AE15
 '@BASEBOARD_FAB2_LIB.BASEBOARD_FAB2(SCH_1):PAGE121_I34@MSTR_U_PROC.LBG_CORE_QAT_EXT_D(CHIPS)':
 'GPP_L3_TESTCH0_D1': CDS_PINID='GPP_L3_TESTCH0_D1';
NODE_NAME     R3P5 2
 '@BASEBOARD_FAB2_LIB.BASEBOARD_FAB2(SCH_1):PAGE133_I366@MSTR_DISCRETE.RES(CHIPS)':
 'B': CDS_PINID='B';
NET_NAME
'FM_PRSNT_2_3_N'
 '@BASEBOARD_FAB2_LIB.BASEBOARD_FAB2(SCH_1):FM_PRSNT_2_3_N':
 C_SIGNAL='@baseboard_fab2_lib.baseboard_fab2(sch_1):fm_prsnt_2_3_n';
NODE_NAME     U7C1 AE11
 '@BASEBOARD_FAB2_LIB.BASEBOARD_FAB2(SCH_1):PAGE121_I34@MSTR_U_PROC.LBG_CORE_QAT_EXT_D(CHIPS)':
 'GPP_L4_TESTCH0_D2': CDS_PINID='GPP_L4_TESTCH0_D2';
NODE_NAME     R3P6 2
 '@BASEBOARD_FAB2_LIB.BASEBOARD_FAB2(SCH_1):PAGE133_I367@MSTR_DISCRETE.RES(CHIPS)':
 'B': CDS_PINID='B';
NET_NAME
'FM_PRSNT_2_4_N'
 '@BASEBOARD_FAB2_LIB.BASEBOARD_FAB2(SCH_1):FM_PRSNT_2_4_N':
 C_SIGNAL='@baseboard_fab2_lib.baseboard_fab2(sch_1):fm_prsnt_2_4_n';
NODE_NAME     U7C1 Y18
 '@BASEBOARD_FAB2_LIB.BASEBOARD_FAB2(SCH_1):PAGE121_I34@MSTR_U_PROC.LBG_CORE_QAT_EXT_D(CHIPS)':
 'GPP_L5_TESTCH0_D3': CDS_PINID='GPP_L5_TESTCH0_D3';
NODE_NAME     R3N15 2
 '@BASEBOARD_FAB2_LIB.BASEBOARD_FAB2(SCH_1):PAGE133_I368@MSTR_DISCRETE.RES(CHIPS)':
 'B': CDS_PINID='B';
NET_NAME
'FM_PRSNT_2_5_N'
 '@BASEBOARD_FAB2_LIB.BASEBOARD_FAB2(SCH_1):FM_PRSNT_2_5_N':
 C_SIGNAL='@baseboard_fab2_lib.baseboard_fab2(sch_1):fm_prsnt_2_5_n';
NODE_NAME     U7C1 AA20
 '@BASEBOARD_FAB2_LIB.BASEBOARD_FAB2(SCH_1):PAGE121_I34@MSTR_U_PROC.LBG_CORE_QAT_EXT_D(CHIPS)':
 'GPP_L6_TESTCH0_D4': CDS_PINID='GPP_L6_TESTCH0_D4';
NODE_NAME     R3N16 2
 '@BASEBOARD_FAB2_LIB.BASEBOARD_FAB2(SCH_1):PAGE133_I369@MSTR_DISCRETE.RES(CHIPS)':
 'B': CDS_PINID='B';
NET_NAME
'FM_PRSNT_2_6_N'
 '@BASEBOARD_FAB2_LIB.BASEBOARD_FAB2(SCH_1):FM_PRSNT_2_6_N':
 C_SIGNAL='@baseboard_fab2_lib.baseboard_fab2(sch_1):fm_prsnt_2_6_n';
NODE_NAME     U7C1 AA17
 '@BASEBOARD_FAB2_LIB.BASEBOARD_FAB2(SCH_1):PAGE121_I34@MSTR_U_PROC.LBG_CORE_QAT_EXT_D(CHIPS)':
 'GPP_L7_TESTCH0_D5': CDS_PINID='GPP_L7_TESTCH0_D5';
NODE_NAME     R3P8 2
 '@BASEBOARD_FAB2_LIB.BASEBOARD_FAB2(SCH_1):PAGE133_I322@MSTR_DISCRETE.RES(CHIPS)':
 'B': CDS_PINID='B';
NODE_NAME     J8G1 199
 '@BASEBOARD_FAB2_LIB.BASEBOARD_FAB2(SCH_1):PAGE109_I78@MSTR_SCONN.SCONN200_H68296001(CHIPS)':
 'IO199': CDS_PINID='IO199';
NET_NAME
'FM_PS_EN'
 '@BASEBOARD_FAB2_LIB.BASEBOARD_FAB2(SCH_1):FM_PS_EN':
 C_SIGNAL='@baseboard_fab2_lib.baseboard_fab2(sch_1):fm_ps_en';
NODE_NAME     U8D7 F9
 '@BASEBOARD_FAB2_LIB.BASEBOARD_FAB2(SCH_1):PAGE191_I59@MSTR_MEMORY.LCMXO2_A(CHIPS)':
 'PT19C': CDS_PINID='PT19C';
NODE_NAME     C2R6 1
 '@BASEBOARD_FAB2_LIB.BASEBOARD_FAB2(SCH_1):PAGE181_I40@MSTR_DISCRETE.CAP(CHIPS)':
 'A': CDS_PINID='A';
NODE_NAME     U8E1 9
 '@BASEBOARD_FAB2_LIB.BASEBOARD_FAB2(SCH_1):PAGE181_I60@MSTR_TTL.TTL08(CHIPS)':
 'A'<0>: CDS_PINID='A(0)';
NET_NAME
'FM_PVCCIN_CPU0_PWR_IN_ALERT_N'
 '@BASEBOARD_FAB2_LIB.BASEBOARD_FAB2(SCH_1):FM_PVCCIN_CPU0_PWR_IN_ALERT_N':
 C_SIGNAL='@baseboard_fab2_lib.baseboard_fab2(sch_1):fm_pvccin_cpu0_pwr_in_alert~
_n';
NODE_NAME     U7E2 1
 '@BASEBOARD_FAB2_LIB.BASEBOARD_FAB2(SCH_1):PAGE95_I117@MSTR_TTL.TTL1G08(CHIPS)':
 'A'<0>: CDS_PINID='A(0)';
NODE_NAME     EU4D4 14
 '@BASEBOARD_FAB2_LIB.BASEBOARD_FAB2(SCH_1):PAGE201_I155@MSTR_CONTROLLER.PXE1610B(CHIPS)':
 'PINALRT_N': CDS_PINID='PINALRT_N';
NODE_NAME     R4E4 2
 '@BASEBOARD_FAB2_LIB.BASEBOARD_FAB2(SCH_1):PAGE201_I187@MSTR_DISCRETE.RES(CHIPS)':
 'B': CDS_PINID='B';
NET_NAME
'FM_PVCCIN_CPU1_PWR_IN_ALERT_N'
 '@BASEBOARD_FAB2_LIB.BASEBOARD_FAB2(SCH_1):FM_PVCCIN_CPU1_PWR_IN_ALERT_N':
 C_SIGNAL='@baseboard_fab2_lib.baseboard_fab2(sch_1):fm_pvccin_cpu1_pwr_in_alert~
_n';
NODE_NAME     U7E3 1
 '@BASEBOARD_FAB2_LIB.BASEBOARD_FAB2(SCH_1):PAGE95_I118@MSTR_TTL.TTL1G08(CHIPS)':
 'A'<0>: CDS_PINID='A(0)';
NODE_NAME     EU1C2 14
 '@BASEBOARD_FAB2_LIB.BASEBOARD_FAB2(SCH_1):PAGE206_I130@MSTR_CONTROLLER.PXE1610B(CHIPS)':
 'PINALRT_N': CDS_PINID='PINALRT_N';
NODE_NAME     R1D7 2
 '@BASEBOARD_FAB2_LIB.BASEBOARD_FAB2(SCH_1):PAGE206_I155@MSTR_DISCRETE.RES(CHIPS)':
 'B': CDS_PINID='B';
NET_NAME
'FM_PVCCIN_PVCCSA_CPU0_EN_LVC1'
 '@BASEBOARD_FAB2_LIB.BASEBOARD_FAB2(SCH_1):FM_PVCCIN_PVCCSA_CPU0_EN_LVC1':
 C_SIGNAL='@baseboard_fab2_lib.baseboard_fab2(sch_1):fm_pvccin_pvccsa_cpu0_en_lv~
c1';
NODE_NAME     U8D7 A10
 '@BASEBOARD_FAB2_LIB.BASEBOARD_FAB2(SCH_1):PAGE191_I59@MSTR_MEMORY.LCMXO2_A(CHIPS)':
 'PT19B': CDS_PINID='PT19B';
NODE_NAME     R6P18 1
 '@BASEBOARD_FAB2_LIB.BASEBOARD_FAB2(SCH_1):PAGE201_I131@MSTR_DISCRETE.RES(CHIPS)':
 'A': CDS_PINID='A';
NET_NAME
'FM_PVCCIN_PVCCSA_CPU1_EN_LVC1'
 '@BASEBOARD_FAB2_LIB.BASEBOARD_FAB2(SCH_1):FM_PVCCIN_PVCCSA_CPU1_EN_LVC1':
 C_SIGNAL='@baseboard_fab2_lib.baseboard_fab2(sch_1):fm_pvccin_pvccsa_cpu1_en_lv~
c1';
NODE_NAME     U8D7 N16
 '@BASEBOARD_FAB2_LIB.BASEBOARD_FAB2(SCH_1):PAGE191_I59@MSTR_MEMORY.LCMXO2_A(CHIPS)':
 'PR14A': CDS_PINID='PR14A';
NODE_NAME     R9N16 1
 '@BASEBOARD_FAB2_LIB.BASEBOARD_FAB2(SCH_1):PAGE206_I119@MSTR_DISCRETE.RES(CHIPS)':
 'A': CDS_PINID='A';
NET_NAME
'FM_PVCCIOMCP_CPU0_EN'
 '@BASEBOARD_FAB2_LIB.BASEBOARD_FAB2(SCH_1):FM_PVCCIOMCP_CPU0_EN':
 C_SIGNAL='@baseboard_fab2_lib.baseboard_fab2(sch_1):fm_pvcciomcp_cpu0_en';
NODE_NAME     U8D7 K1
 '@BASEBOARD_FAB2_LIB.BASEBOARD_FAB2(SCH_1):PAGE190_I179@MSTR_MEMORY.LCMXO2_A(CHIPS)':
 'PL9B': CDS_PINID='PL9B';
NODE_NAME     J6B1 A16
 '@BASEBOARD_FAB2_LIB.BASEBOARD_FAB2(SCH_1):PAGE194_I56@MSTR_SCONN.SCONN120_H61426002(CHIPS)':
 'IOA16': CDS_PINID='IOA16';
NET_NAME
'FM_PVCCIOMCP_CPU1_EN'
 '@BASEBOARD_FAB2_LIB.BASEBOARD_FAB2(SCH_1):FM_PVCCIOMCP_CPU1_EN':
 C_SIGNAL='@baseboard_fab2_lib.baseboard_fab2(sch_1):fm_pvcciomcp_cpu1_en';
NODE_NAME     U8D7 P7
 '@BASEBOARD_FAB2_LIB.BASEBOARD_FAB2(SCH_1):PAGE190_I179@MSTR_MEMORY.LCMXO2_A(CHIPS)':
 'PB9B': CDS_PINID='PB9B';
NODE_NAME     J4B2 A16
 '@BASEBOARD_FAB2_LIB.BASEBOARD_FAB2(SCH_1):PAGE193_I46@MSTR_SCONN.SCONN120_H61426002(CHIPS)':
 'IOA16': CDS_PINID='IOA16';
NET_NAME
'FM_PVCCIO_CPU0_EN'
 '@BASEBOARD_FAB2_LIB.BASEBOARD_FAB2(SCH_1):FM_PVCCIO_CPU0_EN':
 C_SIGNAL='@baseboard_fab2_lib.baseboard_fab2(sch_1):fm_pvccio_cpu0_en';
NODE_NAME     U8D7 M7
 '@BASEBOARD_FAB2_LIB.BASEBOARD_FAB2(SCH_1):PAGE190_I179@MSTR_MEMORY.LCMXO2_A(CHIPS)':
 'PB9C': CDS_PINID='PB9C';
NODE_NAME     R3P26 1
 '@BASEBOARD_FAB2_LIB.BASEBOARD_FAB2(SCH_1):PAGE211_I87@MSTR_DISCRETE.RES(CHIPS)':
 'A': CDS_PINID='A';
NET_NAME
'FM_PVCCIO_CPU1_EN'
 '@BASEBOARD_FAB2_LIB.BASEBOARD_FAB2(SCH_1):FM_PVCCIO_CPU1_EN':
 C_SIGNAL='@baseboard_fab2_lib.baseboard_fab2(sch_1):fm_pvccio_cpu1_en';
NODE_NAME     U8D7 T7
 '@BASEBOARD_FAB2_LIB.BASEBOARD_FAB2(SCH_1):PAGE190_I179@MSTR_MEMORY.LCMXO2_A(CHIPS)':
 'PB11A_PCLKT2_0': CDS_PINID='PB11A_PCLKT2_0';
NODE_NAME     R6P41 1
 '@BASEBOARD_FAB2_LIB.BASEBOARD_FAB2(SCH_1):PAGE213_I90@MSTR_DISCRETE.RES(CHIPS)':
 'A': CDS_PINID='A';
NET_NAME
'FM_PVCCMCP_CPU0_EN'
 '@BASEBOARD_FAB2_LIB.BASEBOARD_FAB2(SCH_1):FM_PVCCMCP_CPU0_EN':
 C_SIGNAL='@baseboard_fab2_lib.baseboard_fab2(sch_1):fm_pvccmcp_cpu0_en';
NODE_NAME     U8D7 H2
 '@BASEBOARD_FAB2_LIB.BASEBOARD_FAB2(SCH_1):PAGE190_I179@MSTR_MEMORY.LCMXO2_A(CHIPS)':
 'PL6B': CDS_PINID='PL6B';
NODE_NAME     J6B1 C20
 '@BASEBOARD_FAB2_LIB.BASEBOARD_FAB2(SCH_1):PAGE194_I56@MSTR_SCONN.SCONN120_H61426002(CHIPS)':
 'IOC20': CDS_PINID='IOC20';
NET_NAME
'FM_PVCCMCP_CPU1_EN'
 '@BASEBOARD_FAB2_LIB.BASEBOARD_FAB2(SCH_1):FM_PVCCMCP_CPU1_EN':
 C_SIGNAL='@baseboard_fab2_lib.baseboard_fab2(sch_1):fm_pvccmcp_cpu1_en';
NODE_NAME     U8D7 M8
 '@BASEBOARD_FAB2_LIB.BASEBOARD_FAB2(SCH_1):PAGE190_I179@MSTR_MEMORY.LCMXO2_A(CHIPS)':
 'PB16C': CDS_PINID='PB16C';
NODE_NAME     J4B2 C20
 '@BASEBOARD_FAB2_LIB.BASEBOARD_FAB2(SCH_1):PAGE193_I46@MSTR_SCONN.SCONN120_H61426002(CHIPS)':
 'IOC20': CDS_PINID='IOC20';
NET_NAME
'FM_PVDDQ_ABC_EN'
 '@BASEBOARD_FAB2_LIB.BASEBOARD_FAB2(SCH_1):FM_PVDDQ_ABC_EN':
 C_SIGNAL='@baseboard_fab2_lib.baseboard_fab2(sch_1):fm_pvddq_abc_en';
NODE_NAME     U8D7 K14
 '@BASEBOARD_FAB2_LIB.BASEBOARD_FAB2(SCH_1):PAGE191_I59@MSTR_MEMORY.LCMXO2_A(CHIPS)':
 'PR10A': CDS_PINID='PR10A';
NODE_NAME     R7F21 1
 '@BASEBOARD_FAB2_LIB.BASEBOARD_FAB2(SCH_1):PAGE215_I13@MSTR_DISCRETE.RES(CHIPS)':
 'A': CDS_PINID='A';
NET_NAME
'FM_PVDDQ_DEF_EN'
 '@BASEBOARD_FAB2_LIB.BASEBOARD_FAB2(SCH_1):FM_PVDDQ_DEF_EN':
 C_SIGNAL='@baseboard_fab2_lib.baseboard_fab2(sch_1):fm_pvddq_def_en';
NODE_NAME     U8D7 K15
 '@BASEBOARD_FAB2_LIB.BASEBOARD_FAB2(SCH_1):PAGE191_I59@MSTR_MEMORY.LCMXO2_A(CHIPS)':
 'PR10B': CDS_PINID='PR10B';
NODE_NAME     R3M6 1
 '@BASEBOARD_FAB2_LIB.BASEBOARD_FAB2(SCH_1):PAGE218_I15@MSTR_DISCRETE.RES(CHIPS)':
 'A': CDS_PINID='A';
NET_NAME
'FM_PVDDQ_GHJ_EN'
 '@BASEBOARD_FAB2_LIB.BASEBOARD_FAB2(SCH_1):FM_PVDDQ_GHJ_EN':
 C_SIGNAL='@baseboard_fab2_lib.baseboard_fab2(sch_1):fm_pvddq_ghj_en';
NODE_NAME     U8D7 H13
 '@BASEBOARD_FAB2_LIB.BASEBOARD_FAB2(SCH_1):PAGE191_I59@MSTR_MEMORY.LCMXO2_A(CHIPS)':
 'PR6C': CDS_PINID='PR6C';
NODE_NAME     R9U7 1
 '@BASEBOARD_FAB2_LIB.BASEBOARD_FAB2(SCH_1):PAGE223_I14@MSTR_DISCRETE.RES(CHIPS)':
 'A': CDS_PINID='A';
NET_NAME
'FM_PVDDQ_KLM_EN'
 '@BASEBOARD_FAB2_LIB.BASEBOARD_FAB2(SCH_1):FM_PVDDQ_KLM_EN':
 C_SIGNAL='@baseboard_fab2_lib.baseboard_fab2(sch_1):fm_pvddq_klm_en';
NODE_NAME     U8D7 H15
 '@BASEBOARD_FAB2_LIB.BASEBOARD_FAB2(SCH_1):PAGE191_I59@MSTR_MEMORY.LCMXO2_A(CHIPS)':
 'PR6B': CDS_PINID='PR6B';
NODE_NAME     R9M9 1
 '@BASEBOARD_FAB2_LIB.BASEBOARD_FAB2(SCH_1):PAGE226_I14@MSTR_DISCRETE.RES(CHIPS)':
 'A': CDS_PINID='A';
NET_NAME
'FM_PVPP_CPU0_EN'
 '@BASEBOARD_FAB2_LIB.BASEBOARD_FAB2(SCH_1):FM_PVPP_CPU0_EN':
 C_SIGNAL='@baseboard_fab2_lib.baseboard_fab2(sch_1):fm_pvpp_cpu0_en';
NODE_NAME     U8D7 P15
 '@BASEBOARD_FAB2_LIB.BASEBOARD_FAB2(SCH_1):PAGE191_I59@MSTR_MEMORY.LCMXO2_A(CHIPS)':
 'PR14C': CDS_PINID='PR14C';
NODE_NAME     R7F14 1
 '@BASEBOARD_FAB2_LIB.BASEBOARD_FAB2(SCH_1):PAGE231_I136@MSTR_DISCRETE.RES(CHIPS)':
 'A': CDS_PINID='A';
NODE_NAME     C7F8 1
 '@BASEBOARD_FAB2_LIB.BASEBOARD_FAB2(SCH_1):PAGE231_I140@MSTR_DISCRETE.CAP(CHIPS)':
 'A': CDS_PINID='A';
NODE_NAME     R7F9 1
 '@BASEBOARD_FAB2_LIB.BASEBOARD_FAB2(SCH_1):PAGE231_I220@MSTR_DISCRETE.RES(CHIPS)':
 'A': CDS_PINID='A';
NODE_NAME     C7B9 1
 '@BASEBOARD_FAB2_LIB.BASEBOARD_FAB2(SCH_1):PAGE232_I185@MSTR_DISCRETE.CAP(CHIPS)':
 'A': CDS_PINID='A';
NODE_NAME     R7B9 1
 '@BASEBOARD_FAB2_LIB.BASEBOARD_FAB2(SCH_1):PAGE232_I307@MSTR_DISCRETE.RES(CHIPS)':
 'A': CDS_PINID='A';
NET_NAME
'FM_PVPP_CPU1_EN'
 '@BASEBOARD_FAB2_LIB.BASEBOARD_FAB2(SCH_1):FM_PVPP_CPU1_EN':
 C_SIGNAL='@baseboard_fab2_lib.baseboard_fab2(sch_1):fm_pvpp_cpu1_en';
NODE_NAME     U8D7 P16
 '@BASEBOARD_FAB2_LIB.BASEBOARD_FAB2(SCH_1):PAGE191_I59@MSTR_MEMORY.LCMXO2_A(CHIPS)':
 'PR13D': CDS_PINID='PR13D';
NODE_NAME     R4G5 1
 '@BASEBOARD_FAB2_LIB.BASEBOARD_FAB2(SCH_1):PAGE233_I182@MSTR_DISCRETE.RES(CHIPS)':
 'A': CDS_PINID='A';
NODE_NAME     C4G7 1
 '@BASEBOARD_FAB2_LIB.BASEBOARD_FAB2(SCH_1):PAGE233_I183@MSTR_DISCRETE.CAP(CHIPS)':
 'A': CDS_PINID='A';
NODE_NAME     R4G4 1
 '@BASEBOARD_FAB2_LIB.BASEBOARD_FAB2(SCH_1):PAGE233_I275@MSTR_DISCRETE.RES(CHIPS)':
 'A': CDS_PINID='A';
NODE_NAME     C4B5 1
 '@BASEBOARD_FAB2_LIB.BASEBOARD_FAB2(SCH_1):PAGE234_I129@MSTR_DISCRETE.CAP(CHIPS)':
 'A': CDS_PINID='A';
NODE_NAME     R4B1 1
 '@BASEBOARD_FAB2_LIB.BASEBOARD_FAB2(SCH_1):PAGE234_I220@MSTR_DISCRETE.RES(CHIPS)':
 'A': CDS_PINID='A';
NET_NAME
'FM_PVPP_PVDDQ_CPU0_EN_ABC'
 '@BASEBOARD_FAB2_LIB.BASEBOARD_FAB2(SCH_1):FM_PVPP_PVDDQ_CPU0_EN_ABC':
 C_SIGNAL='@baseboard_fab2_lib.baseboard_fab2(sch_1):fm_pvpp_pvddq_cpu0_en_abc';
NODE_NAME     EU7F1 40
 '@BASEBOARD_FAB2_LIB.BASEBOARD_FAB2(SCH_1):PAGE231_I193@MSTR_VREG.NCP3232L(CHIPS)':
 'EN': CDS_PINID='EN';
NODE_NAME     R7F9 2
 '@BASEBOARD_FAB2_LIB.BASEBOARD_FAB2(SCH_1):PAGE231_I220@MSTR_DISCRETE.RES(CHIPS)':
 'B': CDS_PINID='B';
NET_NAME
'FM_PVPP_PVDDQ_CPU0_EN_DEF'
 '@BASEBOARD_FAB2_LIB.BASEBOARD_FAB2(SCH_1):FM_PVPP_PVDDQ_CPU0_EN_DEF':
 C_SIGNAL='@baseboard_fab2_lib.baseboard_fab2(sch_1):fm_pvpp_pvddq_cpu0_en_def';
NODE_NAME     EU7B1 40
 '@BASEBOARD_FAB2_LIB.BASEBOARD_FAB2(SCH_1):PAGE232_I214@MSTR_VREG.NCP3232L(CHIPS)':
 'EN': CDS_PINID='EN';
NODE_NAME     R7B9 2
 '@BASEBOARD_FAB2_LIB.BASEBOARD_FAB2(SCH_1):PAGE232_I307@MSTR_DISCRETE.RES(CHIPS)':
 'B': CDS_PINID='B';
NET_NAME
'FM_PVPP_PVDDQ_CPU1_EN_GHJ'
 '@BASEBOARD_FAB2_LIB.BASEBOARD_FAB2(SCH_1):FM_PVPP_PVDDQ_CPU1_EN_GHJ':
 C_SIGNAL='@baseboard_fab2_lib.baseboard_fab2(sch_1):fm_pvpp_pvddq_cpu1_en_ghj';
NODE_NAME     EU4G1 40
 '@BASEBOARD_FAB2_LIB.BASEBOARD_FAB2(SCH_1):PAGE233_I225@MSTR_VREG.NCP3232L(CHIPS)':
 'EN': CDS_PINID='EN';
NODE_NAME     R4G4 2
 '@BASEBOARD_FAB2_LIB.BASEBOARD_FAB2(SCH_1):PAGE233_I275@MSTR_DISCRETE.RES(CHIPS)':
 'B': CDS_PINID='B';
NET_NAME
'FM_PVPP_PVDDQ_CPU1_EN_KLM'
 '@BASEBOARD_FAB2_LIB.BASEBOARD_FAB2(SCH_1):FM_PVPP_PVDDQ_CPU1_EN_KLM':
 C_SIGNAL='@baseboard_fab2_lib.baseboard_fab2(sch_1):fm_pvpp_pvddq_cpu1_en_klm';
NODE_NAME     EU4A3 40
 '@BASEBOARD_FAB2_LIB.BASEBOARD_FAB2(SCH_1):PAGE234_I184@MSTR_VREG.NCP3232L(CHIPS)':
 'EN': CDS_PINID='EN';
NODE_NAME     R4B1 2
 '@BASEBOARD_FAB2_LIB.BASEBOARD_FAB2(SCH_1):PAGE234_I220@MSTR_DISCRETE.RES(CHIPS)':
 'B': CDS_PINID='B';
NET_NAME
'FM_PVTT_ABC_EN_R'
 '@BASEBOARD_FAB2_LIB.BASEBOARD_FAB2(SCH_1):FM_PVTT_ABC_EN_R':
 C_SIGNAL='@baseboard_fab2_lib.baseboard_fab2(sch_1):fm_pvtt_abc_en_r';
NODE_NAME     C4G23 1
 '@BASEBOARD_FAB2_LIB.BASEBOARD_FAB2(SCH_1):PAGE221_I2@MSTR_DISCRETE.CAP(CHIPS)':
 'A': CDS_PINID='A';
NODE_NAME     R4G23 2
 '@BASEBOARD_FAB2_LIB.BASEBOARD_FAB2(SCH_1):PAGE221_I4@MSTR_DISCRETE.RES(CHIPS)':
 'B': CDS_PINID='B';
NODE_NAME     R6U15 2
 '@BASEBOARD_FAB2_LIB.BASEBOARD_FAB2(SCH_1):PAGE221_I5@MSTR_DISCRETE.RES(CHIPS)':
 'B': CDS_PINID='B';
NODE_NAME     EU4G3 7
 '@BASEBOARD_FAB2_LIB.BASEBOARD_FAB2(SCH_1):PAGE221_I15@MSTR_VREG.MIC5166(CHIPS)':
 'EN': CDS_PINID='EN';
NET_NAME
'FM_PVTT_DEF_EN_R'
 '@BASEBOARD_FAB2_LIB.BASEBOARD_FAB2(SCH_1):FM_PVTT_DEF_EN_R':
 C_SIGNAL='@baseboard_fab2_lib.baseboard_fab2(sch_1):fm_pvtt_def_en_r';
NODE_NAME     C4A2 1
 '@BASEBOARD_FAB2_LIB.BASEBOARD_FAB2(SCH_1):PAGE222_I2@MSTR_DISCRETE.CAP(CHIPS)':
 'A': CDS_PINID='A';
NODE_NAME     R4A2 2
 '@BASEBOARD_FAB2_LIB.BASEBOARD_FAB2(SCH_1):PAGE222_I4@MSTR_DISCRETE.RES(CHIPS)':
 'B': CDS_PINID='B';
NODE_NAME     R6L4 2
 '@BASEBOARD_FAB2_LIB.BASEBOARD_FAB2(SCH_1):PAGE222_I5@MSTR_DISCRETE.RES(CHIPS)':
 'B': CDS_PINID='B';
NODE_NAME     EU4A1 7
 '@BASEBOARD_FAB2_LIB.BASEBOARD_FAB2(SCH_1):PAGE222_I13@MSTR_VREG.MIC5166(CHIPS)':
 'EN': CDS_PINID='EN';
NET_NAME
'FM_PVTT_GHJ_EN_R'
 '@BASEBOARD_FAB2_LIB.BASEBOARD_FAB2(SCH_1):FM_PVTT_GHJ_EN_R':
 C_SIGNAL='@baseboard_fab2_lib.baseboard_fab2(sch_1):fm_pvtt_ghj_en_r';
NODE_NAME     C4G12 1
 '@BASEBOARD_FAB2_LIB.BASEBOARD_FAB2(SCH_1):PAGE229_I2@MSTR_DISCRETE.CAP(CHIPS)':
 'A': CDS_PINID='A';
NODE_NAME     R4G16 2
 '@BASEBOARD_FAB2_LIB.BASEBOARD_FAB2(SCH_1):PAGE229_I4@MSTR_DISCRETE.RES(CHIPS)':
 'B': CDS_PINID='B';
NODE_NAME     R6U3 2
 '@BASEBOARD_FAB2_LIB.BASEBOARD_FAB2(SCH_1):PAGE229_I5@MSTR_DISCRETE.RES(CHIPS)':
 'B': CDS_PINID='B';
NODE_NAME     EU4G2 7
 '@BASEBOARD_FAB2_LIB.BASEBOARD_FAB2(SCH_1):PAGE229_I37@MSTR_VREG.MIC5166(CHIPS)':
 'EN': CDS_PINID='EN';
NET_NAME
'FM_PVTT_KLM_EN_R'
 '@BASEBOARD_FAB2_LIB.BASEBOARD_FAB2(SCH_1):FM_PVTT_KLM_EN_R':
 C_SIGNAL='@baseboard_fab2_lib.baseboard_fab2(sch_1):fm_pvtt_klm_en_r';
NODE_NAME     C4A6 1
 '@BASEBOARD_FAB2_LIB.BASEBOARD_FAB2(SCH_1):PAGE230_I2@MSTR_DISCRETE.CAP(CHIPS)':
 'A': CDS_PINID='A';
NODE_NAME     R4A3 2
 '@BASEBOARD_FAB2_LIB.BASEBOARD_FAB2(SCH_1):PAGE230_I4@MSTR_DISCRETE.RES(CHIPS)':
 'B': CDS_PINID='B';
NODE_NAME     R6L5 2
 '@BASEBOARD_FAB2_LIB.BASEBOARD_FAB2(SCH_1):PAGE230_I5@MSTR_DISCRETE.RES(CHIPS)':
 'B': CDS_PINID='B';
NODE_NAME     EU4A2 7
 '@BASEBOARD_FAB2_LIB.BASEBOARD_FAB2(SCH_1):PAGE230_I37@MSTR_VREG.MIC5166(CHIPS)':
 'EN': CDS_PINID='EN';
NET_NAME
'FM_PWRBRK_N'
 '@BASEBOARD_FAB2_LIB.BASEBOARD_FAB2(SCH_1):FM_PWRBRK_N':
 C_SIGNAL='@baseboard_fab2_lib.baseboard_fab2(sch_1):fm_pwrbrk_n';
NODE_NAME     R7E22 1
 '@BASEBOARD_FAB2_LIB.BASEBOARD_FAB2(SCH_1):PAGE108_I341@MSTR_DISCRETE.RES(CHIPS)':
 'A': CDS_PINID='A';
NODE_NAME     R7E21 2
 '@BASEBOARD_FAB2_LIB.BASEBOARD_FAB2(SCH_1):PAGE108_I343@MSTR_DISCRETE.RES(CHIPS)':
 'B': CDS_PINID='B';
NODE_NAME     U25W4 T4
 '@BASEBOARD_FAB2_LIB.BASEBOARD_FAB2(SCH_1):PAGE147_I106@W_HDL.AST2520A1-GP-GP(CHIPS)':
 'GPION7_PWM7_VPIG7': CDS_PINID='GPION7_PWM7_VPIG7';
NODE_NAME     Q7E8 3
 '@BASEBOARD_FAB2_LIB.BASEBOARD_FAB2(SCH_1):PAGE95_I123@MSTR_DISCRETE.FET_N(CHIPS)':
 'DRN': CDS_PINID='DRN';
NET_NAME
'FM_PWRBRK_SLOT_N'
 '@BASEBOARD_FAB2_LIB.BASEBOARD_FAB2(SCH_1):FM_PWRBRK_SLOT_N':
 C_SIGNAL='@baseboard_fab2_lib.baseboard_fab2(sch_1):fm_pwrbrk_slot_n';
NODE_NAME     J8G1 20
 '@BASEBOARD_FAB2_LIB.BASEBOARD_FAB2(SCH_1):PAGE108_I258@MSTR_SCONN.SCONN200_H68296001(CHIPS)':
 'IO20': CDS_PINID='IO20';
NODE_NAME     R7E22 2
 '@BASEBOARD_FAB2_LIB.BASEBOARD_FAB2(SCH_1):PAGE108_I341@MSTR_DISCRETE.RES(CHIPS)':
 'B': CDS_PINID='B';
NODE_NAME     R2U50 2
 '@BASEBOARD_FAB2_LIB.BASEBOARD_FAB2(SCH_1):PAGE119_I228@MSTR_DISCRETE.RES(CHIPS)':
 'B': CDS_PINID='B';
NET_NAME
'FM_PWR_BTN_N'
 '@BASEBOARD_FAB2_LIB.BASEBOARD_FAB2(SCH_1):FM_PWR_BTN_N':
 C_SIGNAL='@baseboard_fab2_lib.baseboard_fab2(sch_1):fm_pwr_btn_n';
NODE_NAME     U7C1 BH20
 '@BASEBOARD_FAB2_LIB.BASEBOARD_FAB2(SCH_1):PAGE119_I115@MSTR_U_PROC.LBG_CORE_QAT_EXT_D(CHIPS)':
 'GPP_B9_SRCCLKREQ4_N': CDS_PINID='GPP_B9_SRCCLKREQ4_N';
NODE_NAME     R1L26 2
 '@BASEBOARD_FAB2_LIB.BASEBOARD_FAB2(SCH_1):PAGE175_I13@MSTR_DISCRETE.RES(CHIPS)':
 'B': CDS_PINID='B';
NODE_NAME     R25W144 2
 '@BASEBOARD_FAB2_LIB.BASEBOARD_FAB2(SCH_1):PAGE145_I173@MSTR_DISCRETE.RES(CHIPS)':
 'B': CDS_PINID='B';
NODE_NAME     R1W27 1
 '@BASEBOARD_FAB2_LIB.BASEBOARD_FAB2(SCH_1):PAGE190_I351@MSTR_DISCRETE.RES(CHIPS)':
 'A': CDS_PINID='A';
NET_NAME
'FM_PWR_BTN_R1_N'
 '@BASEBOARD_FAB2_LIB.BASEBOARD_FAB2(SCH_1):FM_PWR_BTN_R1_N':
 C_SIGNAL='@baseboard_fab2_lib.baseboard_fab2(sch_1):fm_pwr_btn_r1_n';
NODE_NAME     U25W4 F18
 '@BASEBOARD_FAB2_LIB.BASEBOARD_FAB2(SCH_1):PAGE145_I117@W_HDL.AST2520A1-GP-GP(CHIPS)':
 'GPIOE2_NDSR3': CDS_PINID='GPIOE2_NDSR3';
NODE_NAME     R25W144 1
 '@BASEBOARD_FAB2_LIB.BASEBOARD_FAB2(SCH_1):PAGE145_I173@MSTR_DISCRETE.RES(CHIPS)':
 'A': CDS_PINID='A';
NET_NAME
'FM_PWR_BTN_R2_N'
 '@BASEBOARD_FAB2_LIB.BASEBOARD_FAB2(SCH_1):FM_PWR_BTN_R2_N':
 C_SIGNAL='@baseboard_fab2_lib.baseboard_fab2(sch_1):fm_pwr_btn_r2_n';
NODE_NAME     U8D7 G6
 '@BASEBOARD_FAB2_LIB.BASEBOARD_FAB2(SCH_1):PAGE190_I179@MSTR_MEMORY.LCMXO2_A(CHIPS)':
 'PL3D': CDS_PINID='PL3D';
NODE_NAME     R1W27 2
 '@BASEBOARD_FAB2_LIB.BASEBOARD_FAB2(SCH_1):PAGE190_I351@MSTR_DISCRETE.RES(CHIPS)':
 'B': CDS_PINID='B';
NET_NAME
'FM_PWR_BTN_R_N'
 '@BASEBOARD_FAB2_LIB.BASEBOARD_FAB2(SCH_1):FM_PWR_BTN_R_N':
 C_SIGNAL='@baseboard_fab2_lib.baseboard_fab2(sch_1):fm_pwr_btn_r_n';
NODE_NAME     R1L26 1
 '@BASEBOARD_FAB2_LIB.BASEBOARD_FAB2(SCH_1):PAGE175_I13@MSTR_DISCRETE.RES(CHIPS)':
 'A': CDS_PINID='A';
NODE_NAME     U9A4 4
 '@BASEBOARD_FAB2_LIB.BASEBOARD_FAB2(SCH_1):PAGE175_I97@W_HDL.TC7PZ14FU-GP(CHIPS)':
 '2Y': CDS_PINID='\2y\';
NET_NAME
'FM_PWR_LED'
 '@BASEBOARD_FAB2_LIB.BASEBOARD_FAB2(SCH_1):FM_PWR_LED':
 C_SIGNAL='@baseboard_fab2_lib.baseboard_fab2(sch_1):fm_pwr_led';
NODE_NAME     Q9A2 6
 '@BASEBOARD_FAB2_LIB.BASEBOARD_FAB2(SCH_1):PAGE119_I175@MSTR_DISCRETE.FET_N_DUAL(CHIPS)':
 'DRAIN'<0>: CDS_PINID='DRAIN(0)';
NODE_NAME     Q9A2 5
 '@BASEBOARD_FAB2_LIB.BASEBOARD_FAB2(SCH_1):PAGE119_I180@MSTR_DISCRETE.FET_N_DUAL(CHIPS)':
 'GATE'<0>: CDS_PINID='GATE(0)';
NODE_NAME     R9A18 2
 '@BASEBOARD_FAB2_LIB.BASEBOARD_FAB2(SCH_1):PAGE119_I183@MSTR_DISCRETE.RES(CHIPS)':
 'B': CDS_PINID='B';
NET_NAME
'FM_PWR_LED_A'
 '@BASEBOARD_FAB2_LIB.BASEBOARD_FAB2(SCH_1):FM_PWR_LED_A':
 C_SIGNAL='@baseboard_fab2_lib.baseboard_fab2(sch_1):fm_pwr_led_a';
NODE_NAME     R9A20 1
 '@BASEBOARD_FAB2_LIB.BASEBOARD_FAB2(SCH_1):PAGE119_I178@MSTR_DISCRETE.RES(CHIPS)':
 'A': CDS_PINID='A';
NODE_NAME     DS9A5 1
 '@BASEBOARD_FAB2_LIB.BASEBOARD_FAB2(SCH_1):PAGE119_I179@MSTR_DISCRETE.LED(CHIPS)':
 'A': CDS_PINID='A';
NET_NAME
'FM_PWR_LED_K'
 '@BASEBOARD_FAB2_LIB.BASEBOARD_FAB2(SCH_1):FM_PWR_LED_K':
 C_SIGNAL='@baseboard_fab2_lib.baseboard_fab2(sch_1):fm_pwr_led_k';
NODE_NAME     DS9A5 2
 '@BASEBOARD_FAB2_LIB.BASEBOARD_FAB2(SCH_1):PAGE119_I179@MSTR_DISCRETE.LED(CHIPS)':
 'C': CDS_PINID='C';
NODE_NAME     Q9A2 3
 '@BASEBOARD_FAB2_LIB.BASEBOARD_FAB2(SCH_1):PAGE119_I180@MSTR_DISCRETE.FET_N_DUAL(CHIPS)':
 'DRAIN'<0>: CDS_PINID='DRAIN(0)';
NET_NAME
'FM_PWR_LED_N'
 '@BASEBOARD_FAB2_LIB.BASEBOARD_FAB2(SCH_1):FM_PWR_LED_N':
 C_SIGNAL='@baseboard_fab2_lib.baseboard_fab2(sch_1):fm_pwr_led_n';
NODE_NAME     U7C1 BK46
 '@BASEBOARD_FAB2_LIB.BASEBOARD_FAB2(SCH_1):PAGE119_I115@MSTR_U_PROC.LBG_CORE_QAT_EXT_D(CHIPS)':
 'GPP_D1': CDS_PINID='GPP_D1';
NODE_NAME     Q9A2 2
 '@BASEBOARD_FAB2_LIB.BASEBOARD_FAB2(SCH_1):PAGE119_I175@MSTR_DISCRETE.FET_N_DUAL(CHIPS)':
 'GATE'<0>: CDS_PINID='GATE(0)';
NODE_NAME     R9A21 2
 '@BASEBOARD_FAB2_LIB.BASEBOARD_FAB2(SCH_1):PAGE119_I186@MSTR_DISCRETE.RES(CHIPS)':
 'B': CDS_PINID='B';
NET_NAME
'FM_QAT_EN_N'
 '@BASEBOARD_FAB2_LIB.BASEBOARD_FAB2(SCH_1):FM_QAT_EN_N':
 C_SIGNAL='@baseboard_fab2_lib.baseboard_fab2(sch_1):fm_qat_en_n';
NODE_NAME     U7C1 BR9
 '@BASEBOARD_FAB2_LIB.BASEBOARD_FAB2(SCH_1):PAGE119_I115@MSTR_U_PROC.LBG_CORE_QAT_EXT_D(CHIPS)':
 'GPP_B3_CPU_GP2': CDS_PINID='GPP_B3_CPU_GP2';
NODE_NAME     R2N23 2
 '@BASEBOARD_FAB2_LIB.BASEBOARD_FAB2(SCH_1):PAGE135_I112@MSTR_DISCRETE.RES(CHIPS)':
 'B': CDS_PINID='B';
NODE_NAME     R2N24 1
 '@BASEBOARD_FAB2_LIB.BASEBOARD_FAB2(SCH_1):PAGE135_I113@MSTR_DISCRETE.RES(CHIPS)':
 'A': CDS_PINID='A';
NET_NAME
'FM_RED_LED_ANODE'
 '@BASEBOARD_FAB2_LIB.BASEBOARD_FAB2(SCH_1):FM_RED_LED_ANODE':
 C_SIGNAL='@baseboard_fab2_lib.baseboard_fab2(sch_1):fm_red_led_anode';
NODE_NAME     DS9F1 1
 '@BASEBOARD_FAB2_LIB.BASEBOARD_FAB2(SCH_1):PAGE177_I71@MSTR_DISCRETE.LED(CHIPS)':
 'A': CDS_PINID='A';
NODE_NAME     R9F28 2
 '@BASEBOARD_FAB2_LIB.BASEBOARD_FAB2(SCH_1):PAGE177_I72@MSTR_DISCRETE.RES(CHIPS)':
 'B': CDS_PINID='B';
NET_NAME
'FM_RED_LED_CATHODE'
 '@BASEBOARD_FAB2_LIB.BASEBOARD_FAB2(SCH_1):FM_RED_LED_CATHODE':
 C_SIGNAL='@baseboard_fab2_lib.baseboard_fab2(sch_1):fm_red_led_cathode';
NODE_NAME     DS9F1 2
 '@BASEBOARD_FAB2_LIB.BASEBOARD_FAB2(SCH_1):PAGE177_I71@MSTR_DISCRETE.LED(CHIPS)':
 'C': CDS_PINID='C';
NODE_NAME     Q9F1 3
 '@BASEBOARD_FAB2_LIB.BASEBOARD_FAB2(SCH_1):PAGE177_I79@MSTR_DISCRETE.FET_N_DUAL(CHIPS)':
 'DRAIN'<0>: CDS_PINID='DRAIN(0)';
NET_NAME
'FM_SINT_PRSNT_N'
 '@BASEBOARD_FAB2_LIB.BASEBOARD_FAB2(SCH_1):FM_SINT_PRSNT_N':
 C_SIGNAL='@baseboard_fab2_lib.baseboard_fab2(sch_1):fm_sint_prsnt_n';
NODE_NAME     U7C1 C18
 '@BASEBOARD_FAB2_LIB.BASEBOARD_FAB2(SCH_1):PAGE121_I34@MSTR_U_PROC.LBG_CORE_QAT_EXT_D(CHIPS)':
 'RSVD'<11>: CDS_PINID='RSVD(11)';
NODE_NAME     R7C5 2
 '@BASEBOARD_FAB2_LIB.BASEBOARD_FAB2(SCH_1):PAGE133_I297@MSTR_DISCRETE.RES(CHIPS)':
 'B': CDS_PINID='B';
NODE_NAME     U8D7 B14
 '@BASEBOARD_FAB2_LIB.BASEBOARD_FAB2(SCH_1):PAGE191_I59@MSTR_MEMORY.LCMXO2_A(CHIPS)':
 'PT24A': CDS_PINID='PT24A';
NET_NAME
'FM_SLPS3_N'
 '@BASEBOARD_FAB2_LIB.BASEBOARD_FAB2(SCH_1):FM_SLPS3_N':
 C_SIGNAL='@baseboard_fab2_lib.baseboard_fab2(sch_1):fm_slps3_n';
NODE_NAME     U8D7 G1
 '@BASEBOARD_FAB2_LIB.BASEBOARD_FAB2(SCH_1):PAGE190_I179@MSTR_MEMORY.LCMXO2_A(CHIPS)':
 'PL6A': CDS_PINID='PL6A';
NODE_NAME     U25W4 R22
 '@BASEBOARD_FAB2_LIB.BASEBOARD_FAB2(SCH_1):PAGE148_I28@W_HDL.AST2520A1-GP-GP(CHIPS)':
 'GPIOY0_SIOS3#': CDS_PINID='\gpioy0_sios3#\';
NODE_NAME     U6W1 19
 '@BASEBOARD_FAB2_LIB.BASEBOARD_FAB2(SCH_1):PAGE247_I120@W_HDL.TCA9555PWR-GP(CHIPS)':
 'P16': CDS_PINID='P16';
NODE_NAME     R7W1 1
 '@BASEBOARD_FAB2_LIB.BASEBOARD_FAB2(SCH_1):PAGE118_I167@MSTR_DISCRETE.RES(CHIPS)':
 'A': CDS_PINID='A';
NET_NAME
'FM_SLPS3_R_N'
 '@BASEBOARD_FAB2_LIB.BASEBOARD_FAB2(SCH_1):FM_SLPS3_R_N':
 C_SIGNAL='@baseboard_fab2_lib.baseboard_fab2(sch_1):fm_slps3_r_n';
NODE_NAME     U7C1 D14
 '@BASEBOARD_FAB2_LIB.BASEBOARD_FAB2(SCH_1):PAGE118_I73@MSTR_U_PROC.LBG_CORE_QAT_EXT_D(CHIPS)':
 'GPD4_SLP_S3_N': CDS_PINID='GPD4_SLP_S3_N';
NODE_NAME     R7W1 2
 '@BASEBOARD_FAB2_LIB.BASEBOARD_FAB2(SCH_1):PAGE118_I167@MSTR_DISCRETE.RES(CHIPS)':
 'B': CDS_PINID='B';
NET_NAME
'FM_SLPS4_N'
 '@BASEBOARD_FAB2_LIB.BASEBOARD_FAB2(SCH_1):FM_SLPS4_N':
 C_SIGNAL='@baseboard_fab2_lib.baseboard_fab2(sch_1):fm_slps4_n';
NODE_NAME     U7C1 B16
 '@BASEBOARD_FAB2_LIB.BASEBOARD_FAB2(SCH_1):PAGE118_I73@MSTR_U_PROC.LBG_CORE_QAT_EXT_D(CHIPS)':
 'GPD5_SLP_S4_N': CDS_PINID='GPD5_SLP_S4_N';
NODE_NAME     U8D7 C12
 '@BASEBOARD_FAB2_LIB.BASEBOARD_FAB2(SCH_1):PAGE191_I59@MSTR_MEMORY.LCMXO2_A(CHIPS)':
 'PT23A': CDS_PINID='PT23A';
NODE_NAME     U25W4 R21
 '@BASEBOARD_FAB2_LIB.BASEBOARD_FAB2(SCH_1):PAGE148_I28@W_HDL.AST2520A1-GP-GP(CHIPS)':
 'GPIOY1_SIOS5#': CDS_PINID='\gpioy1_sios5#\';
NET_NAME
'FM_SLP_SUS_N'
 '@BASEBOARD_FAB2_LIB.BASEBOARD_FAB2(SCH_1):FM_SLP_SUS_N':
 C_SIGNAL='@baseboard_fab2_lib.baseboard_fab2(sch_1):fm_slp_sus_n';
NODE_NAME     U7C1 P7
 '@BASEBOARD_FAB2_LIB.BASEBOARD_FAB2(SCH_1):PAGE118_I73@MSTR_U_PROC.LBG_CORE_QAT_EXT_D(CHIPS)':
 'SLP_SUS_N': CDS_PINID='SLP_SUS_N';
NODE_NAME     U8D7 E9
 '@BASEBOARD_FAB2_LIB.BASEBOARD_FAB2(SCH_1):PAGE191_I59@MSTR_MEMORY.LCMXO2_A(CHIPS)':
 'PT17D': CDS_PINID='PT17D';
NET_NAME
'FM_SLT_CFG0'
 '@BASEBOARD_FAB2_LIB.BASEBOARD_FAB2(SCH_1):FM_SLT_CFG0':
 C_SIGNAL='@baseboard_fab2_lib.baseboard_fab2(sch_1):fm_slt_cfg0';
NODE_NAME     J8G1 19
 '@BASEBOARD_FAB2_LIB.BASEBOARD_FAB2(SCH_1):PAGE108_I258@MSTR_SCONN.SCONN200_H68296001(CHIPS)':
 'IO19': CDS_PINID='IO19';
NODE_NAME     U7C1 CA32
 '@BASEBOARD_FAB2_LIB.BASEBOARD_FAB2(SCH_1):PAGE119_I115@MSTR_U_PROC.LBG_CORE_QAT_EXT_D(CHIPS)':
 'GPP_C15': CDS_PINID='GPP_C15';
NODE_NAME     R8C7 2
 '@BASEBOARD_FAB2_LIB.BASEBOARD_FAB2(SCH_1):PAGE133_I327@MSTR_DISCRETE.RES(CHIPS)':
 'B': CDS_PINID='B';
NODE_NAME     U25W4 D8
 '@BASEBOARD_FAB2_LIB.BASEBOARD_FAB2(SCH_1):PAGE147_I106@W_HDL.AST2520A1-GP-GP(CHIPS)':
 'GPIOR6_MDC1': CDS_PINID='GPIOR6_MDC1';
NET_NAME
'FM_SLT_CFG1'
 '@BASEBOARD_FAB2_LIB.BASEBOARD_FAB2(SCH_1):FM_SLT_CFG1':
 C_SIGNAL='@baseboard_fab2_lib.baseboard_fab2(sch_1):fm_slt_cfg1';
NODE_NAME     J8G1 18
 '@BASEBOARD_FAB2_LIB.BASEBOARD_FAB2(SCH_1):PAGE108_I258@MSTR_SCONN.SCONN200_H68296001(CHIPS)':
 'IO18': CDS_PINID='IO18';
NODE_NAME     U7C1 BW37
 '@BASEBOARD_FAB2_LIB.BASEBOARD_FAB2(SCH_1):PAGE119_I115@MSTR_U_PROC.LBG_CORE_QAT_EXT_D(CHIPS)':
 'GPP_C16': CDS_PINID='GPP_C16';
NODE_NAME     R8C1 2
 '@BASEBOARD_FAB2_LIB.BASEBOARD_FAB2(SCH_1):PAGE133_I326@MSTR_DISCRETE.RES(CHIPS)':
 'B': CDS_PINID='B';
NODE_NAME     U25W4 E10
 '@BASEBOARD_FAB2_LIB.BASEBOARD_FAB2(SCH_1):PAGE147_I106@W_HDL.AST2520A1-GP-GP(CHIPS)':
 'GPIOR7_MDIO1': CDS_PINID='GPIOR7_MDIO1';
NET_NAME
'FM_SLT_CFG2_R'
 '@BASEBOARD_FAB2_LIB.BASEBOARD_FAB2(SCH_1):FM_SLT_CFG2_R':
 C_SIGNAL='@baseboard_fab2_lib.baseboard_fab2(sch_1):fm_slt_cfg2_r';
NODE_NAME     U7C1 BY31
 '@BASEBOARD_FAB2_LIB.BASEBOARD_FAB2(SCH_1):PAGE119_I115@MSTR_U_PROC.LBG_CORE_QAT_EXT_D(CHIPS)':
 'GPP_C17': CDS_PINID='GPP_C17';
NODE_NAME     R2U48 2
 '@BASEBOARD_FAB2_LIB.BASEBOARD_FAB2(SCH_1):PAGE119_I213@MSTR_DISCRETE.RES(CHIPS)':
 'B': CDS_PINID='B';
NODE_NAME     R2U50 1
 '@BASEBOARD_FAB2_LIB.BASEBOARD_FAB2(SCH_1):PAGE119_I228@MSTR_DISCRETE.RES(CHIPS)':
 'A': CDS_PINID='A';
NET_NAME
'FM_SOL_UART_CH_SEL'
 '@BASEBOARD_FAB2_LIB.BASEBOARD_FAB2(SCH_1):FM_SOL_UART_CH_SEL':
 C_SIGNAL='@baseboard_fab2_lib.baseboard_fab2(sch_1):fm_sol_uart_ch_sel';
NODE_NAME     U7C1 BG7
 '@BASEBOARD_FAB2_LIB.BASEBOARD_FAB2(SCH_1):PAGE120_I147@MSTR_U_PROC.LBG_CORE_QAT_EXT_D(CHIPS)':
 'GPP_G21_SSATA_DEVSLP1': CDS_PINID='GPP_G21_SSATA_DEVSLP1';
NODE_NAME     U8D7 L10
 '@BASEBOARD_FAB2_LIB.BASEBOARD_FAB2(SCH_1):PAGE190_I179@MSTR_MEMORY.LCMXO2_A(CHIPS)':
 'PB18D': CDS_PINID='PB18D';
NODE_NAME     U25W4 F20
 '@BASEBOARD_FAB2_LIB.BASEBOARD_FAB2(SCH_1):PAGE145_I117@W_HDL.AST2520A1-GP-GP(CHIPS)':
 'GPIOD2_SD2DAT0': CDS_PINID='GPIOD2_SD2DAT0';
NODE_NAME     R6W16 2
 '@BASEBOARD_FAB2_LIB.BASEBOARD_FAB2(SCH_1):PAGE168_I46@MSTR_DISCRETE.RES(CHIPS)':
 'B': CDS_PINID='B';
NODE_NAME     Q6W2 3
 '@BASEBOARD_FAB2_LIB.BASEBOARD_FAB2(SCH_1):PAGE168_I47@MSTR_DISCRETE.NPN(CHIPS)':
 'C': CDS_PINID='C';
NET_NAME
'FM_SPEAKER_PCH_N'
 '@BASEBOARD_FAB2_LIB.BASEBOARD_FAB2(SCH_1):FM_SPEAKER_PCH_N':
 C_SIGNAL='@baseboard_fab2_lib.baseboard_fab2(sch_1):fm_speaker_pch_n';
NODE_NAME     Q9A3 3
 '@BASEBOARD_FAB2_LIB.BASEBOARD_FAB2(SCH_1):PAGE175_I49@MSTR_DISCRETE.FET_N(CHIPS)':
 'DRN': CDS_PINID='DRN';
NODE_NAME     DS9A3 1
 '@BASEBOARD_FAB2_LIB.BASEBOARD_FAB2(SCH_1):PAGE175_I67@MSTR_DISCRETE.LED(CHIPS)':
 'C': CDS_PINID='C';
NET_NAME
'FM_SSATA_PCIE_M2_SEL'
 '@BASEBOARD_FAB2_LIB.BASEBOARD_FAB2(SCH_1):FM_SSATA_PCIE_M2_SEL':
 C_SIGNAL='@baseboard_fab2_lib.baseboard_fab2(sch_1):fm_ssata_pcie_m2_sel';
NODE_NAME     U7C1 BH4
 '@BASEBOARD_FAB2_LIB.BASEBOARD_FAB2(SCH_1):PAGE120_I147@MSTR_U_PROC.LBG_CORE_QAT_EXT_D(CHIPS)':
 'GPP_H23_SSATAXPCIE5_SSATAGP5': CDS_PINID='GPP_H23_SSATAXPCIE5_SSATAGP5';
NODE_NAME     R2P14 2
 '@BASEBOARD_FAB2_LIB.BASEBOARD_FAB2(SCH_1):PAGE185_I115@MSTR_DISCRETE.RES(CHIPS)':
 'B': CDS_PINID='B';
NET_NAME
'FM_SYS_THROTTLE_LVC3'
 '@BASEBOARD_FAB2_LIB.BASEBOARD_FAB2(SCH_1):FM_SYS_THROTTLE_LVC3':
 C_SIGNAL='@baseboard_fab2_lib.baseboard_fab2(sch_1):fm_sys_throttle_lvc3';
NODE_NAME     Q2U1 2
 '@BASEBOARD_FAB2_LIB.BASEBOARD_FAB2(SCH_1):PAGE95_I28@MSTR_DISCRETE.FET_N_DUAL(CHIPS)':
 'GATE'<0>: CDS_PINID='GATE(0)';
NODE_NAME     Q4B2 2
 '@BASEBOARD_FAB2_LIB.BASEBOARD_FAB2(SCH_1):PAGE95_I32@MSTR_DISCRETE.FET_N_DUAL(CHIPS)':
 'GATE'<0>: CDS_PINID='GATE(0)';
NODE_NAME     Q4B2 5
 '@BASEBOARD_FAB2_LIB.BASEBOARD_FAB2(SCH_1):PAGE95_I33@MSTR_DISCRETE.FET_N_DUAL(CHIPS)':
 'GATE'<0>: CDS_PINID='GATE(0)';
NODE_NAME     Q7E3 5
 '@BASEBOARD_FAB2_LIB.BASEBOARD_FAB2(SCH_1):PAGE95_I51@MSTR_DISCRETE.FET_N_DUAL(CHIPS)':
 'GATE'<0>: CDS_PINID='GATE(0)';
NODE_NAME     Q7E3 2
 '@BASEBOARD_FAB2_LIB.BASEBOARD_FAB2(SCH_1):PAGE95_I52@MSTR_DISCRETE.FET_N_DUAL(CHIPS)':
 'GATE'<0>: CDS_PINID='GATE(0)';
NODE_NAME     R7E7 2
 '@BASEBOARD_FAB2_LIB.BASEBOARD_FAB2(SCH_1):PAGE95_I106@MSTR_DISCRETE.RES(CHIPS)':
 'B': CDS_PINID='B';
NODE_NAME     Q2U1 5
 '@BASEBOARD_FAB2_LIB.BASEBOARD_FAB2(SCH_1):PAGE95_I113@MSTR_DISCRETE.FET_N_DUAL(CHIPS)':
 'GATE'<0>: CDS_PINID='GATE(0)';
NODE_NAME     Q7E4 3
 '@BASEBOARD_FAB2_LIB.BASEBOARD_FAB2(SCH_1):PAGE95_I122@MSTR_DISCRETE.FET_N(CHIPS)':
 'DRN': CDS_PINID='DRN';
NODE_NAME     Q7E8 1
 '@BASEBOARD_FAB2_LIB.BASEBOARD_FAB2(SCH_1):PAGE95_I123@MSTR_DISCRETE.FET_N(CHIPS)':
 'GATE': CDS_PINID='GATE';
NET_NAME
'FM_THERMTRIP_DLY'
 '@BASEBOARD_FAB2_LIB.BASEBOARD_FAB2(SCH_1):FM_THERMTRIP_DLY':
 C_SIGNAL='@baseboard_fab2_lib.baseboard_fab2(sch_1):fm_thermtrip_dly';
NODE_NAME     R7D18 1
 '@BASEBOARD_FAB2_LIB.BASEBOARD_FAB2(SCH_1):PAGE134_I11@MSTR_DISCRETE.RES(CHIPS)':
 'A': CDS_PINID='A';
NODE_NAME     U8D7 L15
 '@BASEBOARD_FAB2_LIB.BASEBOARD_FAB2(SCH_1):PAGE191_I59@MSTR_MEMORY.LCMXO2_A(CHIPS)':
 'PR12A': CDS_PINID='PR12A';
NET_NAME
'FM_THERMTRIP_DLY_R'
 '@BASEBOARD_FAB2_LIB.BASEBOARD_FAB2(SCH_1):FM_THERMTRIP_DLY_R':
 C_SIGNAL='@baseboard_fab2_lib.baseboard_fab2(sch_1):fm_thermtrip_dly_r';
NODE_NAME     R7D18 2
 '@BASEBOARD_FAB2_LIB.BASEBOARD_FAB2(SCH_1):PAGE134_I11@MSTR_DISCRETE.RES(CHIPS)':
 'B': CDS_PINID='B';
NODE_NAME     Q7D1 1
 '@BASEBOARD_FAB2_LIB.BASEBOARD_FAB2(SCH_1):PAGE134_I14@MSTR_DISCRETE.FET_N(CHIPS)':
 'GATE': CDS_PINID='GATE';
NET_NAME
'FM_THROTTLE_N'
 '@BASEBOARD_FAB2_LIB.BASEBOARD_FAB2(SCH_1):FM_THROTTLE_N':
 C_SIGNAL='@baseboard_fab2_lib.baseboard_fab2(sch_1):fm_throttle_n';
NODE_NAME     R7E9 1
 '@BASEBOARD_FAB2_LIB.BASEBOARD_FAB2(SCH_1):PAGE95_I108@MSTR_DISCRETE.RES(CHIPS)':
 'A': CDS_PINID='A';
NODE_NAME     R8B31 2
 '@BASEBOARD_FAB2_LIB.BASEBOARD_FAB2(SCH_1):PAGE133_I307@MSTR_DISCRETE.RES(CHIPS)':
 'B': CDS_PINID='B';
NODE_NAME     R1R8 2
 '@BASEBOARD_FAB2_LIB.BASEBOARD_FAB2(SCH_1):PAGE170_I51@MSTR_DISCRETE.RES(CHIPS)':
 'B': CDS_PINID='B';
NODE_NAME     U25W4 V20
 '@BASEBOARD_FAB2_LIB.BASEBOARD_FAB2(SCH_1):PAGE146_I104@W_HDL.AST2520A1-GP-GP(CHIPS)':
 'GPIOS0_VPOB2_SPI2CS1#': CDS_PINID='\gpios0_vpob2_spi2cs1#\';
NODE_NAME     R7W17 2
 '@BASEBOARD_FAB2_LIB.BASEBOARD_FAB2(SCH_1):PAGE119_I229@MSTR_DISCRETE.RES(CHIPS)':
 'B': CDS_PINID='B';
NET_NAME
'FM_THROTTLE_R1_N'
 '@BASEBOARD_FAB2_LIB.BASEBOARD_FAB2(SCH_1):FM_THROTTLE_R1_N':
 C_SIGNAL='@baseboard_fab2_lib.baseboard_fab2(sch_1):fm_throttle_r1_n';
NODE_NAME     U1R1 4
 '@BASEBOARD_FAB2_LIB.BASEBOARD_FAB2(SCH_1):PAGE170_I46@MSTR_TTL.TTL1G07_A(CHIPS)':
 'Y': CDS_PINID='Y';
NODE_NAME     R1R8 1
 '@BASEBOARD_FAB2_LIB.BASEBOARD_FAB2(SCH_1):PAGE170_I51@MSTR_DISCRETE.RES(CHIPS)':
 'A': CDS_PINID='A';
NET_NAME
'FM_THROTTLE_R2_N'
 '@BASEBOARD_FAB2_LIB.BASEBOARD_FAB2(SCH_1):FM_THROTTLE_R2_N':
 C_SIGNAL='@baseboard_fab2_lib.baseboard_fab2(sch_1):fm_throttle_r2_n';
NODE_NAME     U7C1 CA39
 '@BASEBOARD_FAB2_LIB.BASEBOARD_FAB2(SCH_1):PAGE119_I115@MSTR_U_PROC.LBG_CORE_QAT_EXT_D(CHIPS)':
 'GPP_C20': CDS_PINID='GPP_C20';
NODE_NAME     R7W17 1
 '@BASEBOARD_FAB2_LIB.BASEBOARD_FAB2(SCH_1):PAGE119_I229@MSTR_DISCRETE.RES(CHIPS)':
 'A': CDS_PINID='A';
NET_NAME
'FM_THROTTLE_R_N'
 '@BASEBOARD_FAB2_LIB.BASEBOARD_FAB2(SCH_1):FM_THROTTLE_R_N':
 C_SIGNAL='@baseboard_fab2_lib.baseboard_fab2(sch_1):fm_throttle_r_n';
NODE_NAME     R7E9 2
 '@BASEBOARD_FAB2_LIB.BASEBOARD_FAB2(SCH_1):PAGE95_I108@MSTR_DISCRETE.RES(CHIPS)':
 'B': CDS_PINID='B';
NODE_NAME     Q7E4 1
 '@BASEBOARD_FAB2_LIB.BASEBOARD_FAB2(SCH_1):PAGE95_I122@MSTR_DISCRETE.FET_N(CHIPS)':
 'GATE': CDS_PINID='GATE';
NET_NAME
'FM_TPM_PRES_N'
 '@BASEBOARD_FAB2_LIB.BASEBOARD_FAB2(SCH_1):FM_TPM_PRES_N':
 C_SIGNAL='@baseboard_fab2_lib.baseboard_fab2(sch_1):fm_tpm_pres_n';
NODE_NAME     U7C1 AE4
 '@BASEBOARD_FAB2_LIB.BASEBOARD_FAB2(SCH_1):PAGE119_I115@MSTR_U_PROC.LBG_CORE_QAT_EXT_D(CHIPS)':
 'GPP_A22': CDS_PINID='GPP_A22';
NODE_NAME     Q9W4 4
 '@BASEBOARD_FAB2_LIB.BASEBOARD_FAB2(SCH_1):PAGE249_I15@W_HDL.LMV331IDCKRG4-GP(CHIPS)':
 'OUT': CDS_PINID='\out\';
NODE_NAME     U25W4 AA22
 '@BASEBOARD_FAB2_LIB.BASEBOARD_FAB2(SCH_1):PAGE146_I104@W_HDL.AST2520A1-GP-GP(CHIPS)':
 'GPIOAA3_VPOR5_NORD3_SALT10': CDS_PINID='GPIOAA3_VPOR5_NORD3_SALT10';
NODE_NAME     R8E3 2
 '@BASEBOARD_FAB2_LIB.BASEBOARD_FAB2(SCH_1):PAGE133_I371@MSTR_DISCRETE.RES(CHIPS)':
 'B': CDS_PINID='B';
NET_NAME
'FM_TPM_PRES_RST'
 '@BASEBOARD_FAB2_LIB.BASEBOARD_FAB2(SCH_1):FM_TPM_PRES_RST':
 C_SIGNAL='@baseboard_fab2_lib.baseboard_fab2(sch_1):fm_tpm_pres_rst';
NODE_NAME     Q9W2 3
 '@BASEBOARD_FAB2_LIB.BASEBOARD_FAB2(SCH_1):PAGE249_I29@MSTR_DISCRETE.NPN(CHIPS)':
 'C': CDS_PINID='C';
NODE_NAME     Q9W3 1
 '@BASEBOARD_FAB2_LIB.BASEBOARD_FAB2(SCH_1):PAGE249_I49@MSTR_DISCRETE.NPN(CHIPS)':
 'B': CDS_PINID='B';
NODE_NAME     R3W5 2
 '@BASEBOARD_FAB2_LIB.BASEBOARD_FAB2(SCH_1):PAGE249_I58@MSTR_DISCRETE.RES(CHIPS)':
 'B': CDS_PINID='B';
NET_NAME
'FM_TPM_PRES_RST_N'
 '@BASEBOARD_FAB2_LIB.BASEBOARD_FAB2(SCH_1):FM_TPM_PRES_RST_N':
 C_SIGNAL='@baseboard_fab2_lib.baseboard_fab2(sch_1):fm_tpm_pres_rst_n';
NODE_NAME     U7C1 BN40
 '@BASEBOARD_FAB2_LIB.BASEBOARD_FAB2(SCH_1):PAGE119_I115@MSTR_U_PROC.LBG_CORE_QAT_EXT_D(CHIPS)':
 'GPP_D12_SSATA_SDATAOUT1': CDS_PINID='GPP_D12_SSATA_SDATAOUT1';
NODE_NAME     R8D22 2
 '@BASEBOARD_FAB2_LIB.BASEBOARD_FAB2(SCH_1):PAGE157_I386@MSTR_DISCRETE.RES(CHIPS)':
 'B': CDS_PINID='B';
NODE_NAME     J8E1 8
 '@BASEBOARD_FAB2_LIB.BASEBOARD_FAB2(SCH_1):PAGE184_I87@MSTR_SCONN.SCONN11_H67026001(CHIPS)':
 'IO8': CDS_PINID='IO8';
NODE_NAME     Q9W4 1
 '@BASEBOARD_FAB2_LIB.BASEBOARD_FAB2(SCH_1):PAGE249_I15@W_HDL.LMV331IDCKRG4-GP(CHIPS)':
 '+IN': CDS_PINID='\+in\';
NODE_NAME     Q9W1 3
 '@BASEBOARD_FAB2_LIB.BASEBOARD_FAB2(SCH_1):PAGE249_I30@MSTR_DISCRETE.FET_N(CHIPS)':
 'DRN': CDS_PINID='DRN';
NODE_NAME     R3W4 1
 '@BASEBOARD_FAB2_LIB.BASEBOARD_FAB2(SCH_1):PAGE249_I31@W_HDL.47KR2F-GP(CHIPS)':
 '1': CDS_PINID='\1\';
NODE_NAME     R8W1 2
 '@BASEBOARD_FAB2_LIB.BASEBOARD_FAB2(SCH_1):PAGE249_I34@MSTR_DISCRETE.RES(CHIPS)':
 'B': CDS_PINID='B';
NODE_NAME     R3W3 2
 '@BASEBOARD_FAB2_LIB.BASEBOARD_FAB2(SCH_1):PAGE249_I36@MSTR_DISCRETE.RES(CHIPS)':
 'B': CDS_PINID='B';
NODE_NAME     R9E14 1
 '@BASEBOARD_FAB2_LIB.BASEBOARD_FAB2(SCH_1):PAGE157_I393@MSTR_DISCRETE.RES(CHIPS)':
 'A': CDS_PINID='A';
NET_NAME
'FM_TPM_PRES_RST_N_R'
 '@BASEBOARD_FAB2_LIB.BASEBOARD_FAB2(SCH_1):FM_TPM_PRES_RST_N_R':
 C_SIGNAL='@baseboard_fab2_lib.baseboard_fab2(sch_1):fm_tpm_pres_rst_n_r';
NODE_NAME     Q9W2 1
 '@BASEBOARD_FAB2_LIB.BASEBOARD_FAB2(SCH_1):PAGE249_I29@MSTR_DISCRETE.NPN(CHIPS)':
 'B': CDS_PINID='B';
NODE_NAME     R3W4 2
 '@BASEBOARD_FAB2_LIB.BASEBOARD_FAB2(SCH_1):PAGE249_I31@W_HDL.47KR2F-GP(CHIPS)':
 '2': CDS_PINID='\2\';
NET_NAME
'FM_UARTSW_LSB_N'
 '@BASEBOARD_FAB2_LIB.BASEBOARD_FAB2(SCH_1):FM_UARTSW_LSB_N':
 C_SIGNAL='@baseboard_fab2_lib.baseboard_fab2(sch_1):fm_uartsw_lsb_n';
NODE_NAME     U7C1 AT4
 '@BASEBOARD_FAB2_LIB.BASEBOARD_FAB2(SCH_1):PAGE120_I147@MSTR_U_PROC.LBG_CORE_QAT_EXT_D(CHIPS)':
 'GPP_H0_SRCCLKREQ6_N': CDS_PINID='GPP_H0_SRCCLKREQ6_N';
NODE_NAME     U9F2 6
 '@BASEBOARD_FAB2_LIB.BASEBOARD_FAB2(SCH_1):PAGE158_I74@MSTR_ANALOG.FSA3357(CHIPS)':
 'S1': CDS_PINID='S1';
NODE_NAME     U9F1 6
 '@BASEBOARD_FAB2_LIB.BASEBOARD_FAB2(SCH_1):PAGE158_I75@MSTR_ANALOG.FSA3357(CHIPS)':
 'S1': CDS_PINID='S1';
NODE_NAME     DS9A4 2
 '@BASEBOARD_FAB2_LIB.BASEBOARD_FAB2(SCH_1):PAGE158_I130@MSTR_DISCRETE.LED(CHIPS)':
 'C': CDS_PINID='C';
NODE_NAME     U8D7 R9
 '@BASEBOARD_FAB2_LIB.BASEBOARD_FAB2(SCH_1):PAGE190_I179@MSTR_MEMORY.LCMXO2_A(CHIPS)':
 'PB18A': CDS_PINID='PB18A';
NODE_NAME     U25W4 N21
 '@BASEBOARD_FAB2_LIB.BASEBOARD_FAB2(SCH_1):PAGE144_I95@W_HDL.AST2520A1-GP-GP(CHIPS)':
 'GPIOQ4_SCL14': CDS_PINID='GPIOQ4_SCL14';
NET_NAME
'FM_UARTSW_LSB_R_N'
 '@BASEBOARD_FAB2_LIB.BASEBOARD_FAB2(SCH_1):FM_UARTSW_LSB_R_N':
 C_SIGNAL='@baseboard_fab2_lib.baseboard_fab2(sch_1):fm_uartsw_lsb_r_n';
NODE_NAME     DS9A4 1
 '@BASEBOARD_FAB2_LIB.BASEBOARD_FAB2(SCH_1):PAGE158_I130@MSTR_DISCRETE.LED(CHIPS)':
 'A': CDS_PINID='A';
NODE_NAME     R1L43 1
 '@BASEBOARD_FAB2_LIB.BASEBOARD_FAB2(SCH_1):PAGE158_I131@MSTR_DISCRETE.RES(CHIPS)':
 'A': CDS_PINID='A';
NET_NAME
'FM_UARTSW_MSB_N'
 '@BASEBOARD_FAB2_LIB.BASEBOARD_FAB2(SCH_1):FM_UARTSW_MSB_N':
 C_SIGNAL='@baseboard_fab2_lib.baseboard_fab2(sch_1):fm_uartsw_msb_n';
NODE_NAME     U7C1 BA13
 '@BASEBOARD_FAB2_LIB.BASEBOARD_FAB2(SCH_1):PAGE120_I147@MSTR_U_PROC.LBG_CORE_QAT_EXT_D(CHIPS)':
 'GPP_G23_SSATAXPCIE0_SSATAGP0': CDS_PINID='GPP_G23_SSATAXPCIE0_SSATAGP0';
NODE_NAME     U9F2 5
 '@BASEBOARD_FAB2_LIB.BASEBOARD_FAB2(SCH_1):PAGE158_I74@MSTR_ANALOG.FSA3357(CHIPS)':
 'S2': CDS_PINID='S2';
NODE_NAME     U9F1 5
 '@BASEBOARD_FAB2_LIB.BASEBOARD_FAB2(SCH_1):PAGE158_I75@MSTR_ANALOG.FSA3357(CHIPS)':
 'S2': CDS_PINID='S2';
NODE_NAME     DS9A7 2
 '@BASEBOARD_FAB2_LIB.BASEBOARD_FAB2(SCH_1):PAGE158_I134@MSTR_DISCRETE.LED(CHIPS)':
 'C': CDS_PINID='C';
NODE_NAME     U8D7 P11
 '@BASEBOARD_FAB2_LIB.BASEBOARD_FAB2(SCH_1):PAGE190_I179@MSTR_MEMORY.LCMXO2_A(CHIPS)':
 'PB21B': CDS_PINID='PB21B';
NODE_NAME     U25W4 N22
 '@BASEBOARD_FAB2_LIB.BASEBOARD_FAB2(SCH_1):PAGE144_I95@W_HDL.AST2520A1-GP-GP(CHIPS)':
 'GPIOQ5_SDA14': CDS_PINID='GPIOQ5_SDA14';
NET_NAME
'FM_UARTSW_MSB_R_N'
 '@BASEBOARD_FAB2_LIB.BASEBOARD_FAB2(SCH_1):FM_UARTSW_MSB_R_N':
 C_SIGNAL='@baseboard_fab2_lib.baseboard_fab2(sch_1):fm_uartsw_msb_r_n';
NODE_NAME     DS9A7 1
 '@BASEBOARD_FAB2_LIB.BASEBOARD_FAB2(SCH_1):PAGE158_I134@MSTR_DISCRETE.LED(CHIPS)':
 'A': CDS_PINID='A';
NODE_NAME     R1L44 1
 '@BASEBOARD_FAB2_LIB.BASEBOARD_FAB2(SCH_1):PAGE158_I136@MSTR_DISCRETE.RES(CHIPS)':
 'A': CDS_PINID='A';
NET_NAME
'FM_UART_ALERT_N'
 '@BASEBOARD_FAB2_LIB.BASEBOARD_FAB2(SCH_1):FM_UART_ALERT_N':
 C_SIGNAL='@baseboard_fab2_lib.baseboard_fab2(sch_1):fm_uart_alert_n';
NODE_NAME     U7C1 BK13
 '@BASEBOARD_FAB2_LIB.BASEBOARD_FAB2(SCH_1):PAGE119_I115@MSTR_U_PROC.LBG_CORE_QAT_EXT_D(CHIPS)':
 'GPP_B15': CDS_PINID='GPP_B15';
NODE_NAME     U8D7 P2
 '@BASEBOARD_FAB2_LIB.BASEBOARD_FAB2(SCH_1):PAGE190_I179@MSTR_MEMORY.LCMXO2_A(CHIPS)':
 'PL14D': CDS_PINID='PL14D';
NODE_NAME     R9F55 2
 '@BASEBOARD_FAB2_LIB.BASEBOARD_FAB2(SCH_1):PAGE183_I3@MSTR_DISCRETE.RES(CHIPS)':
 'B': CDS_PINID='B';
NET_NAME
'FM_UART_PRES_N'
 '@BASEBOARD_FAB2_LIB.BASEBOARD_FAB2(SCH_1):FM_UART_PRES_N':
 C_SIGNAL='@baseboard_fab2_lib.baseboard_fab2(sch_1):fm_uart_pres_n';
NODE_NAME     U7C1 T2
 '@BASEBOARD_FAB2_LIB.BASEBOARD_FAB2(SCH_1):PAGE119_I115@MSTR_U_PROC.LBG_CORE_QAT_EXT_D(CHIPS)':
 'GPP_A16_CLKOUT_LPC2': CDS_PINID='GPP_A16_CLKOUT_LPC2';
NODE_NAME     R7C13 2
 '@BASEBOARD_FAB2_LIB.BASEBOARD_FAB2(SCH_1):PAGE137_I67@MSTR_DISCRETE.RES(CHIPS)':
 'B': CDS_PINID='B';
NODE_NAME     J9G1 9
 '@BASEBOARD_FAB2_LIB.BASEBOARD_FAB2(SCH_1):PAGE137_I128@MSTR_CONN.CONN12_C73564003(CHIPS)':
 'IO9': CDS_PINID='IO9';
NET_NAME
'FM_UART_SEL_N'
 '@BASEBOARD_FAB2_LIB.BASEBOARD_FAB2(SCH_1):FM_UART_SEL_N':
 C_SIGNAL='@baseboard_fab2_lib.baseboard_fab2(sch_1):fm_uart_sel_n';
NODE_NAME     Q6W2 1
 '@BASEBOARD_FAB2_LIB.BASEBOARD_FAB2(SCH_1):PAGE168_I47@MSTR_DISCRETE.NPN(CHIPS)':
 'B': CDS_PINID='B';
NODE_NAME     R6W49 2
 '@BASEBOARD_FAB2_LIB.BASEBOARD_FAB2(SCH_1):PAGE168_I48@MSTR_DISCRETE.RES(CHIPS)':
 'B': CDS_PINID='B';
NET_NAME
'FM_UART_SWITCH_N'
 '@BASEBOARD_FAB2_LIB.BASEBOARD_FAB2(SCH_1):FM_UART_SWITCH_N':
 C_SIGNAL='@baseboard_fab2_lib.baseboard_fab2(sch_1):fm_uart_switch_n';
NODE_NAME     J9A2 12
 '@BASEBOARD_FAB2_LIB.BASEBOARD_FAB2(SCH_1):PAGE155_I171@MSTR_CONN.CONN14_H54902001(CHIPS)':
 'IO12': CDS_PINID='IO12';
NODE_NAME     R1L6 1
 '@BASEBOARD_FAB2_LIB.BASEBOARD_FAB2(SCH_1):PAGE168_I6@MSTR_DISCRETE.RES(CHIPS)':
 'A': CDS_PINID='A';
NODE_NAME     U6W1 20
 '@BASEBOARD_FAB2_LIB.BASEBOARD_FAB2(SCH_1):PAGE247_I120@W_HDL.TCA9555PWR-GP(CHIPS)':
 'P17': CDS_PINID='P17';
NODE_NAME     R9A5 2
 '@BASEBOARD_FAB2_LIB.BASEBOARD_FAB2(SCH_1):PAGE155_I198@MSTR_DISCRETE.RES(CHIPS)':
 'B': CDS_PINID='B';
NODE_NAME     R6W49 1
 '@BASEBOARD_FAB2_LIB.BASEBOARD_FAB2(SCH_1):PAGE168_I48@MSTR_DISCRETE.RES(CHIPS)':
 'A': CDS_PINID='A';
NET_NAME
'FM_USB_P0_EN_BOOT_BIOS_STRAP_N'
 '@BASEBOARD_FAB2_LIB.BASEBOARD_FAB2(SCH_1):FM_USB_P0_EN_BOOT_BIOS_STRAP_N':
 C_SIGNAL='@baseboard_fab2_lib.baseboard_fab2(sch_1):fm_usb_p0_en_boot_bios_stra~
p_n';
NODE_NAME     U7C1 BR17
 '@BASEBOARD_FAB2_LIB.BASEBOARD_FAB2(SCH_1):PAGE119_I115@MSTR_U_PROC.LBG_CORE_QAT_EXT_D(CHIPS)':
 'GPP_B22': CDS_PINID='GPP_B22';
NODE_NAME     R2N14 2
 '@BASEBOARD_FAB2_LIB.BASEBOARD_FAB2(SCH_1):PAGE125_I83@MSTR_DISCRETE.RES(CHIPS)':
 'B': CDS_PINID='B';
NODE_NAME     R1W13 1
 '@BASEBOARD_FAB2_LIB.BASEBOARD_FAB2(SCH_1):PAGE176_I138@MSTR_DISCRETE.RES(CHIPS)':
 'A': CDS_PINID='A';
NET_NAME
'FM_USB_P0_EN_R_N'
 '@BASEBOARD_FAB2_LIB.BASEBOARD_FAB2(SCH_1):FM_USB_P0_EN_R_N':
 C_SIGNAL='@baseboard_fab2_lib.baseboard_fab2(sch_1):fm_usb_p0_en_r_n';
NODE_NAME     U1M3 4
 '@BASEBOARD_FAB2_LIB.BASEBOARD_FAB2(SCH_1):PAGE176_I100@MSTR_VREG.TPS2061(CHIPS)':
 'EN_N': CDS_PINID='EN_N';
NODE_NAME     R1M25 1
 '@BASEBOARD_FAB2_LIB.BASEBOARD_FAB2(SCH_1):PAGE176_I111@MSTR_DISCRETE.RES(CHIPS)':
 'A': CDS_PINID='A';
NODE_NAME     R1W12 2
 '@BASEBOARD_FAB2_LIB.BASEBOARD_FAB2(SCH_1):PAGE176_I137@MSTR_DISCRETE.RES(CHIPS)':
 'B': CDS_PINID='B';
NODE_NAME     R1W13 2
 '@BASEBOARD_FAB2_LIB.BASEBOARD_FAB2(SCH_1):PAGE176_I138@MSTR_DISCRETE.RES(CHIPS)':
 'B': CDS_PINID='B';
NET_NAME
'FM_UV_ADR_TRIGGER_EN'
 '@BASEBOARD_FAB2_LIB.BASEBOARD_FAB2(SCH_1):FM_UV_ADR_TRIGGER_EN':
 C_SIGNAL='@baseboard_fab2_lib.baseboard_fab2(sch_1):fm_uv_adr_trigger_en';
NODE_NAME     U7C1 BL15
 '@BASEBOARD_FAB2_LIB.BASEBOARD_FAB2(SCH_1):PAGE119_I115@MSTR_U_PROC.LBG_CORE_QAT_EXT_D(CHIPS)':
 'GPP_B18': CDS_PINID='GPP_B18';
NODE_NAME     U8D7 H12
 '@BASEBOARD_FAB2_LIB.BASEBOARD_FAB2(SCH_1):PAGE191_I59@MSTR_MEMORY.LCMXO2_A(CHIPS)':
 'PR5D': CDS_PINID='PR5D';
NODE_NAME     U25W4 C16
 '@BASEBOARD_FAB2_LIB.BASEBOARD_FAB2(SCH_1):PAGE144_I95@W_HDL.AST2520A1-GP-GP(CHIPS)':
 'GPIOI3_SYSMISO': CDS_PINID='GPIOI3_SYSMISO';
NODE_NAME     R2U30 2
 '@BASEBOARD_FAB2_LIB.BASEBOARD_FAB2(SCH_1):PAGE125_I88@MSTR_DISCRETE.RES(CHIPS)':
 'B': CDS_PINID='B';
NET_NAME
'FM_UV_ADR_TRIGGER_N'
 '@BASEBOARD_FAB2_LIB.BASEBOARD_FAB2(SCH_1):FM_UV_ADR_TRIGGER_N':
 C_SIGNAL='@baseboard_fab2_lib.baseboard_fab2(sch_1):fm_uv_adr_trigger_n';
NODE_NAME     U8D7 G15
 '@BASEBOARD_FAB2_LIB.BASEBOARD_FAB2(SCH_1):PAGE191_I59@MSTR_MEMORY.LCMXO2_A(CHIPS)':
 'PR5A': CDS_PINID='PR5A';
NODE_NAME     R9P6 2
 '@BASEBOARD_FAB2_LIB.BASEBOARD_FAB2(SCH_1):PAGE200_I149@MSTR_DISCRETE.RES(CHIPS)':
 'B': CDS_PINID='B';
NODE_NAME     U9P1 6
 '@BASEBOARD_FAB2_LIB.BASEBOARD_FAB2(SCH_1):PAGE200_I163@MSTR_VREG.TPS3700(CHIPS)':
 'OUTA': CDS_PINID='OUTA';
NODE_NAME     CR9P2 1
 '@BASEBOARD_FAB2_LIB.BASEBOARD_FAB2(SCH_1):PAGE200_I213@MSTR_DISCRETE.DIODE(CHIPS)':
 'C': CDS_PINID='C';
NET_NAME
'FM_WBG_PRSNT_N'
 '@BASEBOARD_FAB2_LIB.BASEBOARD_FAB2(SCH_1):FM_WBG_PRSNT_N':
 C_SIGNAL='@baseboard_fab2_lib.baseboard_fab2(sch_1):fm_wbg_prsnt_n';
NODE_NAME     U7C1 D8
 '@BASEBOARD_FAB2_LIB.BASEBOARD_FAB2(SCH_1):PAGE121_I34@MSTR_U_PROC.LBG_CORE_QAT_EXT_D(CHIPS)':
 'RSVD'<10>: CDS_PINID='RSVD(10)';
NODE_NAME     R7C8 2
 '@BASEBOARD_FAB2_LIB.BASEBOARD_FAB2(SCH_1):PAGE133_I296@MSTR_DISCRETE.RES(CHIPS)':
 'B': CDS_PINID='B';
NODE_NAME     U8D7 G11
 '@BASEBOARD_FAB2_LIB.BASEBOARD_FAB2(SCH_1):PAGE191_I59@MSTR_MEMORY.LCMXO2_A(CHIPS)':
 'PR5C': CDS_PINID='PR5C';
NET_NAME
'FM_XRC_PRESENT_N'
 '@BASEBOARD_FAB2_LIB.BASEBOARD_FAB2(SCH_1):FM_XRC_PRESENT_N':
 C_SIGNAL='@baseboard_fab2_lib.baseboard_fab2(sch_1):fm_xrc_present_n';
NODE_NAME     U7C1 BW48
 '@BASEBOARD_FAB2_LIB.BASEBOARD_FAB2(SCH_1):PAGE119_I115@MSTR_U_PROC.LBG_CORE_QAT_EXT_D(CHIPS)':
 'GPP_D17': CDS_PINID='GPP_D17';
NODE_NAME     R8B23 2
 '@BASEBOARD_FAB2_LIB.BASEBOARD_FAB2(SCH_1):PAGE133_I280@MSTR_DISCRETE.RES(CHIPS)':
 'B': CDS_PINID='B';
NODE_NAME     U25W4 AA4
 '@BASEBOARD_FAB2_LIB.BASEBOARD_FAB2(SCH_1):PAGE147_I106@W_HDL.AST2520A1-GP-GP(CHIPS)':
 'GPIOO6_TACH6_VPIR4': CDS_PINID='GPIOO6_TACH6_VPIR4';
NODE_NAME     J1C1 G5
 '@BASEBOARD_FAB2_LIB.BASEBOARD_FAB2(SCH_1):PAGE182_I79@W_HDL.DM-FCI-CONN76-8R-GP-U-01(CHIPS)':
 'MB_SLOT_ID1': CDS_PINID='MB_SLOT_ID1';
NET_NAME
'FM_XRC_READY_N'
 '@BASEBOARD_FAB2_LIB.BASEBOARD_FAB2(SCH_1):FM_XRC_READY_N':
 C_SIGNAL='@baseboard_fab2_lib.baseboard_fab2(sch_1):fm_xrc_ready_n';
NODE_NAME     U7C1 CA41
 '@BASEBOARD_FAB2_LIB.BASEBOARD_FAB2(SCH_1):PAGE119_I115@MSTR_U_PROC.LBG_CORE_QAT_EXT_D(CHIPS)':
 'GPP_D18': CDS_PINID='GPP_D18';
NODE_NAME     R8B30 2
 '@BASEBOARD_FAB2_LIB.BASEBOARD_FAB2(SCH_1):PAGE133_I282@MSTR_DISCRETE.RES(CHIPS)':
 'B': CDS_PINID='B';
NODE_NAME     U25W4 W4
 '@BASEBOARD_FAB2_LIB.BASEBOARD_FAB2(SCH_1):PAGE147_I106@W_HDL.AST2520A1-GP-GP(CHIPS)':
 'GPIOO7_TACH7_VPIR5': CDS_PINID='GPIOO7_TACH7_VPIR5';
NODE_NAME     R1C31 1
 '@BASEBOARD_FAB2_LIB.BASEBOARD_FAB2(SCH_1):PAGE182_I6@MSTR_DISCRETE.RES(CHIPS)':
 'A': CDS_PINID='A';
NODE_NAME     J1C1 H5
 '@BASEBOARD_FAB2_LIB.BASEBOARD_FAB2(SCH_1):PAGE182_I79@W_HDL.DM-FCI-CONN76-8R-GP-U-01(CHIPS)':
 'MB_SLOT_ID2': CDS_PINID='MB_SLOT_ID2';
NET_NAME
'FP_ID_LED_P5V_STBY_N'
 '@BASEBOARD_FAB2_LIB.BASEBOARD_FAB2(SCH_1):FP_ID_LED_P5V_STBY_N':
 C_SIGNAL='@baseboard_fab2_lib.baseboard_fab2(sch_1):fp_id_led_p5v_stby_n';
NODE_NAME     DS9A1 1
 '@BASEBOARD_FAB2_LIB.BASEBOARD_FAB2(SCH_1):PAGE175_I50@MSTR_DISCRETE.LED(CHIPS)':
 'C': CDS_PINID='C';
NODE_NAME     U1L2 4
 '@BASEBOARD_FAB2_LIB.BASEBOARD_FAB2(SCH_1):PAGE175_I57@MSTR_TTL.TTL1G86(CHIPS)':
 'Y': CDS_PINID='Y';
NET_NAME
'FP_ID_LED_XOR_R'
 '@BASEBOARD_FAB2_LIB.BASEBOARD_FAB2(SCH_1):FP_ID_LED_XOR_R':
 C_SIGNAL='@baseboard_fab2_lib.baseboard_fab2(sch_1):fp_id_led_xor_r';
NODE_NAME     DS9A1 2
 '@BASEBOARD_FAB2_LIB.BASEBOARD_FAB2(SCH_1):PAGE175_I50@MSTR_DISCRETE.LED(CHIPS)':
 'A': CDS_PINID='A';
NODE_NAME     R1L8 2
 '@BASEBOARD_FAB2_LIB.BASEBOARD_FAB2(SCH_1):PAGE175_I58@MSTR_DISCRETE.RES(CHIPS)':
 'B': CDS_PINID='B';
NET_NAME
'FP_LED_HDD_ACTIVITY_AND_N'
 '@BASEBOARD_FAB2_LIB.BASEBOARD_FAB2(SCH_1):FP_LED_HDD_ACTIVITY_AND_N':
 C_SIGNAL='@baseboard_fab2_lib.baseboard_fab2(sch_1):fp_led_hdd_activity_and_n';
NODE_NAME     DS9A2 1
 '@BASEBOARD_FAB2_LIB.BASEBOARD_FAB2(SCH_1):PAGE177_I42@MSTR_DISCRETE.LED(CHIPS)':
 'C': CDS_PINID='C';
NODE_NAME     U1M1 4
 '@BASEBOARD_FAB2_LIB.BASEBOARD_FAB2(SCH_1):PAGE177_I70@MSTR_TTL.TTL1G08(CHIPS)':
 'Y'<0>: CDS_PINID='Y(0)';
NET_NAME
'FP_LED_HDD_ACTIVITY_AND_R_N'
 '@BASEBOARD_FAB2_LIB.BASEBOARD_FAB2(SCH_1):FP_LED_HDD_ACTIVITY_AND_R_N':
 C_SIGNAL='@baseboard_fab2_lib.baseboard_fab2(sch_1):fp_led_hdd_activity_and_r_n~
';
NODE_NAME     DS9A2 2
 '@BASEBOARD_FAB2_LIB.BASEBOARD_FAB2(SCH_1):PAGE177_I42@MSTR_DISCRETE.LED(CHIPS)':
 'A': CDS_PINID='A';
NODE_NAME     R1L21 2
 '@BASEBOARD_FAB2_LIB.BASEBOARD_FAB2(SCH_1):PAGE177_I43@MSTR_DISCRETE.RES(CHIPS)':
 'B': CDS_PINID='B';
NET_NAME
'FP_NMI_BTN'
 '@BASEBOARD_FAB2_LIB.BASEBOARD_FAB2(SCH_1):FP_NMI_BTN':
 C_SIGNAL='@baseboard_fab2_lib.baseboard_fab2(sch_1):fp_nmi_btn';
NODE_NAME     U2R1 1
 '@BASEBOARD_FAB2_LIB.BASEBOARD_FAB2(SCH_1):PAGE157_I390@W_HDL.TC7PZ14FU-GP(CHIPS)':
 '1A': CDS_PINID='\1a\';
NODE_NAME     U2R1 4
 '@BASEBOARD_FAB2_LIB.BASEBOARD_FAB2(SCH_1):PAGE157_I390@W_HDL.TC7PZ14FU-GP(CHIPS)':
 '2Y': CDS_PINID='\2y\';
NET_NAME
'FP_NMI_BTN_N'
 '@BASEBOARD_FAB2_LIB.BASEBOARD_FAB2(SCH_1):FP_NMI_BTN_N':
 C_SIGNAL='@baseboard_fab2_lib.baseboard_fab2(sch_1):fp_nmi_btn_n';
NODE_NAME     U7C1 BN11
 '@BASEBOARD_FAB2_LIB.BASEBOARD_FAB2(SCH_1):PAGE119_I115@MSTR_U_PROC.LBG_CORE_QAT_EXT_D(CHIPS)':
 'GPP_B8_SRCCLKREQ3_N': CDS_PINID='GPP_B8_SRCCLKREQ3_N';
NODE_NAME     R8F24 2
 '@BASEBOARD_FAB2_LIB.BASEBOARD_FAB2(SCH_1):PAGE157_I316@MSTR_DISCRETE.RES(CHIPS)':
 'B': CDS_PINID='B';
NODE_NAME     U25W4 E18
 '@BASEBOARD_FAB2_LIB.BASEBOARD_FAB2(SCH_1):PAGE145_I117@W_HDL.AST2520A1-GP-GP(CHIPS)':
 'GPIOE4_NDTR3': CDS_PINID='GPIOE4_NDTR3';
NODE_NAME     R2R10 2
 '@BASEBOARD_FAB2_LIB.BASEBOARD_FAB2(SCH_1):PAGE157_I391@MSTR_DISCRETE.RES(CHIPS)':
 'B': CDS_PINID='B';
NET_NAME
'FP_NMI_BTN_OUT_N'
 '@BASEBOARD_FAB2_LIB.BASEBOARD_FAB2(SCH_1):FP_NMI_BTN_OUT_N':
 C_SIGNAL='@baseboard_fab2_lib.baseboard_fab2(sch_1):fp_nmi_btn_out_n';
NODE_NAME     R2R9 2
 '@BASEBOARD_FAB2_LIB.BASEBOARD_FAB2(SCH_1):PAGE157_I352@MSTR_DISCRETE.RES(CHIPS)':
 'B': CDS_PINID='B';
NODE_NAME     C2R12 1
 '@BASEBOARD_FAB2_LIB.BASEBOARD_FAB2(SCH_1):PAGE157_I353@DEV_DISCRETE.CAP_A(CHIPS)':
 'A': CDS_PINID='A';
NODE_NAME     U2R1 3
 '@BASEBOARD_FAB2_LIB.BASEBOARD_FAB2(SCH_1):PAGE157_I390@W_HDL.TC7PZ14FU-GP(CHIPS)':
 '2A': CDS_PINID='\2a\';
NET_NAME
'FP_NMI_BTN_OUT_R_N'
 '@BASEBOARD_FAB2_LIB.BASEBOARD_FAB2(SCH_1):FP_NMI_BTN_OUT_R_N':
 C_SIGNAL='@baseboard_fab2_lib.baseboard_fab2(sch_1):fp_nmi_btn_out_r_n';
NODE_NAME     S8E1 2
 '@BASEBOARD_FAB2_LIB.BASEBOARD_FAB2(SCH_1):PAGE157_I351@MSTR_MISC.SWITCH_D90553001(CHIPS)':
 'B': CDS_PINID='B';
NODE_NAME     R2R9 1
 '@BASEBOARD_FAB2_LIB.BASEBOARD_FAB2(SCH_1):PAGE157_I352@MSTR_DISCRETE.RES(CHIPS)':
 'A': CDS_PINID='A';
NODE_NAME     R8E32 2
 '@BASEBOARD_FAB2_LIB.BASEBOARD_FAB2(SCH_1):PAGE157_I385@MSTR_DISCRETE.RES(CHIPS)':
 'B': CDS_PINID='B';
NET_NAME
'FP_NMI_BTN_R_N'
 '@BASEBOARD_FAB2_LIB.BASEBOARD_FAB2(SCH_1):FP_NMI_BTN_R_N':
 C_SIGNAL='@baseboard_fab2_lib.baseboard_fab2(sch_1):fp_nmi_btn_r_n';
NODE_NAME     U2R1 6
 '@BASEBOARD_FAB2_LIB.BASEBOARD_FAB2(SCH_1):PAGE157_I390@W_HDL.TC7PZ14FU-GP(CHIPS)':
 '1Y': CDS_PINID='\1y\';
NODE_NAME     R2R10 1
 '@BASEBOARD_FAB2_LIB.BASEBOARD_FAB2(SCH_1):PAGE157_I391@MSTR_DISCRETE.RES(CHIPS)':
 'A': CDS_PINID='A';
NET_NAME
'FP_PWR_BTN_BUF1_N'
 '@BASEBOARD_FAB2_LIB.BASEBOARD_FAB2(SCH_1):FP_PWR_BTN_BUF1_N':
 C_SIGNAL='@baseboard_fab2_lib.baseboard_fab2(sch_1):fp_pwr_btn_buf1_n';
NODE_NAME     U9A4 6
 '@BASEBOARD_FAB2_LIB.BASEBOARD_FAB2(SCH_1):PAGE175_I97@W_HDL.TC7PZ14FU-GP(CHIPS)':
 '1Y': CDS_PINID='\1y\';
NODE_NAME     U9A4 3
 '@BASEBOARD_FAB2_LIB.BASEBOARD_FAB2(SCH_1):PAGE175_I97@W_HDL.TC7PZ14FU-GP(CHIPS)':
 '2A': CDS_PINID='\2a\';
NET_NAME
'FP_PWR_BTN_R1_N'
 '@BASEBOARD_FAB2_LIB.BASEBOARD_FAB2(SCH_1):FP_PWR_BTN_R1_N':
 C_SIGNAL='@baseboard_fab2_lib.baseboard_fab2(sch_1):fp_pwr_btn_r1_n';
NODE_NAME     R1L31 2
 '@BASEBOARD_FAB2_LIB.BASEBOARD_FAB2(SCH_1):PAGE175_I4@MSTR_DISCRETE.RES(CHIPS)':
 'B': CDS_PINID='B';
NODE_NAME     C1L18 1
 '@BASEBOARD_FAB2_LIB.BASEBOARD_FAB2(SCH_1):PAGE175_I11@DEV_DISCRETE.CAP_A(CHIPS)':
 'A': CDS_PINID='A';
NODE_NAME     U9A4 1
 '@BASEBOARD_FAB2_LIB.BASEBOARD_FAB2(SCH_1):PAGE175_I97@W_HDL.TC7PZ14FU-GP(CHIPS)':
 '1A': CDS_PINID='\1a\';
NET_NAME
'FP_PWR_BTN_R_N'
 '@BASEBOARD_FAB2_LIB.BASEBOARD_FAB2(SCH_1):FP_PWR_BTN_R_N':
 C_SIGNAL='@baseboard_fab2_lib.baseboard_fab2(sch_1):fp_pwr_btn_r_n';
NODE_NAME     R1L31 1
 '@BASEBOARD_FAB2_LIB.BASEBOARD_FAB2(SCH_1):PAGE175_I4@MSTR_DISCRETE.RES(CHIPS)':
 'A': CDS_PINID='A';
NODE_NAME     R1L27 2
 '@BASEBOARD_FAB2_LIB.BASEBOARD_FAB2(SCH_1):PAGE175_I5@MSTR_DISCRETE.RES(CHIPS)':
 'B': CDS_PINID='B';
NODE_NAME     S9A2 3
 '@BASEBOARD_FAB2_LIB.BASEBOARD_FAB2(SCH_1):PAGE175_I92@MSTR_MISC.SWITCH_D37771002(CHIPS)':
 'PIN3': CDS_PINID='PIN3';
NODE_NAME     S9A2 4
 '@BASEBOARD_FAB2_LIB.BASEBOARD_FAB2(SCH_1):PAGE175_I92@MSTR_MISC.SWITCH_D37771002(CHIPS)':
 'PIN4': CDS_PINID='PIN4';
NODE_NAME     U6W1 14
 '@BASEBOARD_FAB2_LIB.BASEBOARD_FAB2(SCH_1):PAGE247_I120@W_HDL.TCA9555PWR-GP(CHIPS)':
 'P11': CDS_PINID='P11';
NET_NAME
'FP_PWR_ID_LED_N'
 '@BASEBOARD_FAB2_LIB.BASEBOARD_FAB2(SCH_1):FP_PWR_ID_LED_N':
 C_SIGNAL='@baseboard_fab2_lib.baseboard_fab2(sch_1):fp_pwr_id_led_n';
NODE_NAME     U7C1 BD3
 '@BASEBOARD_FAB2_LIB.BASEBOARD_FAB2(SCH_1):PAGE120_I147@MSTR_U_PROC.LBG_CORE_QAT_EXT_D(CHIPS)':
 'GPP_H19_SSATAXPCIE1_SSATAGP1': CDS_PINID='GPP_H19_SSATAXPCIE1_SSATAGP1';
NODE_NAME     R8D14 2
 '@BASEBOARD_FAB2_LIB.BASEBOARD_FAB2(SCH_1):PAGE133_I301@MSTR_DISCRETE.RES(CHIPS)':
 'B': CDS_PINID='B';
NODE_NAME     U1L2 2
 '@BASEBOARD_FAB2_LIB.BASEBOARD_FAB2(SCH_1):PAGE175_I57@MSTR_TTL.TTL1G86(CHIPS)':
 'B': CDS_PINID='B';
NODE_NAME     U25W4 Y22
 '@BASEBOARD_FAB2_LIB.BASEBOARD_FAB2(SCH_1):PAGE146_I104@W_HDL.AST2520A1-GP-GP(CHIPS)':
 'GPIOAA2_VPOR4_NORD2_SALT9': CDS_PINID='GPIOAA2_VPOR4_NORD2_SALT9';
NET_NAME
'FP_RST_BTN_BUF1_N'
 '@BASEBOARD_FAB2_LIB.BASEBOARD_FAB2(SCH_1):FP_RST_BTN_BUF1_N':
 C_SIGNAL='@baseboard_fab2_lib.baseboard_fab2(sch_1):fp_rst_btn_buf1_n';
NODE_NAME     U9A3 6
 '@BASEBOARD_FAB2_LIB.BASEBOARD_FAB2(SCH_1):PAGE175_I93@W_HDL.TC7PZ14FU-GP(CHIPS)':
 '1Y': CDS_PINID='\1y\';
NODE_NAME     U9A3 3
 '@BASEBOARD_FAB2_LIB.BASEBOARD_FAB2(SCH_1):PAGE175_I93@W_HDL.TC7PZ14FU-GP(CHIPS)':
 '2A': CDS_PINID='\2a\';
NET_NAME
'FP_RST_BTN_R_N'
 '@BASEBOARD_FAB2_LIB.BASEBOARD_FAB2(SCH_1):FP_RST_BTN_R_N':
 C_SIGNAL='@baseboard_fab2_lib.baseboard_fab2(sch_1):fp_rst_btn_r_n';
NODE_NAME     C1L10 1
 '@BASEBOARD_FAB2_LIB.BASEBOARD_FAB2(SCH_1):PAGE175_I19@DEV_DISCRETE.CAP_A(CHIPS)':
 'A': CDS_PINID='A';
NODE_NAME     R1L22 2
 '@BASEBOARD_FAB2_LIB.BASEBOARD_FAB2(SCH_1):PAGE175_I22@MSTR_DISCRETE.RES(CHIPS)':
 'B': CDS_PINID='B';
NODE_NAME     U9A3 1
 '@BASEBOARD_FAB2_LIB.BASEBOARD_FAB2(SCH_1):PAGE175_I93@W_HDL.TC7PZ14FU-GP(CHIPS)':
 '1A': CDS_PINID='\1a\';
NET_NAME
'GND'
 '@BASEBOARD_FAB2_LIB.BASEBOARD_FAB2(SCH_1):GND':
 C_SIGNAL='@baseboard_fab2_lib.baseboard_fab2(sch_1):gnd',
 BOM_COST='TBD',
 ROOM='TBD';
NODE_NAME     R5D1 2
 '@BASEBOARD_FAB2_LIB.BASEBOARD_FAB2(SCH_1):PAGE21_I177@MSTR_DISCRETE.RES(CHIPS)':
 'B': CDS_PINID='B';
NODE_NAME     R5D2 2
 '@BASEBOARD_FAB2_LIB.BASEBOARD_FAB2(SCH_1):PAGE21_I178@MSTR_DISCRETE.RES(CHIPS)':
 'B': CDS_PINID='B';
NODE_NAME     R6D1 2
 '@BASEBOARD_FAB2_LIB.BASEBOARD_FAB2(SCH_1):PAGE21_I179@MSTR_DISCRETE.RES(CHIPS)':
 'B': CDS_PINID='B';
NODE_NAME     R4P8 2
 '@BASEBOARD_FAB2_LIB.BASEBOARD_FAB2(SCH_1):PAGE21_I180@MSTR_DISCRETE.RES(CHIPS)':
 'B': CDS_PINID='B';
NODE_NAME     R4P10 2
 '@BASEBOARD_FAB2_LIB.BASEBOARD_FAB2(SCH_1):PAGE21_I181@MSTR_DISCRETE.RES(CHIPS)':
 'B': CDS_PINID='B';
NODE_NAME     R4P11 2
 '@BASEBOARD_FAB2_LIB.BASEBOARD_FAB2(SCH_1):PAGE21_I182@MSTR_DISCRETE.RES(CHIPS)':
 'B': CDS_PINID='B';
NODE_NAME     R6D11 2
 '@BASEBOARD_FAB2_LIB.BASEBOARD_FAB2(SCH_1):PAGE21_I184@MSTR_DISCRETE.RES(CHIPS)':
 'B': CDS_PINID='B';
NODE_NAME     R4P3 2
 '@BASEBOARD_FAB2_LIB.BASEBOARD_FAB2(SCH_1):PAGE21_I186@MSTR_DISCRETE.RES(CHIPS)':
 'B': CDS_PINID='B';
NODE_NAME     R4P2 2
 '@BASEBOARD_FAB2_LIB.BASEBOARD_FAB2(SCH_1):PAGE21_I188@MSTR_DISCRETE.RES(CHIPS)':
 'B': CDS_PINID='B';
NODE_NAME     R4P4 2
 '@BASEBOARD_FAB2_LIB.BASEBOARD_FAB2(SCH_1):PAGE21_I189@MSTR_DISCRETE.RES(CHIPS)':
 'B': CDS_PINID='B';
NODE_NAME     R6D2 2
 '@BASEBOARD_FAB2_LIB.BASEBOARD_FAB2(SCH_1):PAGE21_I204@MSTR_DISCRETE.RES(CHIPS)':
 'B': CDS_PINID='B';
NODE_NAME     R5R1 2
 '@BASEBOARD_FAB2_LIB.BASEBOARD_FAB2(SCH_1):PAGE22_I188@MSTR_DISCRETE.RES(CHIPS)':
 'B': CDS_PINID='B';
NODE_NAME     R5P4 2
 '@BASEBOARD_FAB2_LIB.BASEBOARD_FAB2(SCH_1):PAGE22_I190@MSTR_DISCRETE.RES(CHIPS)':
 'B': CDS_PINID='B';
NODE_NAME     U5D1 DF23
 '@BASEBOARD_FAB2_LIB.BASEBOARD_FAB2(SCH_1):PAGE35_I3@CHPSET_LIB.SKX_EXT_B(CHIPS)':
 'UPI2_RX_DN'<0>: CDS_PINID='UPI2_RX_DN(0)';
NODE_NAME     U5D1 DE22
 '@BASEBOARD_FAB2_LIB.BASEBOARD_FAB2(SCH_1):PAGE35_I3@CHPSET_LIB.SKX_EXT_B(CHIPS)':
 'UPI2_RX_DN'<1>: CDS_PINID='UPI2_RX_DN(1)';
NODE_NAME     U5D1 DC22
 '@BASEBOARD_FAB2_LIB.BASEBOARD_FAB2(SCH_1):PAGE35_I3@CHPSET_LIB.SKX_EXT_B(CHIPS)':
 'UPI2_RX_DN'<2>: CDS_PINID='UPI2_RX_DN(2)';
NODE_NAME     U5D1 DB21
 '@BASEBOARD_FAB2_LIB.BASEBOARD_FAB2(SCH_1):PAGE35_I3@CHPSET_LIB.SKX_EXT_B(CHIPS)':
 'UPI2_RX_DN'<3>: CDS_PINID='UPI2_RX_DN(3)';
NODE_NAME     U5D1 DD19
 '@BASEBOARD_FAB2_LIB.BASEBOARD_FAB2(SCH_1):PAGE35_I3@CHPSET_LIB.SKX_EXT_B(CHIPS)':
 'UPI2_RX_DN'<4>: CDS_PINID='UPI2_RX_DN(4)';
NODE_NAME     U5D1 DA20
 '@BASEBOARD_FAB2_LIB.BASEBOARD_FAB2(SCH_1):PAGE35_I3@CHPSET_LIB.SKX_EXT_B(CHIPS)':
 'UPI2_RX_DN'<5>: CDS_PINID='UPI2_RX_DN(5)';
NODE_NAME     U5D1 CW20
 '@BASEBOARD_FAB2_LIB.BASEBOARD_FAB2(SCH_1):PAGE35_I3@CHPSET_LIB.SKX_EXT_B(CHIPS)':
 'UPI2_RX_DN'<6>: CDS_PINID='UPI2_RX_DN(6)';
NODE_NAME     U5D1 CV19
 '@BASEBOARD_FAB2_LIB.BASEBOARD_FAB2(SCH_1):PAGE35_I3@CHPSET_LIB.SKX_EXT_B(CHIPS)':
 'UPI2_RX_DN'<7>: CDS_PINID='UPI2_RX_DN(7)';
NODE_NAME     U5D1 CT21
 '@BASEBOARD_FAB2_LIB.BASEBOARD_FAB2(SCH_1):PAGE35_I3@CHPSET_LIB.SKX_EXT_B(CHIPS)':
 'UPI2_RX_DN'<8>: CDS_PINID='UPI2_RX_DN(8)';
NODE_NAME     U5D1 CR18
 '@BASEBOARD_FAB2_LIB.BASEBOARD_FAB2(SCH_1):PAGE35_I3@CHPSET_LIB.SKX_EXT_B(CHIPS)':
 'UPI2_RX_DN'<9>: CDS_PINID='UPI2_RX_DN(9)';
NODE_NAME     U5D1 CN20
 '@BASEBOARD_FAB2_LIB.BASEBOARD_FAB2(SCH_1):PAGE35_I3@CHPSET_LIB.SKX_EXT_B(CHIPS)':
 'UPI2_RX_DN'<10>: CDS_PINID='UPI2_RX_DN(10)';
NODE_NAME     U5D1 CP21
 '@BASEBOARD_FAB2_LIB.BASEBOARD_FAB2(SCH_1):PAGE35_I3@CHPSET_LIB.SKX_EXT_B(CHIPS)':
 'UPI2_RX_DN'<11>: CDS_PINID='UPI2_RX_DN(11)';
NODE_NAME     U5D1 CL16
 '@BASEBOARD_FAB2_LIB.BASEBOARD_FAB2(SCH_1):PAGE35_I3@CHPSET_LIB.SKX_EXT_B(CHIPS)':
 'UPI2_RX_DN'<12>: CDS_PINID='UPI2_RX_DN(12)';
NODE_NAME     U5D1 CJ18
 '@BASEBOARD_FAB2_LIB.BASEBOARD_FAB2(SCH_1):PAGE35_I3@CHPSET_LIB.SKX_EXT_B(CHIPS)':
 'UPI2_RX_DN'<13>: CDS_PINID='UPI2_RX_DN(13)';
NODE_NAME     U5D1 CH17
 '@BASEBOARD_FAB2_LIB.BASEBOARD_FAB2(SCH_1):PAGE35_I3@CHPSET_LIB.SKX_EXT_B(CHIPS)':
 'UPI2_RX_DN'<14>: CDS_PINID='UPI2_RX_DN(14)';
NODE_NAME     U5D1 CE16
 '@BASEBOARD_FAB2_LIB.BASEBOARD_FAB2(SCH_1):PAGE35_I3@CHPSET_LIB.SKX_EXT_B(CHIPS)':
 'UPI2_RX_DN'<15>: CDS_PINID='UPI2_RX_DN(15)';
NODE_NAME     U5D1 CD15
 '@BASEBOARD_FAB2_LIB.BASEBOARD_FAB2(SCH_1):PAGE35_I3@CHPSET_LIB.SKX_EXT_B(CHIPS)':
 'UPI2_RX_DN'<16>: CDS_PINID='UPI2_RX_DN(16)';
NODE_NAME     U5D1 CF17
 '@BASEBOARD_FAB2_LIB.BASEBOARD_FAB2(SCH_1):PAGE35_I3@CHPSET_LIB.SKX_EXT_B(CHIPS)':
 'UPI2_RX_DN'<17>: CDS_PINID='UPI2_RX_DN(17)';
NODE_NAME     U5D1 CB15
 '@BASEBOARD_FAB2_LIB.BASEBOARD_FAB2(SCH_1):PAGE35_I3@CHPSET_LIB.SKX_EXT_B(CHIPS)':
 'UPI2_RX_DN'<18>: CDS_PINID='UPI2_RX_DN(18)';
NODE_NAME     U5D1 BY17
 '@BASEBOARD_FAB2_LIB.BASEBOARD_FAB2(SCH_1):PAGE35_I3@CHPSET_LIB.SKX_EXT_B(CHIPS)':
 'UPI2_RX_DN'<19>: CDS_PINID='UPI2_RX_DN(19)';
NODE_NAME     U5D1 DG22
 '@BASEBOARD_FAB2_LIB.BASEBOARD_FAB2(SCH_1):PAGE35_I3@CHPSET_LIB.SKX_EXT_B(CHIPS)':
 'UPI2_RX_DP'<0>: CDS_PINID='UPI2_RX_DP(0)';
NODE_NAME     U5D1 DD21
 '@BASEBOARD_FAB2_LIB.BASEBOARD_FAB2(SCH_1):PAGE35_I3@CHPSET_LIB.SKX_EXT_B(CHIPS)':
 'UPI2_RX_DP'<1>: CDS_PINID='UPI2_RX_DP(1)';
NODE_NAME     U5D1 DA22
 '@BASEBOARD_FAB2_LIB.BASEBOARD_FAB2(SCH_1):PAGE35_I3@CHPSET_LIB.SKX_EXT_B(CHIPS)':
 'UPI2_RX_DP'<2>: CDS_PINID='UPI2_RX_DP(2)';
NODE_NAME     U5D1 DC20
 '@BASEBOARD_FAB2_LIB.BASEBOARD_FAB2(SCH_1):PAGE35_I3@CHPSET_LIB.SKX_EXT_B(CHIPS)':
 'UPI2_RX_DP'<3>: CDS_PINID='UPI2_RX_DP(3)';
NODE_NAME     U5D1 DB19
 '@BASEBOARD_FAB2_LIB.BASEBOARD_FAB2(SCH_1):PAGE35_I3@CHPSET_LIB.SKX_EXT_B(CHIPS)':
 'UPI2_RX_DP'<4>: CDS_PINID='UPI2_RX_DP(4)';
NODE_NAME     U5D1 CY19
 '@BASEBOARD_FAB2_LIB.BASEBOARD_FAB2(SCH_1):PAGE35_I3@CHPSET_LIB.SKX_EXT_B(CHIPS)':
 'UPI2_RX_DP'<5>: CDS_PINID='UPI2_RX_DP(5)';
NODE_NAME     U5D1 CU20
 '@BASEBOARD_FAB2_LIB.BASEBOARD_FAB2(SCH_1):PAGE35_I3@CHPSET_LIB.SKX_EXT_B(CHIPS)':
 'UPI2_RX_DP'<6>: CDS_PINID='UPI2_RX_DP(6)';
NODE_NAME     U5D1 CW18
 '@BASEBOARD_FAB2_LIB.BASEBOARD_FAB2(SCH_1):PAGE35_I3@CHPSET_LIB.SKX_EXT_B(CHIPS)':
 'UPI2_RX_DP'<7>: CDS_PINID='UPI2_RX_DP(7)';
NODE_NAME     U5D1 CR20
 '@BASEBOARD_FAB2_LIB.BASEBOARD_FAB2(SCH_1):PAGE35_I3@CHPSET_LIB.SKX_EXT_B(CHIPS)':
 'UPI2_RX_DP'<8>: CDS_PINID='UPI2_RX_DP(8)';
NODE_NAME     U5D1 CN18
 '@BASEBOARD_FAB2_LIB.BASEBOARD_FAB2(SCH_1):PAGE35_I3@CHPSET_LIB.SKX_EXT_B(CHIPS)':
 'UPI2_RX_DP'<9>: CDS_PINID='UPI2_RX_DP(9)';
NODE_NAME     U5D1 CP19
 '@BASEBOARD_FAB2_LIB.BASEBOARD_FAB2(SCH_1):PAGE35_I3@CHPSET_LIB.SKX_EXT_B(CHIPS)':
 'UPI2_RX_DP'<10>: CDS_PINID='UPI2_RX_DP(10)';
NODE_NAME     U5D1 CM21
 '@BASEBOARD_FAB2_LIB.BASEBOARD_FAB2(SCH_1):PAGE35_I3@CHPSET_LIB.SKX_EXT_B(CHIPS)':
 'UPI2_RX_DP'<11>: CDS_PINID='UPI2_RX_DP(11)';
NODE_NAME     U5D1 CJ16
 '@BASEBOARD_FAB2_LIB.BASEBOARD_FAB2(SCH_1):PAGE35_I3@CHPSET_LIB.SKX_EXT_B(CHIPS)':
 'UPI2_RX_DP'<12>: CDS_PINID='UPI2_RX_DP(12)';
NODE_NAME     U5D1 CK17
 '@BASEBOARD_FAB2_LIB.BASEBOARD_FAB2(SCH_1):PAGE35_I3@CHPSET_LIB.SKX_EXT_B(CHIPS)':
 'UPI2_RX_DP'<13>: CDS_PINID='UPI2_RX_DP(13)';
NODE_NAME     U5D1 CG16
 '@BASEBOARD_FAB2_LIB.BASEBOARD_FAB2(SCH_1):PAGE35_I3@CHPSET_LIB.SKX_EXT_B(CHIPS)':
 'UPI2_RX_DP'<14>: CDS_PINID='UPI2_RX_DP(14)';
NODE_NAME     U5D1 CF15
 '@BASEBOARD_FAB2_LIB.BASEBOARD_FAB2(SCH_1):PAGE35_I3@CHPSET_LIB.SKX_EXT_B(CHIPS)':
 'UPI2_RX_DP'<15>: CDS_PINID='UPI2_RX_DP(15)';
NODE_NAME     U5D1 CC14
 '@BASEBOARD_FAB2_LIB.BASEBOARD_FAB2(SCH_1):PAGE35_I3@CHPSET_LIB.SKX_EXT_B(CHIPS)':
 'UPI2_RX_DP'<16>: CDS_PINID='UPI2_RX_DP(16)';
NODE_NAME     U5D1 CD17
 '@BASEBOARD_FAB2_LIB.BASEBOARD_FAB2(SCH_1):PAGE35_I3@CHPSET_LIB.SKX_EXT_B(CHIPS)':
 'UPI2_RX_DP'<17>: CDS_PINID='UPI2_RX_DP(17)';
NODE_NAME     U5D1 BY15
 '@BASEBOARD_FAB2_LIB.BASEBOARD_FAB2(SCH_1):PAGE35_I3@CHPSET_LIB.SKX_EXT_B(CHIPS)':
 'UPI2_RX_DP'<18>: CDS_PINID='UPI2_RX_DP(18)';
NODE_NAME     U5D1 CA16
 '@BASEBOARD_FAB2_LIB.BASEBOARD_FAB2(SCH_1):PAGE35_I3@CHPSET_LIB.SKX_EXT_B(CHIPS)':
 'UPI2_RX_DP'<19>: CDS_PINID='UPI2_RX_DP(19)';
NODE_NAME     R5D5 2
 '@BASEBOARD_FAB2_LIB.BASEBOARD_FAB2(SCH_1):PAGE37_I303@MSTR_DISCRETE.RES(CHIPS)':
 'B': CDS_PINID='B';
NODE_NAME     C6D1 2
 '@BASEBOARD_FAB2_LIB.BASEBOARD_FAB2(SCH_1):PAGE38_I19@MSTR_DISCRETE.CAP(CHIPS)':
 'B': CDS_PINID='B';
NODE_NAME     U5D1 J74
 '@BASEBOARD_FAB2_LIB.BASEBOARD_FAB2(SCH_1):PAGE40_I20@CHPSET_LIB.SKX_EXT_B(CHIPS)':
 'VSS'<1094>: CDS_PINID='VSS(1094)';
NODE_NAME     U5D1 J72
 '@BASEBOARD_FAB2_LIB.BASEBOARD_FAB2(SCH_1):PAGE40_I20@CHPSET_LIB.SKX_EXT_B(CHIPS)':
 'VSS'<1095>: CDS_PINID='VSS(1095)';
NODE_NAME     U5D1 J40
 '@BASEBOARD_FAB2_LIB.BASEBOARD_FAB2(SCH_1):PAGE40_I20@CHPSET_LIB.SKX_EXT_B(CHIPS)':
 'VSS'<1096>: CDS_PINID='VSS(1096)';
NODE_NAME     U5D1 J38
 '@BASEBOARD_FAB2_LIB.BASEBOARD_FAB2(SCH_1):PAGE40_I20@CHPSET_LIB.SKX_EXT_B(CHIPS)':
 'VSS'<1097>: CDS_PINID='VSS(1097)';
NODE_NAME     U5D1 J34
 '@BASEBOARD_FAB2_LIB.BASEBOARD_FAB2(SCH_1):PAGE40_I20@CHPSET_LIB.SKX_EXT_B(CHIPS)':
 'VSS'<1098>: CDS_PINID='VSS(1098)';
NODE_NAME     U5D1 J32
 '@BASEBOARD_FAB2_LIB.BASEBOARD_FAB2(SCH_1):PAGE40_I20@CHPSET_LIB.SKX_EXT_B(CHIPS)':
 'VSS'<1099>: CDS_PINID='VSS(1099)';
NODE_NAME     U5D1 J28
 '@BASEBOARD_FAB2_LIB.BASEBOARD_FAB2(SCH_1):PAGE40_I20@CHPSET_LIB.SKX_EXT_B(CHIPS)':
 'VSS'<1100>: CDS_PINID='VSS(1100)';
NODE_NAME     U5D1 J26
 '@BASEBOARD_FAB2_LIB.BASEBOARD_FAB2(SCH_1):PAGE40_I20@CHPSET_LIB.SKX_EXT_B(CHIPS)':
 'VSS'<1101>: CDS_PINID='VSS(1101)';
NODE_NAME     U5D1 J22
 '@BASEBOARD_FAB2_LIB.BASEBOARD_FAB2(SCH_1):PAGE40_I20@CHPSET_LIB.SKX_EXT_B(CHIPS)':
 'VSS'<1102>: CDS_PINID='VSS(1102)';
NODE_NAME     U5D1 J14
 '@BASEBOARD_FAB2_LIB.BASEBOARD_FAB2(SCH_1):PAGE40_I20@CHPSET_LIB.SKX_EXT_B(CHIPS)':
 'VSS'<1103>: CDS_PINID='VSS(1103)';
NODE_NAME     U5D1 J12
 '@BASEBOARD_FAB2_LIB.BASEBOARD_FAB2(SCH_1):PAGE40_I20@CHPSET_LIB.SKX_EXT_B(CHIPS)':
 'VSS'<1104>: CDS_PINID='VSS(1104)';
NODE_NAME     U5D1 J4
 '@BASEBOARD_FAB2_LIB.BASEBOARD_FAB2(SCH_1):PAGE40_I20@CHPSET_LIB.SKX_EXT_B(CHIPS)':
 'VSS'<1105>: CDS_PINID='VSS(1105)';
NODE_NAME     U5D1 DN44
 '@BASEBOARD_FAB2_LIB.BASEBOARD_FAB2(SCH_1):PAGE40_I20@CHPSET_LIB.SKX_EXT_B(CHIPS)':
 'VSS'<1106>: CDS_PINID='VSS(1106)';
NODE_NAME     U5D1 H75
 '@BASEBOARD_FAB2_LIB.BASEBOARD_FAB2(SCH_1):PAGE40_I20@CHPSET_LIB.SKX_EXT_B(CHIPS)':
 'VSS'<1107>: CDS_PINID='VSS(1107)';
NODE_NAME     U5D1 H71
 '@BASEBOARD_FAB2_LIB.BASEBOARD_FAB2(SCH_1):PAGE40_I20@CHPSET_LIB.SKX_EXT_B(CHIPS)':
 'VSS'<1108>: CDS_PINID='VSS(1108)';
NODE_NAME     U5D1 H65
 '@BASEBOARD_FAB2_LIB.BASEBOARD_FAB2(SCH_1):PAGE40_I20@CHPSET_LIB.SKX_EXT_B(CHIPS)':
 'VSS'<1109>: CDS_PINID='VSS(1109)';
NODE_NAME     U5D1 H41
 '@BASEBOARD_FAB2_LIB.BASEBOARD_FAB2(SCH_1):PAGE40_I20@CHPSET_LIB.SKX_EXT_B(CHIPS)':
 'VSS'<1110>: CDS_PINID='VSS(1110)';
NODE_NAME     U5D1 H39
 '@BASEBOARD_FAB2_LIB.BASEBOARD_FAB2(SCH_1):PAGE40_I20@CHPSET_LIB.SKX_EXT_B(CHIPS)':
 'VSS'<1111>: CDS_PINID='VSS(1111)';
NODE_NAME     U5D1 H37
 '@BASEBOARD_FAB2_LIB.BASEBOARD_FAB2(SCH_1):PAGE40_I20@CHPSET_LIB.SKX_EXT_B(CHIPS)':
 'VSS'<1112>: CDS_PINID='VSS(1112)';
NODE_NAME     U5D1 H35
 '@BASEBOARD_FAB2_LIB.BASEBOARD_FAB2(SCH_1):PAGE40_I20@CHPSET_LIB.SKX_EXT_B(CHIPS)':
 'VSS'<1113>: CDS_PINID='VSS(1113)';
NODE_NAME     U5D1 H33
 '@BASEBOARD_FAB2_LIB.BASEBOARD_FAB2(SCH_1):PAGE40_I20@CHPSET_LIB.SKX_EXT_B(CHIPS)':
 'VSS'<1114>: CDS_PINID='VSS(1114)';
NODE_NAME     U5D1 H31
 '@BASEBOARD_FAB2_LIB.BASEBOARD_FAB2(SCH_1):PAGE40_I20@CHPSET_LIB.SKX_EXT_B(CHIPS)':
 'VSS'<1115>: CDS_PINID='VSS(1115)';
NODE_NAME     U5D1 H29
 '@BASEBOARD_FAB2_LIB.BASEBOARD_FAB2(SCH_1):PAGE40_I20@CHPSET_LIB.SKX_EXT_B(CHIPS)':
 'VSS'<1116>: CDS_PINID='VSS(1116)';
NODE_NAME     U5D1 H27
 '@BASEBOARD_FAB2_LIB.BASEBOARD_FAB2(SCH_1):PAGE40_I20@CHPSET_LIB.SKX_EXT_B(CHIPS)':
 'VSS'<1117>: CDS_PINID='VSS(1117)';
NODE_NAME     U5D1 H25
 '@BASEBOARD_FAB2_LIB.BASEBOARD_FAB2(SCH_1):PAGE40_I20@CHPSET_LIB.SKX_EXT_B(CHIPS)':
 'VSS'<1118>: CDS_PINID='VSS(1118)';
NODE_NAME     U5D1 H11
 '@BASEBOARD_FAB2_LIB.BASEBOARD_FAB2(SCH_1):PAGE40_I20@CHPSET_LIB.SKX_EXT_B(CHIPS)':
 'VSS'<1119>: CDS_PINID='VSS(1119)';
NODE_NAME     U5D1 H3
 '@BASEBOARD_FAB2_LIB.BASEBOARD_FAB2(SCH_1):PAGE40_I20@CHPSET_LIB.SKX_EXT_B(CHIPS)':
 'VSS'<1120>: CDS_PINID='VSS(1120)';
NODE_NAME     U5D1 G82
 '@BASEBOARD_FAB2_LIB.BASEBOARD_FAB2(SCH_1):PAGE40_I20@CHPSET_LIB.SKX_EXT_B(CHIPS)':
 'VSS'<1121>: CDS_PINID='VSS(1121)';
NODE_NAME     U5D1 G80
 '@BASEBOARD_FAB2_LIB.BASEBOARD_FAB2(SCH_1):PAGE40_I20@CHPSET_LIB.SKX_EXT_B(CHIPS)':
 'VSS'<1122>: CDS_PINID='VSS(1122)';
NODE_NAME     U5D1 G78
 '@BASEBOARD_FAB2_LIB.BASEBOARD_FAB2(SCH_1):PAGE40_I20@CHPSET_LIB.SKX_EXT_B(CHIPS)':
 'VSS'<1123>: CDS_PINID='VSS(1123)';
NODE_NAME     U5D1 G76
 '@BASEBOARD_FAB2_LIB.BASEBOARD_FAB2(SCH_1):PAGE40_I20@CHPSET_LIB.SKX_EXT_B(CHIPS)':
 'VSS'<1124>: CDS_PINID='VSS(1124)';
NODE_NAME     U5D1 G70
 '@BASEBOARD_FAB2_LIB.BASEBOARD_FAB2(SCH_1):PAGE40_I20@CHPSET_LIB.SKX_EXT_B(CHIPS)':
 'VSS'<1125>: CDS_PINID='VSS(1125)';
NODE_NAME     U5D1 G66
 '@BASEBOARD_FAB2_LIB.BASEBOARD_FAB2(SCH_1):PAGE40_I20@CHPSET_LIB.SKX_EXT_B(CHIPS)':
 'VSS'<1126>: CDS_PINID='VSS(1126)';
NODE_NAME     U5D1 G42
 '@BASEBOARD_FAB2_LIB.BASEBOARD_FAB2(SCH_1):PAGE40_I20@CHPSET_LIB.SKX_EXT_B(CHIPS)':
 'VSS'<1127>: CDS_PINID='VSS(1127)';
NODE_NAME     U5D1 G38
 '@BASEBOARD_FAB2_LIB.BASEBOARD_FAB2(SCH_1):PAGE40_I20@CHPSET_LIB.SKX_EXT_B(CHIPS)':
 'VSS'<1128>: CDS_PINID='VSS(1128)';
NODE_NAME     U5D1 G36
 '@BASEBOARD_FAB2_LIB.BASEBOARD_FAB2(SCH_1):PAGE40_I20@CHPSET_LIB.SKX_EXT_B(CHIPS)':
 'VSS'<1129>: CDS_PINID='VSS(1129)';
NODE_NAME     U5D1 G32
 '@BASEBOARD_FAB2_LIB.BASEBOARD_FAB2(SCH_1):PAGE40_I20@CHPSET_LIB.SKX_EXT_B(CHIPS)':
 'VSS'<1130>: CDS_PINID='VSS(1130)';
NODE_NAME     U5D1 G30
 '@BASEBOARD_FAB2_LIB.BASEBOARD_FAB2(SCH_1):PAGE40_I20@CHPSET_LIB.SKX_EXT_B(CHIPS)':
 'VSS'<1131>: CDS_PINID='VSS(1131)';
NODE_NAME     U5D1 G26
 '@BASEBOARD_FAB2_LIB.BASEBOARD_FAB2(SCH_1):PAGE40_I20@CHPSET_LIB.SKX_EXT_B(CHIPS)':
 'VSS'<1132>: CDS_PINID='VSS(1132)';
NODE_NAME     U5D1 G24
 '@BASEBOARD_FAB2_LIB.BASEBOARD_FAB2(SCH_1):PAGE40_I20@CHPSET_LIB.SKX_EXT_B(CHIPS)':
 'VSS'<1133>: CDS_PINID='VSS(1133)';
NODE_NAME     U5D1 G22
 '@BASEBOARD_FAB2_LIB.BASEBOARD_FAB2(SCH_1):PAGE40_I20@CHPSET_LIB.SKX_EXT_B(CHIPS)':
 'VSS'<1134>: CDS_PINID='VSS(1134)';
NODE_NAME     U5D1 G8
 '@BASEBOARD_FAB2_LIB.BASEBOARD_FAB2(SCH_1):PAGE40_I20@CHPSET_LIB.SKX_EXT_B(CHIPS)':
 'VSS'<1135>: CDS_PINID='VSS(1135)';
NODE_NAME     U5D1 G4
 '@BASEBOARD_FAB2_LIB.BASEBOARD_FAB2(SCH_1):PAGE40_I20@CHPSET_LIB.SKX_EXT_B(CHIPS)':
 'VSS'<1136>: CDS_PINID='VSS(1136)';
NODE_NAME     U5D1 F69
 '@BASEBOARD_FAB2_LIB.BASEBOARD_FAB2(SCH_1):PAGE40_I20@CHPSET_LIB.SKX_EXT_B(CHIPS)':
 'VSS'<1137>: CDS_PINID='VSS(1137)';
NODE_NAME     U5D1 F67
 '@BASEBOARD_FAB2_LIB.BASEBOARD_FAB2(SCH_1):PAGE40_I20@CHPSET_LIB.SKX_EXT_B(CHIPS)':
 'VSS'<1138>: CDS_PINID='VSS(1138)';
NODE_NAME     U5D1 F43
 '@BASEBOARD_FAB2_LIB.BASEBOARD_FAB2(SCH_1):PAGE40_I20@CHPSET_LIB.SKX_EXT_B(CHIPS)':
 'VSS'<1139>: CDS_PINID='VSS(1139)';
NODE_NAME     U5D1 F37
 '@BASEBOARD_FAB2_LIB.BASEBOARD_FAB2(SCH_1):PAGE40_I20@CHPSET_LIB.SKX_EXT_B(CHIPS)':
 'VSS'<1140>: CDS_PINID='VSS(1140)';
NODE_NAME     U5D1 F31
 '@BASEBOARD_FAB2_LIB.BASEBOARD_FAB2(SCH_1):PAGE40_I20@CHPSET_LIB.SKX_EXT_B(CHIPS)':
 'VSS'<1141>: CDS_PINID='VSS(1141)';
NODE_NAME     U5D1 F25
 '@BASEBOARD_FAB2_LIB.BASEBOARD_FAB2(SCH_1):PAGE40_I20@CHPSET_LIB.SKX_EXT_B(CHIPS)':
 'VSS'<1142>: CDS_PINID='VSS(1142)';
NODE_NAME     U5D1 F19
 '@BASEBOARD_FAB2_LIB.BASEBOARD_FAB2(SCH_1):PAGE40_I20@CHPSET_LIB.SKX_EXT_B(CHIPS)':
 'VSS'<1143>: CDS_PINID='VSS(1143)';
NODE_NAME     U5D1 F17
 '@BASEBOARD_FAB2_LIB.BASEBOARD_FAB2(SCH_1):PAGE40_I20@CHPSET_LIB.SKX_EXT_B(CHIPS)':
 'VSS'<1144>: CDS_PINID='VSS(1144)';
NODE_NAME     U5D1 F5
 '@BASEBOARD_FAB2_LIB.BASEBOARD_FAB2(SCH_1):PAGE40_I20@CHPSET_LIB.SKX_EXT_B(CHIPS)':
 'VSS'<1145>: CDS_PINID='VSS(1145)';
NODE_NAME     U5D1 E76
 '@BASEBOARD_FAB2_LIB.BASEBOARD_FAB2(SCH_1):PAGE40_I20@CHPSET_LIB.SKX_EXT_B(CHIPS)':
 'VSS'<1146>: CDS_PINID='VSS(1146)';
NODE_NAME     U5D1 E74
 '@BASEBOARD_FAB2_LIB.BASEBOARD_FAB2(SCH_1):PAGE40_I20@CHPSET_LIB.SKX_EXT_B(CHIPS)':
 'VSS'<1147>: CDS_PINID='VSS(1147)';
NODE_NAME     U5D1 E72
 '@BASEBOARD_FAB2_LIB.BASEBOARD_FAB2(SCH_1):PAGE40_I20@CHPSET_LIB.SKX_EXT_B(CHIPS)':
 'VSS'<1148>: CDS_PINID='VSS(1148)';
NODE_NAME     U5D1 E22
 '@BASEBOARD_FAB2_LIB.BASEBOARD_FAB2(SCH_1):PAGE40_I20@CHPSET_LIB.SKX_EXT_B(CHIPS)':
 'VSS'<1149>: CDS_PINID='VSS(1149)';
NODE_NAME     U5D1 E20
 '@BASEBOARD_FAB2_LIB.BASEBOARD_FAB2(SCH_1):PAGE40_I20@CHPSET_LIB.SKX_EXT_B(CHIPS)':
 'VSS'<1150>: CDS_PINID='VSS(1150)';
NODE_NAME     U5D1 E18
 '@BASEBOARD_FAB2_LIB.BASEBOARD_FAB2(SCH_1):PAGE40_I20@CHPSET_LIB.SKX_EXT_B(CHIPS)':
 'VSS'<1151>: CDS_PINID='VSS(1151)';
NODE_NAME     U5D1 E16
 '@BASEBOARD_FAB2_LIB.BASEBOARD_FAB2(SCH_1):PAGE40_I20@CHPSET_LIB.SKX_EXT_B(CHIPS)':
 'VSS'<1152>: CDS_PINID='VSS(1152)';
NODE_NAME     U5D1 E8
 '@BASEBOARD_FAB2_LIB.BASEBOARD_FAB2(SCH_1):PAGE40_I20@CHPSET_LIB.SKX_EXT_B(CHIPS)':
 'VSS'<1153>: CDS_PINID='VSS(1153)';
NODE_NAME     U5D1 E6
 '@BASEBOARD_FAB2_LIB.BASEBOARD_FAB2(SCH_1):PAGE40_I20@CHPSET_LIB.SKX_EXT_B(CHIPS)':
 'VSS'<1154>: CDS_PINID='VSS(1154)';
NODE_NAME     U5D1 D77
 '@BASEBOARD_FAB2_LIB.BASEBOARD_FAB2(SCH_1):PAGE40_I20@CHPSET_LIB.SKX_EXT_B(CHIPS)':
 'VSS'<1155>: CDS_PINID='VSS(1155)';
NODE_NAME     U5D1 D43
 '@BASEBOARD_FAB2_LIB.BASEBOARD_FAB2(SCH_1):PAGE40_I20@CHPSET_LIB.SKX_EXT_B(CHIPS)':
 'VSS'<1156>: CDS_PINID='VSS(1156)';
NODE_NAME     U5D1 D41
 '@BASEBOARD_FAB2_LIB.BASEBOARD_FAB2(SCH_1):PAGE40_I20@CHPSET_LIB.SKX_EXT_B(CHIPS)':
 'VSS'<1157>: CDS_PINID='VSS(1157)';
NODE_NAME     U5D1 D39
 '@BASEBOARD_FAB2_LIB.BASEBOARD_FAB2(SCH_1):PAGE40_I20@CHPSET_LIB.SKX_EXT_B(CHIPS)':
 'VSS'<1158>: CDS_PINID='VSS(1158)';
NODE_NAME     U5D1 D37
 '@BASEBOARD_FAB2_LIB.BASEBOARD_FAB2(SCH_1):PAGE40_I20@CHPSET_LIB.SKX_EXT_B(CHIPS)':
 'VSS'<1159>: CDS_PINID='VSS(1159)';
NODE_NAME     U5D1 D35
 '@BASEBOARD_FAB2_LIB.BASEBOARD_FAB2(SCH_1):PAGE40_I20@CHPSET_LIB.SKX_EXT_B(CHIPS)':
 'VSS'<1160>: CDS_PINID='VSS(1160)';
NODE_NAME     U5D1 D33
 '@BASEBOARD_FAB2_LIB.BASEBOARD_FAB2(SCH_1):PAGE40_I20@CHPSET_LIB.SKX_EXT_B(CHIPS)':
 'VSS'<1161>: CDS_PINID='VSS(1161)';
NODE_NAME     U5D1 D31
 '@BASEBOARD_FAB2_LIB.BASEBOARD_FAB2(SCH_1):PAGE40_I20@CHPSET_LIB.SKX_EXT_B(CHIPS)':
 'VSS'<1162>: CDS_PINID='VSS(1162)';
NODE_NAME     U5D1 D29
 '@BASEBOARD_FAB2_LIB.BASEBOARD_FAB2(SCH_1):PAGE40_I20@CHPSET_LIB.SKX_EXT_B(CHIPS)':
 'VSS'<1163>: CDS_PINID='VSS(1163)';
NODE_NAME     U5D1 D27
 '@BASEBOARD_FAB2_LIB.BASEBOARD_FAB2(SCH_1):PAGE40_I20@CHPSET_LIB.SKX_EXT_B(CHIPS)':
 'VSS'<1164>: CDS_PINID='VSS(1164)';
NODE_NAME     U5D1 D25
 '@BASEBOARD_FAB2_LIB.BASEBOARD_FAB2(SCH_1):PAGE40_I20@CHPSET_LIB.SKX_EXT_B(CHIPS)':
 'VSS'<1165>: CDS_PINID='VSS(1165)';
NODE_NAME     U5D1 D13
 '@BASEBOARD_FAB2_LIB.BASEBOARD_FAB2(SCH_1):PAGE40_I20@CHPSET_LIB.SKX_EXT_B(CHIPS)':
 'VSS'<1166>: CDS_PINID='VSS(1166)';
NODE_NAME     U5D1 D11
 '@BASEBOARD_FAB2_LIB.BASEBOARD_FAB2(SCH_1):PAGE40_I20@CHPSET_LIB.SKX_EXT_B(CHIPS)':
 'VSS'<1167>: CDS_PINID='VSS(1167)';
NODE_NAME     U5D1 CM27
 '@BASEBOARD_FAB2_LIB.BASEBOARD_FAB2(SCH_1):PAGE40_I20@CHPSET_LIB.SKX_EXT_B(CHIPS)':
 'VSS'<1168>: CDS_PINID='VSS(1168)';
NODE_NAME     U5D1 C78
 '@BASEBOARD_FAB2_LIB.BASEBOARD_FAB2(SCH_1):PAGE40_I20@CHPSET_LIB.SKX_EXT_B(CHIPS)':
 'VSS'<1169>: CDS_PINID='VSS(1169)';
NODE_NAME     U5D1 C76
 '@BASEBOARD_FAB2_LIB.BASEBOARD_FAB2(SCH_1):PAGE40_I20@CHPSET_LIB.SKX_EXT_B(CHIPS)':
 'VSS'<1170>: CDS_PINID='VSS(1170)';
NODE_NAME     U5D1 C16
 '@BASEBOARD_FAB2_LIB.BASEBOARD_FAB2(SCH_1):PAGE40_I20@CHPSET_LIB.SKX_EXT_B(CHIPS)':
 'VSS'<1171>: CDS_PINID='VSS(1171)';
NODE_NAME     U5D1 C14
 '@BASEBOARD_FAB2_LIB.BASEBOARD_FAB2(SCH_1):PAGE40_I20@CHPSET_LIB.SKX_EXT_B(CHIPS)':
 'VSS'<1172>: CDS_PINID='VSS(1172)';
NODE_NAME     U5D1 C12
 '@BASEBOARD_FAB2_LIB.BASEBOARD_FAB2(SCH_1):PAGE40_I20@CHPSET_LIB.SKX_EXT_B(CHIPS)':
 'VSS'<1173>: CDS_PINID='VSS(1173)';
NODE_NAME     U5D1 C10
 '@BASEBOARD_FAB2_LIB.BASEBOARD_FAB2(SCH_1):PAGE40_I20@CHPSET_LIB.SKX_EXT_B(CHIPS)':
 'VSS'<1174>: CDS_PINID='VSS(1174)';
NODE_NAME     U5D1 C8
 '@BASEBOARD_FAB2_LIB.BASEBOARD_FAB2(SCH_1):PAGE40_I20@CHPSET_LIB.SKX_EXT_B(CHIPS)':
 'VSS'<1175>: CDS_PINID='VSS(1175)';
NODE_NAME     U5D1 B75
 '@BASEBOARD_FAB2_LIB.BASEBOARD_FAB2(SCH_1):PAGE40_I20@CHPSET_LIB.SKX_EXT_B(CHIPS)':
 'VSS'<1176>: CDS_PINID='VSS(1176)';
NODE_NAME     U5D1 B71
 '@BASEBOARD_FAB2_LIB.BASEBOARD_FAB2(SCH_1):PAGE40_I20@CHPSET_LIB.SKX_EXT_B(CHIPS)':
 'VSS'<1177>: CDS_PINID='VSS(1177)';
NODE_NAME     U5D1 B37
 '@BASEBOARD_FAB2_LIB.BASEBOARD_FAB2(SCH_1):PAGE40_I20@CHPSET_LIB.SKX_EXT_B(CHIPS)':
 'VSS'<1178>: CDS_PINID='VSS(1178)';
NODE_NAME     U5D1 B31
 '@BASEBOARD_FAB2_LIB.BASEBOARD_FAB2(SCH_1):PAGE40_I20@CHPSET_LIB.SKX_EXT_B(CHIPS)':
 'VSS'<1179>: CDS_PINID='VSS(1179)';
NODE_NAME     U5D1 B25
 '@BASEBOARD_FAB2_LIB.BASEBOARD_FAB2(SCH_1):PAGE40_I20@CHPSET_LIB.SKX_EXT_B(CHIPS)':
 'VSS'<1180>: CDS_PINID='VSS(1180)';
NODE_NAME     U5D1 A38
 '@BASEBOARD_FAB2_LIB.BASEBOARD_FAB2(SCH_1):PAGE40_I20@CHPSET_LIB.SKX_EXT_B(CHIPS)':
 'VSS'<1181>: CDS_PINID='VSS(1181)';
NODE_NAME     U5D1 A36
 '@BASEBOARD_FAB2_LIB.BASEBOARD_FAB2(SCH_1):PAGE40_I20@CHPSET_LIB.SKX_EXT_B(CHIPS)':
 'VSS'<1182>: CDS_PINID='VSS(1182)';
NODE_NAME     U5D1 A32
 '@BASEBOARD_FAB2_LIB.BASEBOARD_FAB2(SCH_1):PAGE40_I20@CHPSET_LIB.SKX_EXT_B(CHIPS)':
 'VSS'<1183>: CDS_PINID='VSS(1183)';
NODE_NAME     U5D1 A30
 '@BASEBOARD_FAB2_LIB.BASEBOARD_FAB2(SCH_1):PAGE40_I20@CHPSET_LIB.SKX_EXT_B(CHIPS)':
 'VSS'<1184>: CDS_PINID='VSS(1184)';
NODE_NAME     U5D1 A26
 '@BASEBOARD_FAB2_LIB.BASEBOARD_FAB2(SCH_1):PAGE40_I20@CHPSET_LIB.SKX_EXT_B(CHIPS)':
 'VSS'<1185>: CDS_PINID='VSS(1185)';
NODE_NAME     U5D1 AC58
 '@BASEBOARD_FAB2_LIB.BASEBOARD_FAB2(SCH_1):PAGE40_I20@CHPSET_LIB.SKX_EXT_B(CHIPS)':
 'VSS'<1186>: CDS_PINID='VSS(1186)';
NODE_NAME     U5D1 AC60
 '@BASEBOARD_FAB2_LIB.BASEBOARD_FAB2(SCH_1):PAGE40_I20@CHPSET_LIB.SKX_EXT_B(CHIPS)':
 'VSS'<1187>: CDS_PINID='VSS(1187)';
NODE_NAME     U5D1 AC62
 '@BASEBOARD_FAB2_LIB.BASEBOARD_FAB2(SCH_1):PAGE40_I20@CHPSET_LIB.SKX_EXT_B(CHIPS)':
 'VSS'<1188>: CDS_PINID='VSS(1188)';
NODE_NAME     U5D1 AJ4
 '@BASEBOARD_FAB2_LIB.BASEBOARD_FAB2(SCH_1):PAGE40_I20@CHPSET_LIB.SKX_EXT_B(CHIPS)':
 'VSS'<1189>: CDS_PINID='VSS(1189)';
NODE_NAME     U5D1 AR6
 '@BASEBOARD_FAB2_LIB.BASEBOARD_FAB2(SCH_1):PAGE40_I20@CHPSET_LIB.SKX_EXT_B(CHIPS)':
 'VSS'<1190>: CDS_PINID='VSS(1190)';
NODE_NAME     U5D1 CG6
 '@BASEBOARD_FAB2_LIB.BASEBOARD_FAB2(SCH_1):PAGE40_I20@CHPSET_LIB.SKX_EXT_B(CHIPS)':
 'VSS'<1191>: CDS_PINID='VSS(1191)';
NODE_NAME     U5D1 CW6
 '@BASEBOARD_FAB2_LIB.BASEBOARD_FAB2(SCH_1):PAGE40_I20@CHPSET_LIB.SKX_EXT_B(CHIPS)':
 'VSS'<1192>: CDS_PINID='VSS(1192)';
NODE_NAME     U5D1 DE48
 '@BASEBOARD_FAB2_LIB.BASEBOARD_FAB2(SCH_1):PAGE40_I20@CHPSET_LIB.SKX_EXT_B(CHIPS)':
 'VSS'<1193>: CDS_PINID='VSS(1193)';
NODE_NAME     U5D1 DE50
 '@BASEBOARD_FAB2_LIB.BASEBOARD_FAB2(SCH_1):PAGE40_I20@CHPSET_LIB.SKX_EXT_B(CHIPS)':
 'VSS'<1194>: CDS_PINID='VSS(1194)';
NODE_NAME     U5D1 DE52
 '@BASEBOARD_FAB2_LIB.BASEBOARD_FAB2(SCH_1):PAGE40_I20@CHPSET_LIB.SKX_EXT_B(CHIPS)':
 'VSS'<1195>: CDS_PINID='VSS(1195)';
NODE_NAME     U5D1 DE54
 '@BASEBOARD_FAB2_LIB.BASEBOARD_FAB2(SCH_1):PAGE40_I20@CHPSET_LIB.SKX_EXT_B(CHIPS)':
 'VSS'<1196>: CDS_PINID='VSS(1196)';
NODE_NAME     U5D1 DE56
 '@BASEBOARD_FAB2_LIB.BASEBOARD_FAB2(SCH_1):PAGE40_I20@CHPSET_LIB.SKX_EXT_B(CHIPS)':
 'VSS'<1197>: CDS_PINID='VSS(1197)';
NODE_NAME     U5D1 DE58
 '@BASEBOARD_FAB2_LIB.BASEBOARD_FAB2(SCH_1):PAGE40_I20@CHPSET_LIB.SKX_EXT_B(CHIPS)':
 'VSS'<1198>: CDS_PINID='VSS(1198)';
NODE_NAME     U5D1 DE60
 '@BASEBOARD_FAB2_LIB.BASEBOARD_FAB2(SCH_1):PAGE40_I20@CHPSET_LIB.SKX_EXT_B(CHIPS)':
 'VSS'<1199>: CDS_PINID='VSS(1199)';
NODE_NAME     U5D1 DE62
 '@BASEBOARD_FAB2_LIB.BASEBOARD_FAB2(SCH_1):PAGE40_I20@CHPSET_LIB.SKX_EXT_B(CHIPS)':
 'VSS'<1200>: CDS_PINID='VSS(1200)';
NODE_NAME     U5D1 DL8
 '@BASEBOARD_FAB2_LIB.BASEBOARD_FAB2(SCH_1):PAGE40_I20@CHPSET_LIB.SKX_EXT_B(CHIPS)':
 'VSS'<1201>: CDS_PINID='VSS(1201)';
NODE_NAME     U5D1 DN18
 '@BASEBOARD_FAB2_LIB.BASEBOARD_FAB2(SCH_1):PAGE40_I20@CHPSET_LIB.SKX_EXT_B(CHIPS)':
 'VSS'<1202>: CDS_PINID='VSS(1202)';
NODE_NAME     U5D1 DP45
 '@BASEBOARD_FAB2_LIB.BASEBOARD_FAB2(SCH_1):PAGE40_I20@CHPSET_LIB.SKX_EXT_B(CHIPS)':
 'VSS'<1203>: CDS_PINID='VSS(1203)';
NODE_NAME     U5D1 DP47
 '@BASEBOARD_FAB2_LIB.BASEBOARD_FAB2(SCH_1):PAGE40_I20@CHPSET_LIB.SKX_EXT_B(CHIPS)':
 'VSS'<1204>: CDS_PINID='VSS(1204)';
NODE_NAME     U5D1 DP49
 '@BASEBOARD_FAB2_LIB.BASEBOARD_FAB2(SCH_1):PAGE40_I20@CHPSET_LIB.SKX_EXT_B(CHIPS)':
 'VSS'<1205>: CDS_PINID='VSS(1205)';
NODE_NAME     U5D1 DP51
 '@BASEBOARD_FAB2_LIB.BASEBOARD_FAB2(SCH_1):PAGE40_I20@CHPSET_LIB.SKX_EXT_B(CHIPS)':
 'VSS'<1206>: CDS_PINID='VSS(1206)';
NODE_NAME     U5D1 DP53
 '@BASEBOARD_FAB2_LIB.BASEBOARD_FAB2(SCH_1):PAGE40_I20@CHPSET_LIB.SKX_EXT_B(CHIPS)':
 'VSS'<1207>: CDS_PINID='VSS(1207)';
NODE_NAME     U5D1 DP55
 '@BASEBOARD_FAB2_LIB.BASEBOARD_FAB2(SCH_1):PAGE40_I20@CHPSET_LIB.SKX_EXT_B(CHIPS)':
 'VSS'<1208>: CDS_PINID='VSS(1208)';
NODE_NAME     U5D1 DP57
 '@BASEBOARD_FAB2_LIB.BASEBOARD_FAB2(SCH_1):PAGE40_I20@CHPSET_LIB.SKX_EXT_B(CHIPS)':
 'VSS'<1209>: CDS_PINID='VSS(1209)';
NODE_NAME     U5D1 DP59
 '@BASEBOARD_FAB2_LIB.BASEBOARD_FAB2(SCH_1):PAGE40_I20@CHPSET_LIB.SKX_EXT_B(CHIPS)':
 'VSS'<1210>: CDS_PINID='VSS(1210)';
NODE_NAME     U5D1 DP61
 '@BASEBOARD_FAB2_LIB.BASEBOARD_FAB2(SCH_1):PAGE40_I20@CHPSET_LIB.SKX_EXT_B(CHIPS)':
 'VSS'<1211>: CDS_PINID='VSS(1211)';
NODE_NAME     U5D1 DP63
 '@BASEBOARD_FAB2_LIB.BASEBOARD_FAB2(SCH_1):PAGE40_I20@CHPSET_LIB.SKX_EXT_B(CHIPS)':
 'VSS'<1212>: CDS_PINID='VSS(1212)';
NODE_NAME     U5D1 DP9
 '@BASEBOARD_FAB2_LIB.BASEBOARD_FAB2(SCH_1):PAGE40_I20@CHPSET_LIB.SKX_EXT_B(CHIPS)':
 'VSS'<1213>: CDS_PINID='VSS(1213)';
NODE_NAME     U5D1 DV19
 '@BASEBOARD_FAB2_LIB.BASEBOARD_FAB2(SCH_1):PAGE40_I20@CHPSET_LIB.SKX_EXT_B(CHIPS)':
 'VSS'<1214>: CDS_PINID='VSS(1214)';
NODE_NAME     U5D1 DY45
 '@BASEBOARD_FAB2_LIB.BASEBOARD_FAB2(SCH_1):PAGE40_I20@CHPSET_LIB.SKX_EXT_B(CHIPS)':
 'VSS'<1215>: CDS_PINID='VSS(1215)';
NODE_NAME     U5D1 DY47
 '@BASEBOARD_FAB2_LIB.BASEBOARD_FAB2(SCH_1):PAGE40_I20@CHPSET_LIB.SKX_EXT_B(CHIPS)':
 'VSS'<1216>: CDS_PINID='VSS(1216)';
NODE_NAME     U5D1 DY49
 '@BASEBOARD_FAB2_LIB.BASEBOARD_FAB2(SCH_1):PAGE40_I20@CHPSET_LIB.SKX_EXT_B(CHIPS)':
 'VSS'<1217>: CDS_PINID='VSS(1217)';
NODE_NAME     U5D1 DY51
 '@BASEBOARD_FAB2_LIB.BASEBOARD_FAB2(SCH_1):PAGE40_I20@CHPSET_LIB.SKX_EXT_B(CHIPS)':
 'VSS'<1218>: CDS_PINID='VSS(1218)';
NODE_NAME     U5D1 DY53
 '@BASEBOARD_FAB2_LIB.BASEBOARD_FAB2(SCH_1):PAGE40_I20@CHPSET_LIB.SKX_EXT_B(CHIPS)':
 'VSS'<1219>: CDS_PINID='VSS(1219)';
NODE_NAME     U5D1 DY55
 '@BASEBOARD_FAB2_LIB.BASEBOARD_FAB2(SCH_1):PAGE40_I20@CHPSET_LIB.SKX_EXT_B(CHIPS)':
 'VSS'<1220>: CDS_PINID='VSS(1220)';
NODE_NAME     U5D1 DY57
 '@BASEBOARD_FAB2_LIB.BASEBOARD_FAB2(SCH_1):PAGE40_I20@CHPSET_LIB.SKX_EXT_B(CHIPS)':
 'VSS'<1221>: CDS_PINID='VSS(1221)';
NODE_NAME     U5D1 DY59
 '@BASEBOARD_FAB2_LIB.BASEBOARD_FAB2(SCH_1):PAGE40_I20@CHPSET_LIB.SKX_EXT_B(CHIPS)':
 'VSS'<1222>: CDS_PINID='VSS(1222)';
NODE_NAME     U5D1 DY61
 '@BASEBOARD_FAB2_LIB.BASEBOARD_FAB2(SCH_1):PAGE40_I20@CHPSET_LIB.SKX_EXT_B(CHIPS)':
 'VSS'<1223>: CDS_PINID='VSS(1223)';
NODE_NAME     U5D1 DY63
 '@BASEBOARD_FAB2_LIB.BASEBOARD_FAB2(SCH_1):PAGE40_I20@CHPSET_LIB.SKX_EXT_B(CHIPS)':
 'VSS'<1224>: CDS_PINID='VSS(1224)';
NODE_NAME     U5D1 EA14
 '@BASEBOARD_FAB2_LIB.BASEBOARD_FAB2(SCH_1):PAGE40_I20@CHPSET_LIB.SKX_EXT_B(CHIPS)':
 'VSS'<1225>: CDS_PINID='VSS(1225)';
NODE_NAME     U5D1 L8
 '@BASEBOARD_FAB2_LIB.BASEBOARD_FAB2(SCH_1):PAGE40_I20@CHPSET_LIB.SKX_EXT_B(CHIPS)':
 'VSS'<1226>: CDS_PINID='VSS(1226)';
NODE_NAME     U5D1 V11
 '@BASEBOARD_FAB2_LIB.BASEBOARD_FAB2(SCH_1):PAGE40_I20@CHPSET_LIB.SKX_EXT_B(CHIPS)':
 'VSS'<1227>: CDS_PINID='VSS(1227)';
NODE_NAME     U5D1 E66
 '@BASEBOARD_FAB2_LIB.BASEBOARD_FAB2(SCH_1):PAGE40_I20@CHPSET_LIB.SKX_EXT_B(CHIPS)':
 'VSS'<1228>: CDS_PINID='VSS(1228)';
NODE_NAME     U5D1 ED69
 '@BASEBOARD_FAB2_LIB.BASEBOARD_FAB2(SCH_1):PAGE40_I20@CHPSET_LIB.SKX_EXT_B(CHIPS)':
 'VSS'<1229>: CDS_PINID='VSS(1229)';
NODE_NAME     U5D1 EE80
 '@BASEBOARD_FAB2_LIB.BASEBOARD_FAB2(SCH_1):PAGE40_I20@CHPSET_LIB.SKX_EXT_B(CHIPS)':
 'VSS'<1230>: CDS_PINID='VSS(1230)';
NODE_NAME     U5D1 EE8
 '@BASEBOARD_FAB2_LIB.BASEBOARD_FAB2(SCH_1):PAGE40_I20@CHPSET_LIB.SKX_EXT_B(CHIPS)':
 'VSS'<1231>: CDS_PINID='VSS(1231)';
NODE_NAME     U5D1 EE40
 '@BASEBOARD_FAB2_LIB.BASEBOARD_FAB2(SCH_1):PAGE40_I20@CHPSET_LIB.SKX_EXT_B(CHIPS)':
 'VSS'<1232>: CDS_PINID='VSS(1232)';
NODE_NAME     U5D1 ED81
 '@BASEBOARD_FAB2_LIB.BASEBOARD_FAB2(SCH_1):PAGE40_I20@CHPSET_LIB.SKX_EXT_B(CHIPS)':
 'VSS'<1233>: CDS_PINID='VSS(1233)';
NODE_NAME     U5D1 ED7
 '@BASEBOARD_FAB2_LIB.BASEBOARD_FAB2(SCH_1):PAGE40_I20@CHPSET_LIB.SKX_EXT_B(CHIPS)':
 'VSS'<1234>: CDS_PINID='VSS(1234)';
NODE_NAME     U5D1 ED41
 '@BASEBOARD_FAB2_LIB.BASEBOARD_FAB2(SCH_1):PAGE40_I20@CHPSET_LIB.SKX_EXT_B(CHIPS)':
 'VSS'<1235>: CDS_PINID='VSS(1235)';
NODE_NAME     U5D1 EC82
 '@BASEBOARD_FAB2_LIB.BASEBOARD_FAB2(SCH_1):PAGE40_I20@CHPSET_LIB.SKX_EXT_B(CHIPS)':
 'VSS'<1236>: CDS_PINID='VSS(1236)';
NODE_NAME     U5D1 EC6
 '@BASEBOARD_FAB2_LIB.BASEBOARD_FAB2(SCH_1):PAGE40_I20@CHPSET_LIB.SKX_EXT_B(CHIPS)':
 'VSS'<1237>: CDS_PINID='VSS(1237)';
NODE_NAME     U5D1 EC42
 '@BASEBOARD_FAB2_LIB.BASEBOARD_FAB2(SCH_1):PAGE40_I20@CHPSET_LIB.SKX_EXT_B(CHIPS)':
 'VSS'<1238>: CDS_PINID='VSS(1238)';
NODE_NAME     U5D1 DW2
 '@BASEBOARD_FAB2_LIB.BASEBOARD_FAB2(SCH_1):PAGE40_I20@CHPSET_LIB.SKX_EXT_B(CHIPS)':
 'VSS'<1239>: CDS_PINID='VSS(1239)';
NODE_NAME     U5D1 EB83
 '@BASEBOARD_FAB2_LIB.BASEBOARD_FAB2(SCH_1):PAGE40_I20@CHPSET_LIB.SKX_EXT_B(CHIPS)':
 'VSS'<1240>: CDS_PINID='VSS(1240)';
NODE_NAME     U5D1 EA84
 '@BASEBOARD_FAB2_LIB.BASEBOARD_FAB2(SCH_1):PAGE40_I20@CHPSET_LIB.SKX_EXT_B(CHIPS)':
 'VSS'<1241>: CDS_PINID='VSS(1241)';
NODE_NAME     U5D1 DY85
 '@BASEBOARD_FAB2_LIB.BASEBOARD_FAB2(SCH_1):PAGE40_I20@CHPSET_LIB.SKX_EXT_B(CHIPS)':
 'VSS'<1242>: CDS_PINID='VSS(1242)';
NODE_NAME     U5D1 J86
 '@BASEBOARD_FAB2_LIB.BASEBOARD_FAB2(SCH_1):PAGE40_I20@CHPSET_LIB.SKX_EXT_B(CHIPS)':
 'VSS'<1243>: CDS_PINID='VSS(1243)';
NODE_NAME     U5D1 E82
 '@BASEBOARD_FAB2_LIB.BASEBOARD_FAB2(SCH_1):PAGE40_I20@CHPSET_LIB.SKX_EXT_B(CHIPS)':
 'VSS'<1244>: CDS_PINID='VSS(1244)';
NODE_NAME     U5D1 D81
 '@BASEBOARD_FAB2_LIB.BASEBOARD_FAB2(SCH_1):PAGE40_I20@CHPSET_LIB.SKX_EXT_B(CHIPS)':
 'VSS'<1245>: CDS_PINID='VSS(1245)';
NODE_NAME     U5D1 D3
 '@BASEBOARD_FAB2_LIB.BASEBOARD_FAB2(SCH_1):PAGE40_I20@CHPSET_LIB.SKX_EXT_B(CHIPS)':
 'VSS'<1246>: CDS_PINID='VSS(1246)';
NODE_NAME     U5D1 C80
 '@BASEBOARD_FAB2_LIB.BASEBOARD_FAB2(SCH_1):PAGE40_I20@CHPSET_LIB.SKX_EXT_B(CHIPS)':
 'VSS'<1247>: CDS_PINID='VSS(1247)';
NODE_NAME     U5D1 C4
 '@BASEBOARD_FAB2_LIB.BASEBOARD_FAB2(SCH_1):PAGE40_I20@CHPSET_LIB.SKX_EXT_B(CHIPS)':
 'VSS'<1248>: CDS_PINID='VSS(1248)';
NODE_NAME     U5D1 B79
 '@BASEBOARD_FAB2_LIB.BASEBOARD_FAB2(SCH_1):PAGE40_I20@CHPSET_LIB.SKX_EXT_B(CHIPS)':
 'VSS'<1249>: CDS_PINID='VSS(1249)';
NODE_NAME     U5D1 B5
 '@BASEBOARD_FAB2_LIB.BASEBOARD_FAB2(SCH_1):PAGE40_I20@CHPSET_LIB.SKX_EXT_B(CHIPS)':
 'VSS'<1250>: CDS_PINID='VSS(1250)';
NODE_NAME     U5D1 B43
 '@BASEBOARD_FAB2_LIB.BASEBOARD_FAB2(SCH_1):PAGE40_I20@CHPSET_LIB.SKX_EXT_B(CHIPS)':
 'VSS'<1251>: CDS_PINID='VSS(1251)';
NODE_NAME     U5D1 A42
 '@BASEBOARD_FAB2_LIB.BASEBOARD_FAB2(SCH_1):PAGE40_I20@CHPSET_LIB.SKX_EXT_B(CHIPS)':
 'VSS'<1252>: CDS_PINID='VSS(1252)';
NODE_NAME     U5D1 B9
 '@BASEBOARD_FAB2_LIB.BASEBOARD_FAB2(SCH_1):PAGE40_I20@CHPSET_LIB.SKX_EXT_B(CHIPS)':
 'VSS'<1253>: CDS_PINID='VSS(1253)';
NODE_NAME     U5D1 AA16
 '@BASEBOARD_FAB2_LIB.BASEBOARD_FAB2(SCH_1):PAGE40_I21@CHPSET_LIB.SKX_EXT_B(CHIPS)':
 'VSS'<934>: CDS_PINID='VSS(934)';
NODE_NAME     U5D1 AA4
 '@BASEBOARD_FAB2_LIB.BASEBOARD_FAB2(SCH_1):PAGE40_I21@CHPSET_LIB.SKX_EXT_B(CHIPS)':
 'VSS'<935>: CDS_PINID='VSS(935)';
NODE_NAME     U5D1 Y85
 '@BASEBOARD_FAB2_LIB.BASEBOARD_FAB2(SCH_1):PAGE40_I21@CHPSET_LIB.SKX_EXT_B(CHIPS)':
 'VSS'<936>: CDS_PINID='VSS(936)';
NODE_NAME     U5D1 Y83
 '@BASEBOARD_FAB2_LIB.BASEBOARD_FAB2(SCH_1):PAGE40_I21@CHPSET_LIB.SKX_EXT_B(CHIPS)':
 'VSS'<937>: CDS_PINID='VSS(937)';
NODE_NAME     U5D1 Y81
 '@BASEBOARD_FAB2_LIB.BASEBOARD_FAB2(SCH_1):PAGE40_I21@CHPSET_LIB.SKX_EXT_B(CHIPS)':
 'VSS'<938>: CDS_PINID='VSS(938)';
NODE_NAME     U5D1 Y79
 '@BASEBOARD_FAB2_LIB.BASEBOARD_FAB2(SCH_1):PAGE40_I21@CHPSET_LIB.SKX_EXT_B(CHIPS)':
 'VSS'<939>: CDS_PINID='VSS(939)';
NODE_NAME     U5D1 Y73
 '@BASEBOARD_FAB2_LIB.BASEBOARD_FAB2(SCH_1):PAGE40_I21@CHPSET_LIB.SKX_EXT_B(CHIPS)':
 'VSS'<940>: CDS_PINID='VSS(940)';
NODE_NAME     U5D1 Y71
 '@BASEBOARD_FAB2_LIB.BASEBOARD_FAB2(SCH_1):PAGE40_I21@CHPSET_LIB.SKX_EXT_B(CHIPS)':
 'VSS'<941>: CDS_PINID='VSS(941)';
NODE_NAME     U5D1 Y9
 '@BASEBOARD_FAB2_LIB.BASEBOARD_FAB2(SCH_1):PAGE40_I21@CHPSET_LIB.SKX_EXT_B(CHIPS)':
 'VSS'<942>: CDS_PINID='VSS(942)';
NODE_NAME     U5D1 Y7
 '@BASEBOARD_FAB2_LIB.BASEBOARD_FAB2(SCH_1):PAGE40_I21@CHPSET_LIB.SKX_EXT_B(CHIPS)':
 'VSS'<943>: CDS_PINID='VSS(943)';
NODE_NAME     U5D1 Y67
 '@BASEBOARD_FAB2_LIB.BASEBOARD_FAB2(SCH_1):PAGE40_I21@CHPSET_LIB.SKX_EXT_B(CHIPS)':
 'VSS'<944>: CDS_PINID='VSS(944)';
NODE_NAME     U5D1 Y5
 '@BASEBOARD_FAB2_LIB.BASEBOARD_FAB2(SCH_1):PAGE40_I21@CHPSET_LIB.SKX_EXT_B(CHIPS)':
 'VSS'<945>: CDS_PINID='VSS(945)';
NODE_NAME     U5D1 Y17
 '@BASEBOARD_FAB2_LIB.BASEBOARD_FAB2(SCH_1):PAGE40_I21@CHPSET_LIB.SKX_EXT_B(CHIPS)':
 'VSS'<946>: CDS_PINID='VSS(946)';
NODE_NAME     U5D1 Y15
 '@BASEBOARD_FAB2_LIB.BASEBOARD_FAB2(SCH_1):PAGE40_I21@CHPSET_LIB.SKX_EXT_B(CHIPS)':
 'VSS'<947>: CDS_PINID='VSS(947)';
NODE_NAME     U5D1 W82
 '@BASEBOARD_FAB2_LIB.BASEBOARD_FAB2(SCH_1):PAGE40_I21@CHPSET_LIB.SKX_EXT_B(CHIPS)':
 'VSS'<948>: CDS_PINID='VSS(948)';
NODE_NAME     U5D1 W78
 '@BASEBOARD_FAB2_LIB.BASEBOARD_FAB2(SCH_1):PAGE40_I21@CHPSET_LIB.SKX_EXT_B(CHIPS)':
 'VSS'<949>: CDS_PINID='VSS(949)';
NODE_NAME     U5D1 W74
 '@BASEBOARD_FAB2_LIB.BASEBOARD_FAB2(SCH_1):PAGE40_I21@CHPSET_LIB.SKX_EXT_B(CHIPS)':
 'VSS'<950>: CDS_PINID='VSS(950)';
NODE_NAME     U5D1 W68
 '@BASEBOARD_FAB2_LIB.BASEBOARD_FAB2(SCH_1):PAGE40_I21@CHPSET_LIB.SKX_EXT_B(CHIPS)':
 'VSS'<951>: CDS_PINID='VSS(951)';
NODE_NAME     U5D1 W42
 '@BASEBOARD_FAB2_LIB.BASEBOARD_FAB2(SCH_1):PAGE40_I21@CHPSET_LIB.SKX_EXT_B(CHIPS)':
 'VSS'<952>: CDS_PINID='VSS(952)';
NODE_NAME     U5D1 W40
 '@BASEBOARD_FAB2_LIB.BASEBOARD_FAB2(SCH_1):PAGE40_I21@CHPSET_LIB.SKX_EXT_B(CHIPS)':
 'VSS'<953>: CDS_PINID='VSS(953)';
NODE_NAME     U5D1 W38
 '@BASEBOARD_FAB2_LIB.BASEBOARD_FAB2(SCH_1):PAGE40_I21@CHPSET_LIB.SKX_EXT_B(CHIPS)':
 'VSS'<954>: CDS_PINID='VSS(954)';
NODE_NAME     U5D1 W36
 '@BASEBOARD_FAB2_LIB.BASEBOARD_FAB2(SCH_1):PAGE40_I21@CHPSET_LIB.SKX_EXT_B(CHIPS)':
 'VSS'<955>: CDS_PINID='VSS(955)';
NODE_NAME     U5D1 W34
 '@BASEBOARD_FAB2_LIB.BASEBOARD_FAB2(SCH_1):PAGE40_I21@CHPSET_LIB.SKX_EXT_B(CHIPS)':
 'VSS'<956>: CDS_PINID='VSS(956)';
NODE_NAME     U5D1 W32
 '@BASEBOARD_FAB2_LIB.BASEBOARD_FAB2(SCH_1):PAGE40_I21@CHPSET_LIB.SKX_EXT_B(CHIPS)':
 'VSS'<957>: CDS_PINID='VSS(957)';
NODE_NAME     U5D1 W30
 '@BASEBOARD_FAB2_LIB.BASEBOARD_FAB2(SCH_1):PAGE40_I21@CHPSET_LIB.SKX_EXT_B(CHIPS)':
 'VSS'<958>: CDS_PINID='VSS(958)';
NODE_NAME     U5D1 W28
 '@BASEBOARD_FAB2_LIB.BASEBOARD_FAB2(SCH_1):PAGE40_I21@CHPSET_LIB.SKX_EXT_B(CHIPS)':
 'VSS'<959>: CDS_PINID='VSS(959)';
NODE_NAME     U5D1 W26
 '@BASEBOARD_FAB2_LIB.BASEBOARD_FAB2(SCH_1):PAGE40_I21@CHPSET_LIB.SKX_EXT_B(CHIPS)':
 'VSS'<960>: CDS_PINID='VSS(960)';
NODE_NAME     U5D1 W24
 '@BASEBOARD_FAB2_LIB.BASEBOARD_FAB2(SCH_1):PAGE40_I21@CHPSET_LIB.SKX_EXT_B(CHIPS)':
 'VSS'<961>: CDS_PINID='VSS(961)';
NODE_NAME     U5D1 W22
 '@BASEBOARD_FAB2_LIB.BASEBOARD_FAB2(SCH_1):PAGE40_I21@CHPSET_LIB.SKX_EXT_B(CHIPS)':
 'VSS'<962>: CDS_PINID='VSS(962)';
NODE_NAME     U5D1 W12
 '@BASEBOARD_FAB2_LIB.BASEBOARD_FAB2(SCH_1):PAGE40_I21@CHPSET_LIB.SKX_EXT_B(CHIPS)':
 'VSS'<963>: CDS_PINID='VSS(963)';
NODE_NAME     U5D1 AC56
 '@BASEBOARD_FAB2_LIB.BASEBOARD_FAB2(SCH_1):PAGE40_I21@CHPSET_LIB.SKX_EXT_B(CHIPS)':
 'VSS'<964>: CDS_PINID='VSS(964)';
NODE_NAME     U5D1 W8
 '@BASEBOARD_FAB2_LIB.BASEBOARD_FAB2(SCH_1):PAGE40_I21@CHPSET_LIB.SKX_EXT_B(CHIPS)':
 'VSS'<965>: CDS_PINID='VSS(965)';
NODE_NAME     U5D1 V83
 '@BASEBOARD_FAB2_LIB.BASEBOARD_FAB2(SCH_1):PAGE40_I21@CHPSET_LIB.SKX_EXT_B(CHIPS)':
 'VSS'<966>: CDS_PINID='VSS(966)';
NODE_NAME     U5D1 V77
 '@BASEBOARD_FAB2_LIB.BASEBOARD_FAB2(SCH_1):PAGE40_I21@CHPSET_LIB.SKX_EXT_B(CHIPS)':
 'VSS'<967>: CDS_PINID='VSS(967)';
NODE_NAME     U5D1 V75
 '@BASEBOARD_FAB2_LIB.BASEBOARD_FAB2(SCH_1):PAGE40_I21@CHPSET_LIB.SKX_EXT_B(CHIPS)':
 'VSS'<968>: CDS_PINID='VSS(968)';
NODE_NAME     U5D1 V73
 '@BASEBOARD_FAB2_LIB.BASEBOARD_FAB2(SCH_1):PAGE40_I21@CHPSET_LIB.SKX_EXT_B(CHIPS)':
 'VSS'<969>: CDS_PINID='VSS(969)';
NODE_NAME     U5D1 V43
 '@BASEBOARD_FAB2_LIB.BASEBOARD_FAB2(SCH_1):PAGE40_I21@CHPSET_LIB.SKX_EXT_B(CHIPS)':
 'VSS'<970>: CDS_PINID='VSS(970)';
NODE_NAME     U5D1 V23
 '@BASEBOARD_FAB2_LIB.BASEBOARD_FAB2(SCH_1):PAGE40_I21@CHPSET_LIB.SKX_EXT_B(CHIPS)':
 'VSS'<971>: CDS_PINID='VSS(971)';
NODE_NAME     U5D1 V21
 '@BASEBOARD_FAB2_LIB.BASEBOARD_FAB2(SCH_1):PAGE40_I21@CHPSET_LIB.SKX_EXT_B(CHIPS)':
 'VSS'<972>: CDS_PINID='VSS(972)';
NODE_NAME     U5D1 V15
 '@BASEBOARD_FAB2_LIB.BASEBOARD_FAB2(SCH_1):PAGE40_I21@CHPSET_LIB.SKX_EXT_B(CHIPS)':
 'VSS'<973>: CDS_PINID='VSS(973)';
NODE_NAME     U5D1 V13
 '@BASEBOARD_FAB2_LIB.BASEBOARD_FAB2(SCH_1):PAGE40_I21@CHPSET_LIB.SKX_EXT_B(CHIPS)':
 'VSS'<974>: CDS_PINID='VSS(974)';
NODE_NAME     U5D1 V9
 '@BASEBOARD_FAB2_LIB.BASEBOARD_FAB2(SCH_1):PAGE40_I21@CHPSET_LIB.SKX_EXT_B(CHIPS)':
 'VSS'<975>: CDS_PINID='VSS(975)';
NODE_NAME     U5D1 V5
 '@BASEBOARD_FAB2_LIB.BASEBOARD_FAB2(SCH_1):PAGE40_I21@CHPSET_LIB.SKX_EXT_B(CHIPS)':
 'VSS'<976>: CDS_PINID='VSS(976)';
NODE_NAME     U5D1 V1
 '@BASEBOARD_FAB2_LIB.BASEBOARD_FAB2(SCH_1):PAGE40_I21@CHPSET_LIB.SKX_EXT_B(CHIPS)':
 'VSS'<977>: CDS_PINID='VSS(977)';
NODE_NAME     U5D1 U86
 '@BASEBOARD_FAB2_LIB.BASEBOARD_FAB2(SCH_1):PAGE40_I21@CHPSET_LIB.SKX_EXT_B(CHIPS)':
 'VSS'<978>: CDS_PINID='VSS(978)';
NODE_NAME     U5D1 U80
 '@BASEBOARD_FAB2_LIB.BASEBOARD_FAB2(SCH_1):PAGE40_I21@CHPSET_LIB.SKX_EXT_B(CHIPS)':
 'VSS'<979>: CDS_PINID='VSS(979)';
NODE_NAME     U5D1 U78
 '@BASEBOARD_FAB2_LIB.BASEBOARD_FAB2(SCH_1):PAGE40_I21@CHPSET_LIB.SKX_EXT_B(CHIPS)':
 'VSS'<980>: CDS_PINID='VSS(980)';
NODE_NAME     U5D1 U76
 '@BASEBOARD_FAB2_LIB.BASEBOARD_FAB2(SCH_1):PAGE40_I21@CHPSET_LIB.SKX_EXT_B(CHIPS)':
 'VSS'<981>: CDS_PINID='VSS(981)';
NODE_NAME     U5D1 U74
 '@BASEBOARD_FAB2_LIB.BASEBOARD_FAB2(SCH_1):PAGE40_I21@CHPSET_LIB.SKX_EXT_B(CHIPS)':
 'VSS'<982>: CDS_PINID='VSS(982)';
NODE_NAME     U5D1 U70
 '@BASEBOARD_FAB2_LIB.BASEBOARD_FAB2(SCH_1):PAGE40_I21@CHPSET_LIB.SKX_EXT_B(CHIPS)':
 'VSS'<983>: CDS_PINID='VSS(983)';
NODE_NAME     U5D1 U68
 '@BASEBOARD_FAB2_LIB.BASEBOARD_FAB2(SCH_1):PAGE40_I21@CHPSET_LIB.SKX_EXT_B(CHIPS)':
 'VSS'<984>: CDS_PINID='VSS(984)';
NODE_NAME     U5D1 U42
 '@BASEBOARD_FAB2_LIB.BASEBOARD_FAB2(SCH_1):PAGE40_I21@CHPSET_LIB.SKX_EXT_B(CHIPS)':
 'VSS'<985>: CDS_PINID='VSS(985)';
NODE_NAME     U5D1 U36
 '@BASEBOARD_FAB2_LIB.BASEBOARD_FAB2(SCH_1):PAGE40_I21@CHPSET_LIB.SKX_EXT_B(CHIPS)':
 'VSS'<986>: CDS_PINID='VSS(986)';
NODE_NAME     U5D1 U30
 '@BASEBOARD_FAB2_LIB.BASEBOARD_FAB2(SCH_1):PAGE40_I21@CHPSET_LIB.SKX_EXT_B(CHIPS)':
 'VSS'<987>: CDS_PINID='VSS(987)';
NODE_NAME     U5D1 U24
 '@BASEBOARD_FAB2_LIB.BASEBOARD_FAB2(SCH_1):PAGE40_I21@CHPSET_LIB.SKX_EXT_B(CHIPS)':
 'VSS'<988>: CDS_PINID='VSS(988)';
NODE_NAME     U5D1 U22
 '@BASEBOARD_FAB2_LIB.BASEBOARD_FAB2(SCH_1):PAGE40_I21@CHPSET_LIB.SKX_EXT_B(CHIPS)':
 'VSS'<989>: CDS_PINID='VSS(989)';
NODE_NAME     U5D1 U20
 '@BASEBOARD_FAB2_LIB.BASEBOARD_FAB2(SCH_1):PAGE40_I21@CHPSET_LIB.SKX_EXT_B(CHIPS)':
 'VSS'<990>: CDS_PINID='VSS(990)';
NODE_NAME     U5D1 U6
 '@BASEBOARD_FAB2_LIB.BASEBOARD_FAB2(SCH_1):PAGE40_I21@CHPSET_LIB.SKX_EXT_B(CHIPS)':
 'VSS'<991>: CDS_PINID='VSS(991)';
NODE_NAME     U5D1 U4
 '@BASEBOARD_FAB2_LIB.BASEBOARD_FAB2(SCH_1):PAGE40_I21@CHPSET_LIB.SKX_EXT_B(CHIPS)':
 'VSS'<992>: CDS_PINID='VSS(992)';
NODE_NAME     U5D1 U2
 '@BASEBOARD_FAB2_LIB.BASEBOARD_FAB2(SCH_1):PAGE40_I21@CHPSET_LIB.SKX_EXT_B(CHIPS)':
 'VSS'<993>: CDS_PINID='VSS(993)';
NODE_NAME     U5D1 T85
 '@BASEBOARD_FAB2_LIB.BASEBOARD_FAB2(SCH_1):PAGE40_I21@CHPSET_LIB.SKX_EXT_B(CHIPS)':
 'VSS'<994>: CDS_PINID='VSS(994)';
NODE_NAME     U5D1 T83
 '@BASEBOARD_FAB2_LIB.BASEBOARD_FAB2(SCH_1):PAGE40_I21@CHPSET_LIB.SKX_EXT_B(CHIPS)':
 'VSS'<995>: CDS_PINID='VSS(995)';
NODE_NAME     U5D1 T77
 '@BASEBOARD_FAB2_LIB.BASEBOARD_FAB2(SCH_1):PAGE40_I21@CHPSET_LIB.SKX_EXT_B(CHIPS)':
 'VSS'<996>: CDS_PINID='VSS(996)';
NODE_NAME     U5D1 T73
 '@BASEBOARD_FAB2_LIB.BASEBOARD_FAB2(SCH_1):PAGE40_I21@CHPSET_LIB.SKX_EXT_B(CHIPS)':
 'VSS'<997>: CDS_PINID='VSS(997)';
NODE_NAME     U5D1 T65
 '@BASEBOARD_FAB2_LIB.BASEBOARD_FAB2(SCH_1):PAGE40_I21@CHPSET_LIB.SKX_EXT_B(CHIPS)':
 'VSS'<998>: CDS_PINID='VSS(998)';
NODE_NAME     U5D1 T41
 '@BASEBOARD_FAB2_LIB.BASEBOARD_FAB2(SCH_1):PAGE40_I21@CHPSET_LIB.SKX_EXT_B(CHIPS)':
 'VSS'<999>: CDS_PINID='VSS(999)';
NODE_NAME     U5D1 T37
 '@BASEBOARD_FAB2_LIB.BASEBOARD_FAB2(SCH_1):PAGE40_I21@CHPSET_LIB.SKX_EXT_B(CHIPS)':
 'VSS'<1000>: CDS_PINID='VSS(1000)';
NODE_NAME     U5D1 T35
 '@BASEBOARD_FAB2_LIB.BASEBOARD_FAB2(SCH_1):PAGE40_I21@CHPSET_LIB.SKX_EXT_B(CHIPS)':
 'VSS'<1001>: CDS_PINID='VSS(1001)';
NODE_NAME     U5D1 T31
 '@BASEBOARD_FAB2_LIB.BASEBOARD_FAB2(SCH_1):PAGE40_I21@CHPSET_LIB.SKX_EXT_B(CHIPS)':
 'VSS'<1002>: CDS_PINID='VSS(1002)';
NODE_NAME     U5D1 T29
 '@BASEBOARD_FAB2_LIB.BASEBOARD_FAB2(SCH_1):PAGE40_I21@CHPSET_LIB.SKX_EXT_B(CHIPS)':
 'VSS'<1003>: CDS_PINID='VSS(1003)';
NODE_NAME     U5D1 T25
 '@BASEBOARD_FAB2_LIB.BASEBOARD_FAB2(SCH_1):PAGE40_I21@CHPSET_LIB.SKX_EXT_B(CHIPS)':
 'VSS'<1004>: CDS_PINID='VSS(1004)';
NODE_NAME     U5D1 T17
 '@BASEBOARD_FAB2_LIB.BASEBOARD_FAB2(SCH_1):PAGE40_I21@CHPSET_LIB.SKX_EXT_B(CHIPS)':
 'VSS'<1005>: CDS_PINID='VSS(1005)';
NODE_NAME     U5D1 T13
 '@BASEBOARD_FAB2_LIB.BASEBOARD_FAB2(SCH_1):PAGE40_I21@CHPSET_LIB.SKX_EXT_B(CHIPS)':
 'VSS'<1006>: CDS_PINID='VSS(1006)';
NODE_NAME     U5D1 R86
 '@BASEBOARD_FAB2_LIB.BASEBOARD_FAB2(SCH_1):PAGE40_I21@CHPSET_LIB.SKX_EXT_B(CHIPS)':
 'VSS'<1007>: CDS_PINID='VSS(1007)';
NODE_NAME     U5D1 R78
 '@BASEBOARD_FAB2_LIB.BASEBOARD_FAB2(SCH_1):PAGE40_I21@CHPSET_LIB.SKX_EXT_B(CHIPS)':
 'VSS'<1008>: CDS_PINID='VSS(1008)';
NODE_NAME     U5D1 R72
 '@BASEBOARD_FAB2_LIB.BASEBOARD_FAB2(SCH_1):PAGE40_I21@CHPSET_LIB.SKX_EXT_B(CHIPS)':
 'VSS'<1009>: CDS_PINID='VSS(1009)';
NODE_NAME     U5D1 R68
 '@BASEBOARD_FAB2_LIB.BASEBOARD_FAB2(SCH_1):PAGE40_I21@CHPSET_LIB.SKX_EXT_B(CHIPS)':
 'VSS'<1010>: CDS_PINID='VSS(1010)';
NODE_NAME     U5D1 R40
 '@BASEBOARD_FAB2_LIB.BASEBOARD_FAB2(SCH_1):PAGE40_I21@CHPSET_LIB.SKX_EXT_B(CHIPS)':
 'VSS'<1011>: CDS_PINID='VSS(1011)';
NODE_NAME     U5D1 R38
 '@BASEBOARD_FAB2_LIB.BASEBOARD_FAB2(SCH_1):PAGE40_I21@CHPSET_LIB.SKX_EXT_B(CHIPS)':
 'VSS'<1012>: CDS_PINID='VSS(1012)';
NODE_NAME     U5D1 R34
 '@BASEBOARD_FAB2_LIB.BASEBOARD_FAB2(SCH_1):PAGE40_I21@CHPSET_LIB.SKX_EXT_B(CHIPS)':
 'VSS'<1013>: CDS_PINID='VSS(1013)';
NODE_NAME     U5D1 R32
 '@BASEBOARD_FAB2_LIB.BASEBOARD_FAB2(SCH_1):PAGE40_I21@CHPSET_LIB.SKX_EXT_B(CHIPS)':
 'VSS'<1014>: CDS_PINID='VSS(1014)';
NODE_NAME     U5D1 R28
 '@BASEBOARD_FAB2_LIB.BASEBOARD_FAB2(SCH_1):PAGE40_I21@CHPSET_LIB.SKX_EXT_B(CHIPS)':
 'VSS'<1015>: CDS_PINID='VSS(1015)';
NODE_NAME     U5D1 R26
 '@BASEBOARD_FAB2_LIB.BASEBOARD_FAB2(SCH_1):PAGE40_I21@CHPSET_LIB.SKX_EXT_B(CHIPS)':
 'VSS'<1016>: CDS_PINID='VSS(1016)';
NODE_NAME     U5D1 R22
 '@BASEBOARD_FAB2_LIB.BASEBOARD_FAB2(SCH_1):PAGE40_I21@CHPSET_LIB.SKX_EXT_B(CHIPS)':
 'VSS'<1017>: CDS_PINID='VSS(1017)';
NODE_NAME     U5D1 R4
 '@BASEBOARD_FAB2_LIB.BASEBOARD_FAB2(SCH_1):PAGE40_I21@CHPSET_LIB.SKX_EXT_B(CHIPS)':
 'VSS'<1018>: CDS_PINID='VSS(1018)';
NODE_NAME     U5D1 R2
 '@BASEBOARD_FAB2_LIB.BASEBOARD_FAB2(SCH_1):PAGE40_I21@CHPSET_LIB.SKX_EXT_B(CHIPS)':
 'VSS'<1019>: CDS_PINID='VSS(1019)';
NODE_NAME     U5D1 R18
 '@BASEBOARD_FAB2_LIB.BASEBOARD_FAB2(SCH_1):PAGE40_I21@CHPSET_LIB.SKX_EXT_B(CHIPS)':
 'VSS'<1020>: CDS_PINID='VSS(1020)';
NODE_NAME     U5D1 R14
 '@BASEBOARD_FAB2_LIB.BASEBOARD_FAB2(SCH_1):PAGE40_I21@CHPSET_LIB.SKX_EXT_B(CHIPS)':
 'VSS'<1021>: CDS_PINID='VSS(1021)';
NODE_NAME     U5D1 P83
 '@BASEBOARD_FAB2_LIB.BASEBOARD_FAB2(SCH_1):PAGE40_I21@CHPSET_LIB.SKX_EXT_B(CHIPS)':
 'VSS'<1022>: CDS_PINID='VSS(1022)';
NODE_NAME     U5D1 P81
 '@BASEBOARD_FAB2_LIB.BASEBOARD_FAB2(SCH_1):PAGE40_I21@CHPSET_LIB.SKX_EXT_B(CHIPS)':
 'VSS'<1023>: CDS_PINID='VSS(1023)';
NODE_NAME     U5D1 P71
 '@BASEBOARD_FAB2_LIB.BASEBOARD_FAB2(SCH_1):PAGE40_I21@CHPSET_LIB.SKX_EXT_B(CHIPS)':
 'VSS'<1024>: CDS_PINID='VSS(1024)';
NODE_NAME     U5D1 P69
 '@BASEBOARD_FAB2_LIB.BASEBOARD_FAB2(SCH_1):PAGE40_I21@CHPSET_LIB.SKX_EXT_B(CHIPS)':
 'VSS'<1025>: CDS_PINID='VSS(1025)';
NODE_NAME     U5D1 P67
 '@BASEBOARD_FAB2_LIB.BASEBOARD_FAB2(SCH_1):PAGE40_I21@CHPSET_LIB.SKX_EXT_B(CHIPS)':
 'VSS'<1026>: CDS_PINID='VSS(1026)';
NODE_NAME     U5D1 P39
 '@BASEBOARD_FAB2_LIB.BASEBOARD_FAB2(SCH_1):PAGE40_I21@CHPSET_LIB.SKX_EXT_B(CHIPS)':
 'VSS'<1027>: CDS_PINID='VSS(1027)';
NODE_NAME     U5D1 P33
 '@BASEBOARD_FAB2_LIB.BASEBOARD_FAB2(SCH_1):PAGE40_I21@CHPSET_LIB.SKX_EXT_B(CHIPS)':
 'VSS'<1028>: CDS_PINID='VSS(1028)';
NODE_NAME     U5D1 P27
 '@BASEBOARD_FAB2_LIB.BASEBOARD_FAB2(SCH_1):PAGE40_I21@CHPSET_LIB.SKX_EXT_B(CHIPS)':
 'VSS'<1029>: CDS_PINID='VSS(1029)';
NODE_NAME     U5D1 P15
 '@BASEBOARD_FAB2_LIB.BASEBOARD_FAB2(SCH_1):PAGE40_I21@CHPSET_LIB.SKX_EXT_B(CHIPS)':
 'VSS'<1030>: CDS_PINID='VSS(1030)';
NODE_NAME     U5D1 P11
 '@BASEBOARD_FAB2_LIB.BASEBOARD_FAB2(SCH_1):PAGE40_I21@CHPSET_LIB.SKX_EXT_B(CHIPS)':
 'VSS'<1031>: CDS_PINID='VSS(1031)';
NODE_NAME     U5D1 N8
 '@BASEBOARD_FAB2_LIB.BASEBOARD_FAB2(SCH_1):PAGE40_I21@CHPSET_LIB.SKX_EXT_B(CHIPS)':
 'VSS'<1032>: CDS_PINID='VSS(1032)';
NODE_NAME     U5D1 N4
 '@BASEBOARD_FAB2_LIB.BASEBOARD_FAB2(SCH_1):PAGE40_I21@CHPSET_LIB.SKX_EXT_B(CHIPS)':
 'VSS'<1033>: CDS_PINID='VSS(1033)';
NODE_NAME     U5D1 N78
 '@BASEBOARD_FAB2_LIB.BASEBOARD_FAB2(SCH_1):PAGE40_I21@CHPSET_LIB.SKX_EXT_B(CHIPS)':
 'VSS'<1034>: CDS_PINID='VSS(1034)';
NODE_NAME     U5D1 N76
 '@BASEBOARD_FAB2_LIB.BASEBOARD_FAB2(SCH_1):PAGE40_I21@CHPSET_LIB.SKX_EXT_B(CHIPS)':
 'VSS'<1035>: CDS_PINID='VSS(1035)';
NODE_NAME     U5D1 N74
 '@BASEBOARD_FAB2_LIB.BASEBOARD_FAB2(SCH_1):PAGE40_I21@CHPSET_LIB.SKX_EXT_B(CHIPS)':
 'VSS'<1036>: CDS_PINID='VSS(1036)';
NODE_NAME     U5D1 N72
 '@BASEBOARD_FAB2_LIB.BASEBOARD_FAB2(SCH_1):PAGE40_I21@CHPSET_LIB.SKX_EXT_B(CHIPS)':
 'VSS'<1037>: CDS_PINID='VSS(1037)';
NODE_NAME     U5D1 N70
 '@BASEBOARD_FAB2_LIB.BASEBOARD_FAB2(SCH_1):PAGE40_I21@CHPSET_LIB.SKX_EXT_B(CHIPS)':
 'VSS'<1038>: CDS_PINID='VSS(1038)';
NODE_NAME     U5D1 N66
 '@BASEBOARD_FAB2_LIB.BASEBOARD_FAB2(SCH_1):PAGE40_I21@CHPSET_LIB.SKX_EXT_B(CHIPS)':
 'VSS'<1039>: CDS_PINID='VSS(1039)';
NODE_NAME     U5D1 N6
 '@BASEBOARD_FAB2_LIB.BASEBOARD_FAB2(SCH_1):PAGE40_I21@CHPSET_LIB.SKX_EXT_B(CHIPS)':
 'VSS'<1040>: CDS_PINID='VSS(1040)';
NODE_NAME     U5D1 N22
 '@BASEBOARD_FAB2_LIB.BASEBOARD_FAB2(SCH_1):PAGE40_I21@CHPSET_LIB.SKX_EXT_B(CHIPS)':
 'VSS'<1041>: CDS_PINID='VSS(1041)';
NODE_NAME     U5D1 N20
 '@BASEBOARD_FAB2_LIB.BASEBOARD_FAB2(SCH_1):PAGE40_I21@CHPSET_LIB.SKX_EXT_B(CHIPS)':
 'VSS'<1042>: CDS_PINID='VSS(1042)';
NODE_NAME     U5D1 DM19
 '@BASEBOARD_FAB2_LIB.BASEBOARD_FAB2(SCH_1):PAGE40_I21@CHPSET_LIB.SKX_EXT_B(CHIPS)':
 'VSS'<1043>: CDS_PINID='VSS(1043)';
NODE_NAME     U5D1 M85
 '@BASEBOARD_FAB2_LIB.BASEBOARD_FAB2(SCH_1):PAGE40_I21@CHPSET_LIB.SKX_EXT_B(CHIPS)':
 'VSS'<1044>: CDS_PINID='VSS(1044)';
NODE_NAME     U5D1 M83
 '@BASEBOARD_FAB2_LIB.BASEBOARD_FAB2(SCH_1):PAGE40_I21@CHPSET_LIB.SKX_EXT_B(CHIPS)':
 'VSS'<1045>: CDS_PINID='VSS(1045)';
NODE_NAME     U5D1 M79
 '@BASEBOARD_FAB2_LIB.BASEBOARD_FAB2(SCH_1):PAGE40_I21@CHPSET_LIB.SKX_EXT_B(CHIPS)':
 'VSS'<1046>: CDS_PINID='VSS(1046)';
NODE_NAME     U5D1 M71
 '@BASEBOARD_FAB2_LIB.BASEBOARD_FAB2(SCH_1):PAGE40_I21@CHPSET_LIB.SKX_EXT_B(CHIPS)':
 'VSS'<1047>: CDS_PINID='VSS(1047)';
NODE_NAME     U5D1 M65
 '@BASEBOARD_FAB2_LIB.BASEBOARD_FAB2(SCH_1):PAGE40_I21@CHPSET_LIB.SKX_EXT_B(CHIPS)':
 'VSS'<1048>: CDS_PINID='VSS(1048)';
NODE_NAME     U5D1 M43
 '@BASEBOARD_FAB2_LIB.BASEBOARD_FAB2(SCH_1):PAGE40_I21@CHPSET_LIB.SKX_EXT_B(CHIPS)':
 'VSS'<1049>: CDS_PINID='VSS(1049)';
NODE_NAME     U5D1 M41
 '@BASEBOARD_FAB2_LIB.BASEBOARD_FAB2(SCH_1):PAGE40_I21@CHPSET_LIB.SKX_EXT_B(CHIPS)':
 'VSS'<1050>: CDS_PINID='VSS(1050)';
NODE_NAME     U5D1 M39
 '@BASEBOARD_FAB2_LIB.BASEBOARD_FAB2(SCH_1):PAGE40_I21@CHPSET_LIB.SKX_EXT_B(CHIPS)':
 'VSS'<1051>: CDS_PINID='VSS(1051)';
NODE_NAME     U5D1 M37
 '@BASEBOARD_FAB2_LIB.BASEBOARD_FAB2(SCH_1):PAGE40_I21@CHPSET_LIB.SKX_EXT_B(CHIPS)':
 'VSS'<1052>: CDS_PINID='VSS(1052)';
NODE_NAME     U5D1 M35
 '@BASEBOARD_FAB2_LIB.BASEBOARD_FAB2(SCH_1):PAGE40_I21@CHPSET_LIB.SKX_EXT_B(CHIPS)':
 'VSS'<1053>: CDS_PINID='VSS(1053)';
NODE_NAME     U5D1 M33
 '@BASEBOARD_FAB2_LIB.BASEBOARD_FAB2(SCH_1):PAGE40_I21@CHPSET_LIB.SKX_EXT_B(CHIPS)':
 'VSS'<1054>: CDS_PINID='VSS(1054)';
NODE_NAME     U5D1 M31
 '@BASEBOARD_FAB2_LIB.BASEBOARD_FAB2(SCH_1):PAGE40_I21@CHPSET_LIB.SKX_EXT_B(CHIPS)':
 'VSS'<1055>: CDS_PINID='VSS(1055)';
NODE_NAME     U5D1 M29
 '@BASEBOARD_FAB2_LIB.BASEBOARD_FAB2(SCH_1):PAGE40_I21@CHPSET_LIB.SKX_EXT_B(CHIPS)':
 'VSS'<1056>: CDS_PINID='VSS(1056)';
NODE_NAME     U5D1 M27
 '@BASEBOARD_FAB2_LIB.BASEBOARD_FAB2(SCH_1):PAGE40_I21@CHPSET_LIB.SKX_EXT_B(CHIPS)':
 'VSS'<1057>: CDS_PINID='VSS(1057)';
NODE_NAME     U5D1 M25
 '@BASEBOARD_FAB2_LIB.BASEBOARD_FAB2(SCH_1):PAGE40_I21@CHPSET_LIB.SKX_EXT_B(CHIPS)':
 'VSS'<1058>: CDS_PINID='VSS(1058)';
NODE_NAME     U5D1 M23
 '@BASEBOARD_FAB2_LIB.BASEBOARD_FAB2(SCH_1):PAGE40_I21@CHPSET_LIB.SKX_EXT_B(CHIPS)':
 'VSS'<1059>: CDS_PINID='VSS(1059)';
NODE_NAME     U5D1 M19
 '@BASEBOARD_FAB2_LIB.BASEBOARD_FAB2(SCH_1):PAGE40_I21@CHPSET_LIB.SKX_EXT_B(CHIPS)':
 'VSS'<1060>: CDS_PINID='VSS(1060)';
NODE_NAME     U5D1 M17
 '@BASEBOARD_FAB2_LIB.BASEBOARD_FAB2(SCH_1):PAGE40_I21@CHPSET_LIB.SKX_EXT_B(CHIPS)':
 'VSS'<1061>: CDS_PINID='VSS(1061)';
NODE_NAME     U5D1 M15
 '@BASEBOARD_FAB2_LIB.BASEBOARD_FAB2(SCH_1):PAGE40_I21@CHPSET_LIB.SKX_EXT_B(CHIPS)':
 'VSS'<1062>: CDS_PINID='VSS(1062)';
NODE_NAME     U5D1 CT7
 '@BASEBOARD_FAB2_LIB.BASEBOARD_FAB2(SCH_1):PAGE40_I21@CHPSET_LIB.SKX_EXT_B(CHIPS)':
 'VSS'<1063>: CDS_PINID='VSS(1063)';
NODE_NAME     U5D1 BT9
 '@BASEBOARD_FAB2_LIB.BASEBOARD_FAB2(SCH_1):PAGE40_I21@CHPSET_LIB.SKX_EXT_B(CHIPS)':
 'VSS'<1064>: CDS_PINID='VSS(1064)';
NODE_NAME     U5D1 L82
 '@BASEBOARD_FAB2_LIB.BASEBOARD_FAB2(SCH_1):PAGE40_I21@CHPSET_LIB.SKX_EXT_B(CHIPS)':
 'VSS'<1065>: CDS_PINID='VSS(1065)';
NODE_NAME     U5D1 L80
 '@BASEBOARD_FAB2_LIB.BASEBOARD_FAB2(SCH_1):PAGE40_I21@CHPSET_LIB.SKX_EXT_B(CHIPS)':
 'VSS'<1066>: CDS_PINID='VSS(1066)';
NODE_NAME     U5D1 L78
 '@BASEBOARD_FAB2_LIB.BASEBOARD_FAB2(SCH_1):PAGE40_I21@CHPSET_LIB.SKX_EXT_B(CHIPS)':
 'VSS'<1067>: CDS_PINID='VSS(1067)';
NODE_NAME     U5D1 L72
 '@BASEBOARD_FAB2_LIB.BASEBOARD_FAB2(SCH_1):PAGE40_I21@CHPSET_LIB.SKX_EXT_B(CHIPS)':
 'VSS'<1068>: CDS_PINID='VSS(1068)';
NODE_NAME     U5D1 L22
 '@BASEBOARD_FAB2_LIB.BASEBOARD_FAB2(SCH_1):PAGE40_I21@CHPSET_LIB.SKX_EXT_B(CHIPS)':
 'VSS'<1069>: CDS_PINID='VSS(1069)';
NODE_NAME     U5D1 L20
 '@BASEBOARD_FAB2_LIB.BASEBOARD_FAB2(SCH_1):PAGE40_I21@CHPSET_LIB.SKX_EXT_B(CHIPS)':
 'VSS'<1070>: CDS_PINID='VSS(1070)';
NODE_NAME     U5D1 L6
 '@BASEBOARD_FAB2_LIB.BASEBOARD_FAB2(SCH_1):PAGE40_I21@CHPSET_LIB.SKX_EXT_B(CHIPS)':
 'VSS'<1071>: CDS_PINID='VSS(1071)';
NODE_NAME     U5D1 L2
 '@BASEBOARD_FAB2_LIB.BASEBOARD_FAB2(SCH_1):PAGE40_I21@CHPSET_LIB.SKX_EXT_B(CHIPS)':
 'VSS'<1072>: CDS_PINID='VSS(1072)';
NODE_NAME     U5D1 L10
 '@BASEBOARD_FAB2_LIB.BASEBOARD_FAB2(SCH_1):PAGE40_I21@CHPSET_LIB.SKX_EXT_B(CHIPS)':
 'VSS'<1073>: CDS_PINID='VSS(1073)';
NODE_NAME     U5D1 K85
 '@BASEBOARD_FAB2_LIB.BASEBOARD_FAB2(SCH_1):PAGE40_I21@CHPSET_LIB.SKX_EXT_B(CHIPS)':
 'VSS'<1074>: CDS_PINID='VSS(1074)';
NODE_NAME     U5D1 K83
 '@BASEBOARD_FAB2_LIB.BASEBOARD_FAB2(SCH_1):PAGE40_I21@CHPSET_LIB.SKX_EXT_B(CHIPS)':
 'VSS'<1075>: CDS_PINID='VSS(1075)';
NODE_NAME     U5D1 K81
 '@BASEBOARD_FAB2_LIB.BASEBOARD_FAB2(SCH_1):PAGE40_I21@CHPSET_LIB.SKX_EXT_B(CHIPS)':
 'VSS'<1076>: CDS_PINID='VSS(1076)';
NODE_NAME     U5D1 K77
 '@BASEBOARD_FAB2_LIB.BASEBOARD_FAB2(SCH_1):PAGE40_I21@CHPSET_LIB.SKX_EXT_B(CHIPS)':
 'VSS'<1077>: CDS_PINID='VSS(1077)';
NODE_NAME     U5D1 K73
 '@BASEBOARD_FAB2_LIB.BASEBOARD_FAB2(SCH_1):PAGE40_I21@CHPSET_LIB.SKX_EXT_B(CHIPS)':
 'VSS'<1078>: CDS_PINID='VSS(1078)';
NODE_NAME     U5D1 K71
 '@BASEBOARD_FAB2_LIB.BASEBOARD_FAB2(SCH_1):PAGE40_I21@CHPSET_LIB.SKX_EXT_B(CHIPS)':
 'VSS'<1079>: CDS_PINID='VSS(1079)';
NODE_NAME     U5D1 K69
 '@BASEBOARD_FAB2_LIB.BASEBOARD_FAB2(SCH_1):PAGE40_I21@CHPSET_LIB.SKX_EXT_B(CHIPS)':
 'VSS'<1080>: CDS_PINID='VSS(1080)';
NODE_NAME     U5D1 K67
 '@BASEBOARD_FAB2_LIB.BASEBOARD_FAB2(SCH_1):PAGE40_I21@CHPSET_LIB.SKX_EXT_B(CHIPS)':
 'VSS'<1081>: CDS_PINID='VSS(1081)';
NODE_NAME     U5D1 K65
 '@BASEBOARD_FAB2_LIB.BASEBOARD_FAB2(SCH_1):PAGE40_I21@CHPSET_LIB.SKX_EXT_B(CHIPS)':
 'VSS'<1082>: CDS_PINID='VSS(1082)';
NODE_NAME     U5D1 K39
 '@BASEBOARD_FAB2_LIB.BASEBOARD_FAB2(SCH_1):PAGE40_I21@CHPSET_LIB.SKX_EXT_B(CHIPS)':
 'VSS'<1083>: CDS_PINID='VSS(1083)';
NODE_NAME     U5D1 K33
 '@BASEBOARD_FAB2_LIB.BASEBOARD_FAB2(SCH_1):PAGE40_I21@CHPSET_LIB.SKX_EXT_B(CHIPS)':
 'VSS'<1084>: CDS_PINID='VSS(1084)';
NODE_NAME     U5D1 K27
 '@BASEBOARD_FAB2_LIB.BASEBOARD_FAB2(SCH_1):PAGE40_I21@CHPSET_LIB.SKX_EXT_B(CHIPS)':
 'VSS'<1085>: CDS_PINID='VSS(1085)';
NODE_NAME     U5D1 DB7
 '@BASEBOARD_FAB2_LIB.BASEBOARD_FAB2(SCH_1):PAGE40_I21@CHPSET_LIB.SKX_EXT_B(CHIPS)':
 'VSS'<1086>: CDS_PINID='VSS(1086)';
NODE_NAME     U5D1 K17
 '@BASEBOARD_FAB2_LIB.BASEBOARD_FAB2(SCH_1):PAGE40_I21@CHPSET_LIB.SKX_EXT_B(CHIPS)':
 'VSS'<1087>: CDS_PINID='VSS(1087)';
NODE_NAME     U5D1 K13
 '@BASEBOARD_FAB2_LIB.BASEBOARD_FAB2(SCH_1):PAGE40_I21@CHPSET_LIB.SKX_EXT_B(CHIPS)':
 'VSS'<1088>: CDS_PINID='VSS(1088)';
NODE_NAME     U5D1 K11
 '@BASEBOARD_FAB2_LIB.BASEBOARD_FAB2(SCH_1):PAGE40_I21@CHPSET_LIB.SKX_EXT_B(CHIPS)':
 'VSS'<1089>: CDS_PINID='VSS(1089)';
NODE_NAME     U5D1 K1
 '@BASEBOARD_FAB2_LIB.BASEBOARD_FAB2(SCH_1):PAGE40_I21@CHPSET_LIB.SKX_EXT_B(CHIPS)':
 'VSS'<1090>: CDS_PINID='VSS(1090)';
NODE_NAME     U5D1 J84
 '@BASEBOARD_FAB2_LIB.BASEBOARD_FAB2(SCH_1):PAGE40_I21@CHPSET_LIB.SKX_EXT_B(CHIPS)':
 'VSS'<1091>: CDS_PINID='VSS(1091)';
NODE_NAME     U5D1 J82
 '@BASEBOARD_FAB2_LIB.BASEBOARD_FAB2(SCH_1):PAGE40_I21@CHPSET_LIB.SKX_EXT_B(CHIPS)':
 'VSS'<1092>: CDS_PINID='VSS(1092)';
NODE_NAME     U5D1 J76
 '@BASEBOARD_FAB2_LIB.BASEBOARD_FAB2(SCH_1):PAGE40_I21@CHPSET_LIB.SKX_EXT_B(CHIPS)':
 'VSS'<1093>: CDS_PINID='VSS(1093)';
NODE_NAME     U5D1 AL68
 '@BASEBOARD_FAB2_LIB.BASEBOARD_FAB2(SCH_1):PAGE40_I22@CHPSET_LIB.SKX_EXT_B(CHIPS)':
 'VSS'<774>: CDS_PINID='VSS(774)';
NODE_NAME     U5D1 AL64
 '@BASEBOARD_FAB2_LIB.BASEBOARD_FAB2(SCH_1):PAGE40_I22@CHPSET_LIB.SKX_EXT_B(CHIPS)':
 'VSS'<775>: CDS_PINID='VSS(775)';
NODE_NAME     U5D1 AL56
 '@BASEBOARD_FAB2_LIB.BASEBOARD_FAB2(SCH_1):PAGE40_I22@CHPSET_LIB.SKX_EXT_B(CHIPS)':
 'VSS'<776>: CDS_PINID='VSS(776)';
NODE_NAME     U5D1 AL32
 '@BASEBOARD_FAB2_LIB.BASEBOARD_FAB2(SCH_1):PAGE40_I22@CHPSET_LIB.SKX_EXT_B(CHIPS)':
 'VSS'<777>: CDS_PINID='VSS(777)';
NODE_NAME     U5D1 AL30
 '@BASEBOARD_FAB2_LIB.BASEBOARD_FAB2(SCH_1):PAGE40_I22@CHPSET_LIB.SKX_EXT_B(CHIPS)':
 'VSS'<778>: CDS_PINID='VSS(778)';
NODE_NAME     U5D1 AL24
 '@BASEBOARD_FAB2_LIB.BASEBOARD_FAB2(SCH_1):PAGE40_I22@CHPSET_LIB.SKX_EXT_B(CHIPS)':
 'VSS'<779>: CDS_PINID='VSS(779)';
NODE_NAME     U5D1 AL10
 '@BASEBOARD_FAB2_LIB.BASEBOARD_FAB2(SCH_1):PAGE40_I22@CHPSET_LIB.SKX_EXT_B(CHIPS)':
 'VSS'<780>: CDS_PINID='VSS(780)';
NODE_NAME     U5D1 AL4
 '@BASEBOARD_FAB2_LIB.BASEBOARD_FAB2(SCH_1):PAGE40_I22@CHPSET_LIB.SKX_EXT_B(CHIPS)':
 'VSS'<781>: CDS_PINID='VSS(781)';
NODE_NAME     U5D1 AK85
 '@BASEBOARD_FAB2_LIB.BASEBOARD_FAB2(SCH_1):PAGE40_I22@CHPSET_LIB.SKX_EXT_B(CHIPS)':
 'VSS'<782>: CDS_PINID='VSS(782)';
NODE_NAME     U5D1 AK83
 '@BASEBOARD_FAB2_LIB.BASEBOARD_FAB2(SCH_1):PAGE40_I22@CHPSET_LIB.SKX_EXT_B(CHIPS)':
 'VSS'<783>: CDS_PINID='VSS(783)';
NODE_NAME     U5D1 AK81
 '@BASEBOARD_FAB2_LIB.BASEBOARD_FAB2(SCH_1):PAGE40_I22@CHPSET_LIB.SKX_EXT_B(CHIPS)':
 'VSS'<784>: CDS_PINID='VSS(784)';
NODE_NAME     U5D1 AK79
 '@BASEBOARD_FAB2_LIB.BASEBOARD_FAB2(SCH_1):PAGE40_I22@CHPSET_LIB.SKX_EXT_B(CHIPS)':
 'VSS'<785>: CDS_PINID='VSS(785)';
NODE_NAME     U5D1 AK73
 '@BASEBOARD_FAB2_LIB.BASEBOARD_FAB2(SCH_1):PAGE40_I22@CHPSET_LIB.SKX_EXT_B(CHIPS)':
 'VSS'<786>: CDS_PINID='VSS(786)';
NODE_NAME     U5D1 AK67
 '@BASEBOARD_FAB2_LIB.BASEBOARD_FAB2(SCH_1):PAGE40_I22@CHPSET_LIB.SKX_EXT_B(CHIPS)':
 'VSS'<787>: CDS_PINID='VSS(787)';
NODE_NAME     U5D1 AK65
 '@BASEBOARD_FAB2_LIB.BASEBOARD_FAB2(SCH_1):PAGE40_I22@CHPSET_LIB.SKX_EXT_B(CHIPS)':
 'VSS'<788>: CDS_PINID='VSS(788)';
NODE_NAME     U5D1 AK55
 '@BASEBOARD_FAB2_LIB.BASEBOARD_FAB2(SCH_1):PAGE40_I22@CHPSET_LIB.SKX_EXT_B(CHIPS)':
 'VSS'<789>: CDS_PINID='VSS(789)';
NODE_NAME     U5D1 AK33
 '@BASEBOARD_FAB2_LIB.BASEBOARD_FAB2(SCH_1):PAGE40_I22@CHPSET_LIB.SKX_EXT_B(CHIPS)':
 'VSS'<790>: CDS_PINID='VSS(790)';
NODE_NAME     U5D1 AK31
 '@BASEBOARD_FAB2_LIB.BASEBOARD_FAB2(SCH_1):PAGE40_I22@CHPSET_LIB.SKX_EXT_B(CHIPS)':
 'VSS'<791>: CDS_PINID='VSS(791)';
NODE_NAME     U5D1 AK29
 '@BASEBOARD_FAB2_LIB.BASEBOARD_FAB2(SCH_1):PAGE40_I22@CHPSET_LIB.SKX_EXT_B(CHIPS)':
 'VSS'<792>: CDS_PINID='VSS(792)';
NODE_NAME     U5D1 AK25
 '@BASEBOARD_FAB2_LIB.BASEBOARD_FAB2(SCH_1):PAGE40_I22@CHPSET_LIB.SKX_EXT_B(CHIPS)':
 'VSS'<793>: CDS_PINID='VSS(793)';
NODE_NAME     U5D1 AK23
 '@BASEBOARD_FAB2_LIB.BASEBOARD_FAB2(SCH_1):PAGE40_I22@CHPSET_LIB.SKX_EXT_B(CHIPS)':
 'VSS'<794>: CDS_PINID='VSS(794)';
NODE_NAME     U5D1 AK19
 '@BASEBOARD_FAB2_LIB.BASEBOARD_FAB2(SCH_1):PAGE40_I22@CHPSET_LIB.SKX_EXT_B(CHIPS)':
 'VSS'<795>: CDS_PINID='VSS(795)';
NODE_NAME     U5D1 AK13
 '@BASEBOARD_FAB2_LIB.BASEBOARD_FAB2(SCH_1):PAGE40_I22@CHPSET_LIB.SKX_EXT_B(CHIPS)':
 'VSS'<796>: CDS_PINID='VSS(796)';
NODE_NAME     U5D1 AK9
 '@BASEBOARD_FAB2_LIB.BASEBOARD_FAB2(SCH_1):PAGE40_I22@CHPSET_LIB.SKX_EXT_B(CHIPS)':
 'VSS'<797>: CDS_PINID='VSS(797)';
NODE_NAME     U5D1 AJ86
 '@BASEBOARD_FAB2_LIB.BASEBOARD_FAB2(SCH_1):PAGE40_I22@CHPSET_LIB.SKX_EXT_B(CHIPS)':
 'VSS'<798>: CDS_PINID='VSS(798)';
NODE_NAME     U5D1 AJ82
 '@BASEBOARD_FAB2_LIB.BASEBOARD_FAB2(SCH_1):PAGE40_I22@CHPSET_LIB.SKX_EXT_B(CHIPS)':
 'VSS'<799>: CDS_PINID='VSS(799)';
NODE_NAME     U5D1 AJ78
 '@BASEBOARD_FAB2_LIB.BASEBOARD_FAB2(SCH_1):PAGE40_I22@CHPSET_LIB.SKX_EXT_B(CHIPS)':
 'VSS'<800>: CDS_PINID='VSS(800)';
NODE_NAME     U5D1 AJ74
 '@BASEBOARD_FAB2_LIB.BASEBOARD_FAB2(SCH_1):PAGE40_I22@CHPSET_LIB.SKX_EXT_B(CHIPS)':
 'VSS'<801>: CDS_PINID='VSS(801)';
NODE_NAME     U5D1 AJ68
 '@BASEBOARD_FAB2_LIB.BASEBOARD_FAB2(SCH_1):PAGE40_I22@CHPSET_LIB.SKX_EXT_B(CHIPS)':
 'VSS'<802>: CDS_PINID='VSS(802)';
NODE_NAME     U5D1 AJ66
 '@BASEBOARD_FAB2_LIB.BASEBOARD_FAB2(SCH_1):PAGE40_I22@CHPSET_LIB.SKX_EXT_B(CHIPS)':
 'VSS'<803>: CDS_PINID='VSS(803)';
NODE_NAME     U5D1 AJ54
 '@BASEBOARD_FAB2_LIB.BASEBOARD_FAB2(SCH_1):PAGE40_I22@CHPSET_LIB.SKX_EXT_B(CHIPS)':
 'VSS'<804>: CDS_PINID='VSS(804)';
NODE_NAME     U5D1 AJ52
 '@BASEBOARD_FAB2_LIB.BASEBOARD_FAB2(SCH_1):PAGE40_I22@CHPSET_LIB.SKX_EXT_B(CHIPS)':
 'VSS'<805>: CDS_PINID='VSS(805)';
NODE_NAME     U5D1 AJ50
 '@BASEBOARD_FAB2_LIB.BASEBOARD_FAB2(SCH_1):PAGE40_I22@CHPSET_LIB.SKX_EXT_B(CHIPS)':
 'VSS'<806>: CDS_PINID='VSS(806)';
NODE_NAME     U5D1 AJ48
 '@BASEBOARD_FAB2_LIB.BASEBOARD_FAB2(SCH_1):PAGE40_I22@CHPSET_LIB.SKX_EXT_B(CHIPS)':
 'VSS'<807>: CDS_PINID='VSS(807)';
NODE_NAME     U5D1 AJ46
 '@BASEBOARD_FAB2_LIB.BASEBOARD_FAB2(SCH_1):PAGE40_I22@CHPSET_LIB.SKX_EXT_B(CHIPS)':
 'VSS'<808>: CDS_PINID='VSS(808)';
NODE_NAME     U5D1 AJ34
 '@BASEBOARD_FAB2_LIB.BASEBOARD_FAB2(SCH_1):PAGE40_I22@CHPSET_LIB.SKX_EXT_B(CHIPS)':
 'VSS'<809>: CDS_PINID='VSS(809)';
NODE_NAME     U5D1 AJ32
 '@BASEBOARD_FAB2_LIB.BASEBOARD_FAB2(SCH_1):PAGE40_I22@CHPSET_LIB.SKX_EXT_B(CHIPS)':
 'VSS'<810>: CDS_PINID='VSS(810)';
NODE_NAME     U5D1 AJ28
 '@BASEBOARD_FAB2_LIB.BASEBOARD_FAB2(SCH_1):PAGE40_I22@CHPSET_LIB.SKX_EXT_B(CHIPS)':
 'VSS'<811>: CDS_PINID='VSS(811)';
NODE_NAME     U5D1 AJ26
 '@BASEBOARD_FAB2_LIB.BASEBOARD_FAB2(SCH_1):PAGE40_I22@CHPSET_LIB.SKX_EXT_B(CHIPS)':
 'VSS'<812>: CDS_PINID='VSS(812)';
NODE_NAME     U5D1 AJ22
 '@BASEBOARD_FAB2_LIB.BASEBOARD_FAB2(SCH_1):PAGE40_I22@CHPSET_LIB.SKX_EXT_B(CHIPS)':
 'VSS'<813>: CDS_PINID='VSS(813)';
NODE_NAME     U5D1 AJ8
 '@BASEBOARD_FAB2_LIB.BASEBOARD_FAB2(SCH_1):PAGE40_I22@CHPSET_LIB.SKX_EXT_B(CHIPS)':
 'VSS'<814>: CDS_PINID='VSS(814)';
NODE_NAME     U5D1 AH83
 '@BASEBOARD_FAB2_LIB.BASEBOARD_FAB2(SCH_1):PAGE40_I22@CHPSET_LIB.SKX_EXT_B(CHIPS)':
 'VSS'<815>: CDS_PINID='VSS(815)';
NODE_NAME     U5D1 AH77
 '@BASEBOARD_FAB2_LIB.BASEBOARD_FAB2(SCH_1):PAGE40_I22@CHPSET_LIB.SKX_EXT_B(CHIPS)':
 'VSS'<816>: CDS_PINID='VSS(816)';
NODE_NAME     U5D1 AH75
 '@BASEBOARD_FAB2_LIB.BASEBOARD_FAB2(SCH_1):PAGE40_I22@CHPSET_LIB.SKX_EXT_B(CHIPS)':
 'VSS'<817>: CDS_PINID='VSS(817)';
NODE_NAME     U5D1 AH69
 '@BASEBOARD_FAB2_LIB.BASEBOARD_FAB2(SCH_1):PAGE40_I22@CHPSET_LIB.SKX_EXT_B(CHIPS)':
 'VSS'<818>: CDS_PINID='VSS(818)';
NODE_NAME     U5D1 AH65
 '@BASEBOARD_FAB2_LIB.BASEBOARD_FAB2(SCH_1):PAGE40_I22@CHPSET_LIB.SKX_EXT_B(CHIPS)':
 'VSS'<819>: CDS_PINID='VSS(819)';
NODE_NAME     U5D1 AH61
 '@BASEBOARD_FAB2_LIB.BASEBOARD_FAB2(SCH_1):PAGE40_I22@CHPSET_LIB.SKX_EXT_B(CHIPS)':
 'VSS'<820>: CDS_PINID='VSS(820)';
NODE_NAME     U5D1 AH59
 '@BASEBOARD_FAB2_LIB.BASEBOARD_FAB2(SCH_1):PAGE40_I22@CHPSET_LIB.SKX_EXT_B(CHIPS)':
 'VSS'<821>: CDS_PINID='VSS(821)';
NODE_NAME     U5D1 AH53
 '@BASEBOARD_FAB2_LIB.BASEBOARD_FAB2(SCH_1):PAGE40_I22@CHPSET_LIB.SKX_EXT_B(CHIPS)':
 'VSS'<822>: CDS_PINID='VSS(822)';
NODE_NAME     U5D1 AH51
 '@BASEBOARD_FAB2_LIB.BASEBOARD_FAB2(SCH_1):PAGE40_I22@CHPSET_LIB.SKX_EXT_B(CHIPS)':
 'VSS'<823>: CDS_PINID='VSS(823)';
NODE_NAME     U5D1 AH49
 '@BASEBOARD_FAB2_LIB.BASEBOARD_FAB2(SCH_1):PAGE40_I22@CHPSET_LIB.SKX_EXT_B(CHIPS)':
 'VSS'<824>: CDS_PINID='VSS(824)';
NODE_NAME     U5D1 AH47
 '@BASEBOARD_FAB2_LIB.BASEBOARD_FAB2(SCH_1):PAGE40_I22@CHPSET_LIB.SKX_EXT_B(CHIPS)':
 'VSS'<825>: CDS_PINID='VSS(825)';
NODE_NAME     U5D1 AH45
 '@BASEBOARD_FAB2_LIB.BASEBOARD_FAB2(SCH_1):PAGE40_I22@CHPSET_LIB.SKX_EXT_B(CHIPS)':
 'VSS'<826>: CDS_PINID='VSS(826)';
NODE_NAME     U5D1 AH35
 '@BASEBOARD_FAB2_LIB.BASEBOARD_FAB2(SCH_1):PAGE40_I22@CHPSET_LIB.SKX_EXT_B(CHIPS)':
 'VSS'<827>: CDS_PINID='VSS(827)';
NODE_NAME     U5D1 AH33
 '@BASEBOARD_FAB2_LIB.BASEBOARD_FAB2(SCH_1):PAGE40_I22@CHPSET_LIB.SKX_EXT_B(CHIPS)':
 'VSS'<828>: CDS_PINID='VSS(828)';
NODE_NAME     U5D1 AH27
 '@BASEBOARD_FAB2_LIB.BASEBOARD_FAB2(SCH_1):PAGE40_I22@CHPSET_LIB.SKX_EXT_B(CHIPS)':
 'VSS'<829>: CDS_PINID='VSS(829)';
NODE_NAME     U5D1 AH21
 '@BASEBOARD_FAB2_LIB.BASEBOARD_FAB2(SCH_1):PAGE40_I22@CHPSET_LIB.SKX_EXT_B(CHIPS)':
 'VSS'<830>: CDS_PINID='VSS(830)';
NODE_NAME     U5D1 AH5
 '@BASEBOARD_FAB2_LIB.BASEBOARD_FAB2(SCH_1):PAGE40_I22@CHPSET_LIB.SKX_EXT_B(CHIPS)':
 'VSS'<831>: CDS_PINID='VSS(831)';
NODE_NAME     U5D1 AH1
 '@BASEBOARD_FAB2_LIB.BASEBOARD_FAB2(SCH_1):PAGE40_I22@CHPSET_LIB.SKX_EXT_B(CHIPS)':
 'VSS'<832>: CDS_PINID='VSS(832)';
NODE_NAME     U5D1 AG80
 '@BASEBOARD_FAB2_LIB.BASEBOARD_FAB2(SCH_1):PAGE40_I22@CHPSET_LIB.SKX_EXT_B(CHIPS)':
 'VSS'<833>: CDS_PINID='VSS(833)';
NODE_NAME     U5D1 AG78
 '@BASEBOARD_FAB2_LIB.BASEBOARD_FAB2(SCH_1):PAGE40_I22@CHPSET_LIB.SKX_EXT_B(CHIPS)':
 'VSS'<834>: CDS_PINID='VSS(834)';
NODE_NAME     U5D1 AG76
 '@BASEBOARD_FAB2_LIB.BASEBOARD_FAB2(SCH_1):PAGE40_I22@CHPSET_LIB.SKX_EXT_B(CHIPS)':
 'VSS'<835>: CDS_PINID='VSS(835)';
NODE_NAME     U5D1 AG74
 '@BASEBOARD_FAB2_LIB.BASEBOARD_FAB2(SCH_1):PAGE40_I22@CHPSET_LIB.SKX_EXT_B(CHIPS)':
 'VSS'<836>: CDS_PINID='VSS(836)';
NODE_NAME     U5D1 AG70
 '@BASEBOARD_FAB2_LIB.BASEBOARD_FAB2(SCH_1):PAGE40_I22@CHPSET_LIB.SKX_EXT_B(CHIPS)':
 'VSS'<837>: CDS_PINID='VSS(837)';
NODE_NAME     U5D1 AG64
 '@BASEBOARD_FAB2_LIB.BASEBOARD_FAB2(SCH_1):PAGE40_I22@CHPSET_LIB.SKX_EXT_B(CHIPS)':
 'VSS'<838>: CDS_PINID='VSS(838)';
NODE_NAME     U5D1 AG36
 '@BASEBOARD_FAB2_LIB.BASEBOARD_FAB2(SCH_1):PAGE40_I22@CHPSET_LIB.SKX_EXT_B(CHIPS)':
 'VSS'<839>: CDS_PINID='VSS(839)';
NODE_NAME     U5D1 AG18
 '@BASEBOARD_FAB2_LIB.BASEBOARD_FAB2(SCH_1):PAGE40_I22@CHPSET_LIB.SKX_EXT_B(CHIPS)':
 'VSS'<840>: CDS_PINID='VSS(840)';
NODE_NAME     U5D1 AG14
 '@BASEBOARD_FAB2_LIB.BASEBOARD_FAB2(SCH_1):PAGE40_I22@CHPSET_LIB.SKX_EXT_B(CHIPS)':
 'VSS'<841>: CDS_PINID='VSS(841)';
NODE_NAME     U5D1 AG12
 '@BASEBOARD_FAB2_LIB.BASEBOARD_FAB2(SCH_1):PAGE40_I22@CHPSET_LIB.SKX_EXT_B(CHIPS)':
 'VSS'<842>: CDS_PINID='VSS(842)';
NODE_NAME     U5D1 AF85
 '@BASEBOARD_FAB2_LIB.BASEBOARD_FAB2(SCH_1):PAGE40_I22@CHPSET_LIB.SKX_EXT_B(CHIPS)':
 'VSS'<843>: CDS_PINID='VSS(843)';
NODE_NAME     U5D1 AF83
 '@BASEBOARD_FAB2_LIB.BASEBOARD_FAB2(SCH_1):PAGE40_I22@CHPSET_LIB.SKX_EXT_B(CHIPS)':
 'VSS'<844>: CDS_PINID='VSS(844)';
NODE_NAME     U5D1 AF77
 '@BASEBOARD_FAB2_LIB.BASEBOARD_FAB2(SCH_1):PAGE40_I22@CHPSET_LIB.SKX_EXT_B(CHIPS)':
 'VSS'<845>: CDS_PINID='VSS(845)';
NODE_NAME     U5D1 AF73
 '@BASEBOARD_FAB2_LIB.BASEBOARD_FAB2(SCH_1):PAGE40_I22@CHPSET_LIB.SKX_EXT_B(CHIPS)':
 'VSS'<846>: CDS_PINID='VSS(846)';
NODE_NAME     U5D1 AF41
 '@BASEBOARD_FAB2_LIB.BASEBOARD_FAB2(SCH_1):PAGE40_I22@CHPSET_LIB.SKX_EXT_B(CHIPS)':
 'VSS'<847>: CDS_PINID='VSS(847)';
NODE_NAME     U5D1 AF39
 '@BASEBOARD_FAB2_LIB.BASEBOARD_FAB2(SCH_1):PAGE40_I22@CHPSET_LIB.SKX_EXT_B(CHIPS)':
 'VSS'<848>: CDS_PINID='VSS(848)';
NODE_NAME     U5D1 AF37
 '@BASEBOARD_FAB2_LIB.BASEBOARD_FAB2(SCH_1):PAGE40_I22@CHPSET_LIB.SKX_EXT_B(CHIPS)':
 'VSS'<849>: CDS_PINID='VSS(849)';
NODE_NAME     U5D1 AF33
 '@BASEBOARD_FAB2_LIB.BASEBOARD_FAB2(SCH_1):PAGE40_I22@CHPSET_LIB.SKX_EXT_B(CHIPS)':
 'VSS'<850>: CDS_PINID='VSS(850)';
NODE_NAME     U5D1 AF31
 '@BASEBOARD_FAB2_LIB.BASEBOARD_FAB2(SCH_1):PAGE40_I22@CHPSET_LIB.SKX_EXT_B(CHIPS)':
 'VSS'<851>: CDS_PINID='VSS(851)';
NODE_NAME     U5D1 AF29
 '@BASEBOARD_FAB2_LIB.BASEBOARD_FAB2(SCH_1):PAGE40_I22@CHPSET_LIB.SKX_EXT_B(CHIPS)':
 'VSS'<852>: CDS_PINID='VSS(852)';
NODE_NAME     U5D1 AF27
 '@BASEBOARD_FAB2_LIB.BASEBOARD_FAB2(SCH_1):PAGE40_I22@CHPSET_LIB.SKX_EXT_B(CHIPS)':
 'VSS'<853>: CDS_PINID='VSS(853)';
NODE_NAME     U5D1 AF25
 '@BASEBOARD_FAB2_LIB.BASEBOARD_FAB2(SCH_1):PAGE40_I22@CHPSET_LIB.SKX_EXT_B(CHIPS)':
 'VSS'<854>: CDS_PINID='VSS(854)';
NODE_NAME     U5D1 AF23
 '@BASEBOARD_FAB2_LIB.BASEBOARD_FAB2(SCH_1):PAGE40_I22@CHPSET_LIB.SKX_EXT_B(CHIPS)':
 'VSS'<855>: CDS_PINID='VSS(855)';
NODE_NAME     U5D1 AF21
 '@BASEBOARD_FAB2_LIB.BASEBOARD_FAB2(SCH_1):PAGE40_I22@CHPSET_LIB.SKX_EXT_B(CHIPS)':
 'VSS'<856>: CDS_PINID='VSS(856)';
NODE_NAME     U5D1 AF9
 '@BASEBOARD_FAB2_LIB.BASEBOARD_FAB2(SCH_1):PAGE40_I22@CHPSET_LIB.SKX_EXT_B(CHIPS)':
 'VSS'<857>: CDS_PINID='VSS(857)';
NODE_NAME     U5D1 AC52
 '@BASEBOARD_FAB2_LIB.BASEBOARD_FAB2(SCH_1):PAGE40_I22@CHPSET_LIB.SKX_EXT_B(CHIPS)':
 'VSS'<858>: CDS_PINID='VSS(858)';
NODE_NAME     U5D1 AF1
 '@BASEBOARD_FAB2_LIB.BASEBOARD_FAB2(SCH_1):PAGE40_I22@CHPSET_LIB.SKX_EXT_B(CHIPS)':
 'VSS'<859>: CDS_PINID='VSS(859)';
NODE_NAME     U5D1 AE78
 '@BASEBOARD_FAB2_LIB.BASEBOARD_FAB2(SCH_1):PAGE40_I22@CHPSET_LIB.SKX_EXT_B(CHIPS)':
 'VSS'<860>: CDS_PINID='VSS(860)';
NODE_NAME     U5D1 AE70
 '@BASEBOARD_FAB2_LIB.BASEBOARD_FAB2(SCH_1):PAGE40_I22@CHPSET_LIB.SKX_EXT_B(CHIPS)':
 'VSS'<861>: CDS_PINID='VSS(861)';
NODE_NAME     U5D1 AE68
 '@BASEBOARD_FAB2_LIB.BASEBOARD_FAB2(SCH_1):PAGE40_I22@CHPSET_LIB.SKX_EXT_B(CHIPS)':
 'VSS'<862>: CDS_PINID='VSS(862)';
NODE_NAME     U5D1 AE66
 '@BASEBOARD_FAB2_LIB.BASEBOARD_FAB2(SCH_1):PAGE40_I22@CHPSET_LIB.SKX_EXT_B(CHIPS)':
 'VSS'<863>: CDS_PINID='VSS(863)';
NODE_NAME     U5D1 AE64
 '@BASEBOARD_FAB2_LIB.BASEBOARD_FAB2(SCH_1):PAGE40_I22@CHPSET_LIB.SKX_EXT_B(CHIPS)':
 'VSS'<864>: CDS_PINID='VSS(864)';
NODE_NAME     U5D1 AE42
 '@BASEBOARD_FAB2_LIB.BASEBOARD_FAB2(SCH_1):PAGE40_I22@CHPSET_LIB.SKX_EXT_B(CHIPS)':
 'VSS'<865>: CDS_PINID='VSS(865)';
NODE_NAME     U5D1 AE40
 '@BASEBOARD_FAB2_LIB.BASEBOARD_FAB2(SCH_1):PAGE40_I22@CHPSET_LIB.SKX_EXT_B(CHIPS)':
 'VSS'<866>: CDS_PINID='VSS(866)';
NODE_NAME     U5D1 AE38
 '@BASEBOARD_FAB2_LIB.BASEBOARD_FAB2(SCH_1):PAGE40_I22@CHPSET_LIB.SKX_EXT_B(CHIPS)':
 'VSS'<867>: CDS_PINID='VSS(867)';
NODE_NAME     U5D1 AE16
 '@BASEBOARD_FAB2_LIB.BASEBOARD_FAB2(SCH_1):PAGE40_I22@CHPSET_LIB.SKX_EXT_B(CHIPS)':
 'VSS'<868>: CDS_PINID='VSS(868)';
NODE_NAME     U5D1 AC54
 '@BASEBOARD_FAB2_LIB.BASEBOARD_FAB2(SCH_1):PAGE40_I22@CHPSET_LIB.SKX_EXT_B(CHIPS)':
 'VSS'<869>: CDS_PINID='VSS(869)';
NODE_NAME     U5D1 AE8
 '@BASEBOARD_FAB2_LIB.BASEBOARD_FAB2(SCH_1):PAGE40_I22@CHPSET_LIB.SKX_EXT_B(CHIPS)':
 'VSS'<870>: CDS_PINID='VSS(870)';
NODE_NAME     U5D1 AE4
 '@BASEBOARD_FAB2_LIB.BASEBOARD_FAB2(SCH_1):PAGE40_I22@CHPSET_LIB.SKX_EXT_B(CHIPS)':
 'VSS'<871>: CDS_PINID='VSS(871)';
NODE_NAME     U5D1 AD85
 '@BASEBOARD_FAB2_LIB.BASEBOARD_FAB2(SCH_1):PAGE40_I22@CHPSET_LIB.SKX_EXT_B(CHIPS)':
 'VSS'<872>: CDS_PINID='VSS(872)';
NODE_NAME     U5D1 AD83
 '@BASEBOARD_FAB2_LIB.BASEBOARD_FAB2(SCH_1):PAGE40_I22@CHPSET_LIB.SKX_EXT_B(CHIPS)':
 'VSS'<873>: CDS_PINID='VSS(873)';
NODE_NAME     U5D1 AD81
 '@BASEBOARD_FAB2_LIB.BASEBOARD_FAB2(SCH_1):PAGE40_I22@CHPSET_LIB.SKX_EXT_B(CHIPS)':
 'VSS'<874>: CDS_PINID='VSS(874)';
NODE_NAME     U5D1 AD75
 '@BASEBOARD_FAB2_LIB.BASEBOARD_FAB2(SCH_1):PAGE40_I22@CHPSET_LIB.SKX_EXT_B(CHIPS)':
 'VSS'<875>: CDS_PINID='VSS(875)';
NODE_NAME     U5D1 AD73
 '@BASEBOARD_FAB2_LIB.BASEBOARD_FAB2(SCH_1):PAGE40_I22@CHPSET_LIB.SKX_EXT_B(CHIPS)':
 'VSS'<876>: CDS_PINID='VSS(876)';
NODE_NAME     U5D1 AD71
 '@BASEBOARD_FAB2_LIB.BASEBOARD_FAB2(SCH_1):PAGE40_I22@CHPSET_LIB.SKX_EXT_B(CHIPS)':
 'VSS'<877>: CDS_PINID='VSS(877)';
NODE_NAME     U5D1 AD43
 '@BASEBOARD_FAB2_LIB.BASEBOARD_FAB2(SCH_1):PAGE40_I22@CHPSET_LIB.SKX_EXT_B(CHIPS)':
 'VSS'<878>: CDS_PINID='VSS(878)';
NODE_NAME     U5D1 AD39
 '@BASEBOARD_FAB2_LIB.BASEBOARD_FAB2(SCH_1):PAGE40_I22@CHPSET_LIB.SKX_EXT_B(CHIPS)':
 'VSS'<879>: CDS_PINID='VSS(879)';
NODE_NAME     U5D1 AD33
 '@BASEBOARD_FAB2_LIB.BASEBOARD_FAB2(SCH_1):PAGE40_I22@CHPSET_LIB.SKX_EXT_B(CHIPS)':
 'VSS'<880>: CDS_PINID='VSS(880)';
NODE_NAME     U5D1 AD27
 '@BASEBOARD_FAB2_LIB.BASEBOARD_FAB2(SCH_1):PAGE40_I22@CHPSET_LIB.SKX_EXT_B(CHIPS)':
 'VSS'<881>: CDS_PINID='VSS(881)';
NODE_NAME     U5D1 AD21
 '@BASEBOARD_FAB2_LIB.BASEBOARD_FAB2(SCH_1):PAGE40_I22@CHPSET_LIB.SKX_EXT_B(CHIPS)':
 'VSS'<882>: CDS_PINID='VSS(882)';
NODE_NAME     U5D1 AD19
 '@BASEBOARD_FAB2_LIB.BASEBOARD_FAB2(SCH_1):PAGE40_I22@CHPSET_LIB.SKX_EXT_B(CHIPS)':
 'VSS'<883>: CDS_PINID='VSS(883)';
NODE_NAME     U5D1 AD15
 '@BASEBOARD_FAB2_LIB.BASEBOARD_FAB2(SCH_1):PAGE40_I22@CHPSET_LIB.SKX_EXT_B(CHIPS)':
 'VSS'<884>: CDS_PINID='VSS(884)';
NODE_NAME     U5D1 AD13
 '@BASEBOARD_FAB2_LIB.BASEBOARD_FAB2(SCH_1):PAGE40_I22@CHPSET_LIB.SKX_EXT_B(CHIPS)':
 'VSS'<885>: CDS_PINID='VSS(885)';
NODE_NAME     U5D1 AD11
 '@BASEBOARD_FAB2_LIB.BASEBOARD_FAB2(SCH_1):PAGE40_I22@CHPSET_LIB.SKX_EXT_B(CHIPS)':
 'VSS'<886>: CDS_PINID='VSS(886)';
NODE_NAME     U5D1 AD9
 '@BASEBOARD_FAB2_LIB.BASEBOARD_FAB2(SCH_1):PAGE40_I22@CHPSET_LIB.SKX_EXT_B(CHIPS)':
 'VSS'<887>: CDS_PINID='VSS(887)';
NODE_NAME     U5D1 AD7
 '@BASEBOARD_FAB2_LIB.BASEBOARD_FAB2(SCH_1):PAGE40_I22@CHPSET_LIB.SKX_EXT_B(CHIPS)':
 'VSS'<888>: CDS_PINID='VSS(888)';
NODE_NAME     U5D1 AD3
 '@BASEBOARD_FAB2_LIB.BASEBOARD_FAB2(SCH_1):PAGE40_I22@CHPSET_LIB.SKX_EXT_B(CHIPS)':
 'VSS'<889>: CDS_PINID='VSS(889)';
NODE_NAME     U5D1 AC86
 '@BASEBOARD_FAB2_LIB.BASEBOARD_FAB2(SCH_1):PAGE40_I22@CHPSET_LIB.SKX_EXT_B(CHIPS)':
 'VSS'<890>: CDS_PINID='VSS(890)';
NODE_NAME     U5D1 AC84
 '@BASEBOARD_FAB2_LIB.BASEBOARD_FAB2(SCH_1):PAGE40_I22@CHPSET_LIB.SKX_EXT_B(CHIPS)':
 'VSS'<891>: CDS_PINID='VSS(891)';
NODE_NAME     U5D1 AC78
 '@BASEBOARD_FAB2_LIB.BASEBOARD_FAB2(SCH_1):PAGE40_I22@CHPSET_LIB.SKX_EXT_B(CHIPS)':
 'VSS'<892>: CDS_PINID='VSS(892)';
NODE_NAME     U5D1 AC72
 '@BASEBOARD_FAB2_LIB.BASEBOARD_FAB2(SCH_1):PAGE40_I22@CHPSET_LIB.SKX_EXT_B(CHIPS)':
 'VSS'<893>: CDS_PINID='VSS(893)';
NODE_NAME     U5D1 AC70
 '@BASEBOARD_FAB2_LIB.BASEBOARD_FAB2(SCH_1):PAGE40_I22@CHPSET_LIB.SKX_EXT_B(CHIPS)':
 'VSS'<894>: CDS_PINID='VSS(894)';
NODE_NAME     U5D1 AC64
 '@BASEBOARD_FAB2_LIB.BASEBOARD_FAB2(SCH_1):PAGE40_I22@CHPSET_LIB.SKX_EXT_B(CHIPS)':
 'VSS'<895>: CDS_PINID='VSS(895)';
NODE_NAME     U5D1 AC40
 '@BASEBOARD_FAB2_LIB.BASEBOARD_FAB2(SCH_1):PAGE40_I22@CHPSET_LIB.SKX_EXT_B(CHIPS)':
 'VSS'<896>: CDS_PINID='VSS(896)';
NODE_NAME     U5D1 AC38
 '@BASEBOARD_FAB2_LIB.BASEBOARD_FAB2(SCH_1):PAGE40_I22@CHPSET_LIB.SKX_EXT_B(CHIPS)':
 'VSS'<897>: CDS_PINID='VSS(897)';
NODE_NAME     U5D1 AC34
 '@BASEBOARD_FAB2_LIB.BASEBOARD_FAB2(SCH_1):PAGE40_I22@CHPSET_LIB.SKX_EXT_B(CHIPS)':
 'VSS'<898>: CDS_PINID='VSS(898)';
NODE_NAME     U5D1 AC32
 '@BASEBOARD_FAB2_LIB.BASEBOARD_FAB2(SCH_1):PAGE40_I22@CHPSET_LIB.SKX_EXT_B(CHIPS)':
 'VSS'<899>: CDS_PINID='VSS(899)';
NODE_NAME     U5D1 AC28
 '@BASEBOARD_FAB2_LIB.BASEBOARD_FAB2(SCH_1):PAGE40_I22@CHPSET_LIB.SKX_EXT_B(CHIPS)':
 'VSS'<900>: CDS_PINID='VSS(900)';
NODE_NAME     U5D1 AC26
 '@BASEBOARD_FAB2_LIB.BASEBOARD_FAB2(SCH_1):PAGE40_I22@CHPSET_LIB.SKX_EXT_B(CHIPS)':
 'VSS'<901>: CDS_PINID='VSS(901)';
NODE_NAME     U5D1 AC22
 '@BASEBOARD_FAB2_LIB.BASEBOARD_FAB2(SCH_1):PAGE40_I22@CHPSET_LIB.SKX_EXT_B(CHIPS)':
 'VSS'<902>: CDS_PINID='VSS(902)';
NODE_NAME     U5D1 AC18
 '@BASEBOARD_FAB2_LIB.BASEBOARD_FAB2(SCH_1):PAGE40_I22@CHPSET_LIB.SKX_EXT_B(CHIPS)':
 'VSS'<903>: CDS_PINID='VSS(903)';
NODE_NAME     U5D1 AB85
 '@BASEBOARD_FAB2_LIB.BASEBOARD_FAB2(SCH_1):PAGE40_I22@CHPSET_LIB.SKX_EXT_B(CHIPS)':
 'VSS'<904>: CDS_PINID='VSS(904)';
NODE_NAME     U5D1 AB83
 '@BASEBOARD_FAB2_LIB.BASEBOARD_FAB2(SCH_1):PAGE40_I22@CHPSET_LIB.SKX_EXT_B(CHIPS)':
 'VSS'<905>: CDS_PINID='VSS(905)';
NODE_NAME     U5D1 AB79
 '@BASEBOARD_FAB2_LIB.BASEBOARD_FAB2(SCH_1):PAGE40_I22@CHPSET_LIB.SKX_EXT_B(CHIPS)':
 'VSS'<906>: CDS_PINID='VSS(906)';
NODE_NAME     U5D1 AB73
 '@BASEBOARD_FAB2_LIB.BASEBOARD_FAB2(SCH_1):PAGE40_I22@CHPSET_LIB.SKX_EXT_B(CHIPS)':
 'VSS'<907>: CDS_PINID='VSS(907)';
NODE_NAME     U5D1 AB69
 '@BASEBOARD_FAB2_LIB.BASEBOARD_FAB2(SCH_1):PAGE40_I22@CHPSET_LIB.SKX_EXT_B(CHIPS)':
 'VSS'<908>: CDS_PINID='VSS(908)';
NODE_NAME     U5D1 AB65
 '@BASEBOARD_FAB2_LIB.BASEBOARD_FAB2(SCH_1):PAGE40_I22@CHPSET_LIB.SKX_EXT_B(CHIPS)':
 'VSS'<909>: CDS_PINID='VSS(909)';
NODE_NAME     U5D1 AB41
 '@BASEBOARD_FAB2_LIB.BASEBOARD_FAB2(SCH_1):PAGE40_I22@CHPSET_LIB.SKX_EXT_B(CHIPS)':
 'VSS'<910>: CDS_PINID='VSS(910)';
NODE_NAME     U5D1 AB37
 '@BASEBOARD_FAB2_LIB.BASEBOARD_FAB2(SCH_1):PAGE40_I22@CHPSET_LIB.SKX_EXT_B(CHIPS)':
 'VSS'<911>: CDS_PINID='VSS(911)';
NODE_NAME     U5D1 AB35
 '@BASEBOARD_FAB2_LIB.BASEBOARD_FAB2(SCH_1):PAGE40_I22@CHPSET_LIB.SKX_EXT_B(CHIPS)':
 'VSS'<912>: CDS_PINID='VSS(912)';
NODE_NAME     U5D1 AB31
 '@BASEBOARD_FAB2_LIB.BASEBOARD_FAB2(SCH_1):PAGE40_I22@CHPSET_LIB.SKX_EXT_B(CHIPS)':
 'VSS'<913>: CDS_PINID='VSS(913)';
NODE_NAME     U5D1 AB29
 '@BASEBOARD_FAB2_LIB.BASEBOARD_FAB2(SCH_1):PAGE40_I22@CHPSET_LIB.SKX_EXT_B(CHIPS)':
 'VSS'<914>: CDS_PINID='VSS(914)';
NODE_NAME     U5D1 AB25
 '@BASEBOARD_FAB2_LIB.BASEBOARD_FAB2(SCH_1):PAGE40_I22@CHPSET_LIB.SKX_EXT_B(CHIPS)':
 'VSS'<915>: CDS_PINID='VSS(915)';
NODE_NAME     U5D1 AB23
 '@BASEBOARD_FAB2_LIB.BASEBOARD_FAB2(SCH_1):PAGE40_I22@CHPSET_LIB.SKX_EXT_B(CHIPS)':
 'VSS'<916>: CDS_PINID='VSS(916)';
NODE_NAME     U5D1 AB21
 '@BASEBOARD_FAB2_LIB.BASEBOARD_FAB2(SCH_1):PAGE40_I22@CHPSET_LIB.SKX_EXT_B(CHIPS)':
 'VSS'<917>: CDS_PINID='VSS(917)';
NODE_NAME     U5D1 AB11
 '@BASEBOARD_FAB2_LIB.BASEBOARD_FAB2(SCH_1):PAGE40_I22@CHPSET_LIB.SKX_EXT_B(CHIPS)':
 'VSS'<918>: CDS_PINID='VSS(918)';
NODE_NAME     U5D1 AB5
 '@BASEBOARD_FAB2_LIB.BASEBOARD_FAB2(SCH_1):PAGE40_I22@CHPSET_LIB.SKX_EXT_B(CHIPS)':
 'VSS'<919>: CDS_PINID='VSS(919)';
NODE_NAME     U5D1 AB1
 '@BASEBOARD_FAB2_LIB.BASEBOARD_FAB2(SCH_1):PAGE40_I22@CHPSET_LIB.SKX_EXT_B(CHIPS)':
 'VSS'<920>: CDS_PINID='VSS(920)';
NODE_NAME     U5D1 AA82
 '@BASEBOARD_FAB2_LIB.BASEBOARD_FAB2(SCH_1):PAGE40_I22@CHPSET_LIB.SKX_EXT_B(CHIPS)':
 'VSS'<921>: CDS_PINID='VSS(921)';
NODE_NAME     U5D1 AA80
 '@BASEBOARD_FAB2_LIB.BASEBOARD_FAB2(SCH_1):PAGE40_I22@CHPSET_LIB.SKX_EXT_B(CHIPS)':
 'VSS'<922>: CDS_PINID='VSS(922)';
NODE_NAME     U5D1 AA78
 '@BASEBOARD_FAB2_LIB.BASEBOARD_FAB2(SCH_1):PAGE40_I22@CHPSET_LIB.SKX_EXT_B(CHIPS)':
 'VSS'<923>: CDS_PINID='VSS(923)';
NODE_NAME     U5D1 AA76
 '@BASEBOARD_FAB2_LIB.BASEBOARD_FAB2(SCH_1):PAGE40_I22@CHPSET_LIB.SKX_EXT_B(CHIPS)':
 'VSS'<924>: CDS_PINID='VSS(924)';
NODE_NAME     U5D1 AA68
 '@BASEBOARD_FAB2_LIB.BASEBOARD_FAB2(SCH_1):PAGE40_I22@CHPSET_LIB.SKX_EXT_B(CHIPS)':
 'VSS'<925>: CDS_PINID='VSS(925)';
NODE_NAME     U5D1 AA66
 '@BASEBOARD_FAB2_LIB.BASEBOARD_FAB2(SCH_1):PAGE40_I22@CHPSET_LIB.SKX_EXT_B(CHIPS)':
 'VSS'<926>: CDS_PINID='VSS(926)';
NODE_NAME     U5D1 AA64
 '@BASEBOARD_FAB2_LIB.BASEBOARD_FAB2(SCH_1):PAGE40_I22@CHPSET_LIB.SKX_EXT_B(CHIPS)':
 'VSS'<927>: CDS_PINID='VSS(927)';
NODE_NAME     U5D1 AA42
 '@BASEBOARD_FAB2_LIB.BASEBOARD_FAB2(SCH_1):PAGE40_I22@CHPSET_LIB.SKX_EXT_B(CHIPS)':
 'VSS'<928>: CDS_PINID='VSS(928)';
NODE_NAME     U5D1 AA36
 '@BASEBOARD_FAB2_LIB.BASEBOARD_FAB2(SCH_1):PAGE40_I22@CHPSET_LIB.SKX_EXT_B(CHIPS)':
 'VSS'<929>: CDS_PINID='VSS(929)';
NODE_NAME     U5D1 AA30
 '@BASEBOARD_FAB2_LIB.BASEBOARD_FAB2(SCH_1):PAGE40_I22@CHPSET_LIB.SKX_EXT_B(CHIPS)':
 'VSS'<930>: CDS_PINID='VSS(930)';
NODE_NAME     U5D1 AA24
 '@BASEBOARD_FAB2_LIB.BASEBOARD_FAB2(SCH_1):PAGE40_I22@CHPSET_LIB.SKX_EXT_B(CHIPS)':
 'VSS'<931>: CDS_PINID='VSS(931)';
NODE_NAME     U5D1 AA22
 '@BASEBOARD_FAB2_LIB.BASEBOARD_FAB2(SCH_1):PAGE40_I22@CHPSET_LIB.SKX_EXT_B(CHIPS)':
 'VSS'<932>: CDS_PINID='VSS(932)';
NODE_NAME     U5D1 AA18
 '@BASEBOARD_FAB2_LIB.BASEBOARD_FAB2(SCH_1):PAGE40_I22@CHPSET_LIB.SKX_EXT_B(CHIPS)':
 'VSS'<933>: CDS_PINID='VSS(933)';
NODE_NAME     U5D1 BG72
 '@BASEBOARD_FAB2_LIB.BASEBOARD_FAB2(SCH_1):PAGE40_I23@CHPSET_LIB.SKX_EXT_B(CHIPS)':
 'VSS'<614>: CDS_PINID='VSS(614)';
NODE_NAME     U5D1 BG24
 '@BASEBOARD_FAB2_LIB.BASEBOARD_FAB2(SCH_1):PAGE40_I23@CHPSET_LIB.SKX_EXT_B(CHIPS)':
 'VSS'<615>: CDS_PINID='VSS(615)';
NODE_NAME     U5D1 BG22
 '@BASEBOARD_FAB2_LIB.BASEBOARD_FAB2(SCH_1):PAGE40_I23@CHPSET_LIB.SKX_EXT_B(CHIPS)':
 'VSS'<616>: CDS_PINID='VSS(616)';
NODE_NAME     U5D1 BG10
 '@BASEBOARD_FAB2_LIB.BASEBOARD_FAB2(SCH_1):PAGE40_I23@CHPSET_LIB.SKX_EXT_B(CHIPS)':
 'VSS'<617>: CDS_PINID='VSS(617)';
NODE_NAME     U5D1 BG8
 '@BASEBOARD_FAB2_LIB.BASEBOARD_FAB2(SCH_1):PAGE40_I23@CHPSET_LIB.SKX_EXT_B(CHIPS)':
 'VSS'<618>: CDS_PINID='VSS(618)';
NODE_NAME     U5D1 BG6
 '@BASEBOARD_FAB2_LIB.BASEBOARD_FAB2(SCH_1):PAGE40_I23@CHPSET_LIB.SKX_EXT_B(CHIPS)':
 'VSS'<619>: CDS_PINID='VSS(619)';
NODE_NAME     U5D1 BF71
 '@BASEBOARD_FAB2_LIB.BASEBOARD_FAB2(SCH_1):PAGE40_I23@CHPSET_LIB.SKX_EXT_B(CHIPS)':
 'VSS'<620>: CDS_PINID='VSS(620)';
NODE_NAME     U5D1 BF69
 '@BASEBOARD_FAB2_LIB.BASEBOARD_FAB2(SCH_1):PAGE40_I23@CHPSET_LIB.SKX_EXT_B(CHIPS)':
 'VSS'<621>: CDS_PINID='VSS(621)';
NODE_NAME     U5D1 BF67
 '@BASEBOARD_FAB2_LIB.BASEBOARD_FAB2(SCH_1):PAGE40_I23@CHPSET_LIB.SKX_EXT_B(CHIPS)':
 'VSS'<622>: CDS_PINID='VSS(622)';
NODE_NAME     U5D1 BF65
 '@BASEBOARD_FAB2_LIB.BASEBOARD_FAB2(SCH_1):PAGE40_I23@CHPSET_LIB.SKX_EXT_B(CHIPS)':
 'VSS'<623>: CDS_PINID='VSS(623)';
NODE_NAME     U5D1 BF63
 '@BASEBOARD_FAB2_LIB.BASEBOARD_FAB2(SCH_1):PAGE40_I23@CHPSET_LIB.SKX_EXT_B(CHIPS)':
 'VSS'<624>: CDS_PINID='VSS(624)';
NODE_NAME     U5D1 BF25
 '@BASEBOARD_FAB2_LIB.BASEBOARD_FAB2(SCH_1):PAGE40_I23@CHPSET_LIB.SKX_EXT_B(CHIPS)':
 'VSS'<625>: CDS_PINID='VSS(625)';
NODE_NAME     U5D1 BF19
 '@BASEBOARD_FAB2_LIB.BASEBOARD_FAB2(SCH_1):PAGE40_I23@CHPSET_LIB.SKX_EXT_B(CHIPS)':
 'VSS'<626>: CDS_PINID='VSS(626)';
NODE_NAME     U5D1 BF17
 '@BASEBOARD_FAB2_LIB.BASEBOARD_FAB2(SCH_1):PAGE40_I23@CHPSET_LIB.SKX_EXT_B(CHIPS)':
 'VSS'<627>: CDS_PINID='VSS(627)';
NODE_NAME     U5D1 BF15
 '@BASEBOARD_FAB2_LIB.BASEBOARD_FAB2(SCH_1):PAGE40_I23@CHPSET_LIB.SKX_EXT_B(CHIPS)':
 'VSS'<628>: CDS_PINID='VSS(628)';
NODE_NAME     U5D1 BF9
 '@BASEBOARD_FAB2_LIB.BASEBOARD_FAB2(SCH_1):PAGE40_I23@CHPSET_LIB.SKX_EXT_B(CHIPS)':
 'VSS'<629>: CDS_PINID='VSS(629)';
NODE_NAME     U5D1 BE70
 '@BASEBOARD_FAB2_LIB.BASEBOARD_FAB2(SCH_1):PAGE40_I23@CHPSET_LIB.SKX_EXT_B(CHIPS)':
 'VSS'<630>: CDS_PINID='VSS(630)';
NODE_NAME     U5D1 BE68
 '@BASEBOARD_FAB2_LIB.BASEBOARD_FAB2(SCH_1):PAGE40_I23@CHPSET_LIB.SKX_EXT_B(CHIPS)':
 'VSS'<631>: CDS_PINID='VSS(631)';
NODE_NAME     U5D1 BE66
 '@BASEBOARD_FAB2_LIB.BASEBOARD_FAB2(SCH_1):PAGE40_I23@CHPSET_LIB.SKX_EXT_B(CHIPS)':
 'VSS'<632>: CDS_PINID='VSS(632)';
NODE_NAME     U5D1 BE64
 '@BASEBOARD_FAB2_LIB.BASEBOARD_FAB2(SCH_1):PAGE40_I23@CHPSET_LIB.SKX_EXT_B(CHIPS)':
 'VSS'<633>: CDS_PINID='VSS(633)';
NODE_NAME     U5D1 BE26
 '@BASEBOARD_FAB2_LIB.BASEBOARD_FAB2(SCH_1):PAGE40_I23@CHPSET_LIB.SKX_EXT_B(CHIPS)':
 'VSS'<634>: CDS_PINID='VSS(634)';
NODE_NAME     U5D1 BE10
 '@BASEBOARD_FAB2_LIB.BASEBOARD_FAB2(SCH_1):PAGE40_I23@CHPSET_LIB.SKX_EXT_B(CHIPS)':
 'VSS'<635>: CDS_PINID='VSS(635)';
NODE_NAME     U5D1 BE8
 '@BASEBOARD_FAB2_LIB.BASEBOARD_FAB2(SCH_1):PAGE40_I23@CHPSET_LIB.SKX_EXT_B(CHIPS)':
 'VSS'<636>: CDS_PINID='VSS(636)';
NODE_NAME     U5D1 BE6
 '@BASEBOARD_FAB2_LIB.BASEBOARD_FAB2(SCH_1):PAGE40_I23@CHPSET_LIB.SKX_EXT_B(CHIPS)':
 'VSS'<637>: CDS_PINID='VSS(637)';
NODE_NAME     U5D1 BE4
 '@BASEBOARD_FAB2_LIB.BASEBOARD_FAB2(SCH_1):PAGE40_I23@CHPSET_LIB.SKX_EXT_B(CHIPS)':
 'VSS'<638>: CDS_PINID='VSS(638)';
NODE_NAME     U5D1 BD71
 '@BASEBOARD_FAB2_LIB.BASEBOARD_FAB2(SCH_1):PAGE40_I23@CHPSET_LIB.SKX_EXT_B(CHIPS)':
 'VSS'<639>: CDS_PINID='VSS(639)';
NODE_NAME     U5D1 BD63
 '@BASEBOARD_FAB2_LIB.BASEBOARD_FAB2(SCH_1):PAGE40_I23@CHPSET_LIB.SKX_EXT_B(CHIPS)':
 'VSS'<640>: CDS_PINID='VSS(640)';
NODE_NAME     U5D1 BD27
 '@BASEBOARD_FAB2_LIB.BASEBOARD_FAB2(SCH_1):PAGE40_I23@CHPSET_LIB.SKX_EXT_B(CHIPS)':
 'VSS'<641>: CDS_PINID='VSS(641)';
NODE_NAME     U5D1 BD21
 '@BASEBOARD_FAB2_LIB.BASEBOARD_FAB2(SCH_1):PAGE40_I23@CHPSET_LIB.SKX_EXT_B(CHIPS)':
 'VSS'<642>: CDS_PINID='VSS(642)';
NODE_NAME     U5D1 BD15
 '@BASEBOARD_FAB2_LIB.BASEBOARD_FAB2(SCH_1):PAGE40_I23@CHPSET_LIB.SKX_EXT_B(CHIPS)':
 'VSS'<643>: CDS_PINID='VSS(643)';
NODE_NAME     U5D1 BD11
 '@BASEBOARD_FAB2_LIB.BASEBOARD_FAB2(SCH_1):PAGE40_I23@CHPSET_LIB.SKX_EXT_B(CHIPS)':
 'VSS'<644>: CDS_PINID='VSS(644)';
NODE_NAME     U5D1 BD5
 '@BASEBOARD_FAB2_LIB.BASEBOARD_FAB2(SCH_1):PAGE40_I23@CHPSET_LIB.SKX_EXT_B(CHIPS)':
 'VSS'<645>: CDS_PINID='VSS(645)';
NODE_NAME     U5D1 BC82
 '@BASEBOARD_FAB2_LIB.BASEBOARD_FAB2(SCH_1):PAGE40_I23@CHPSET_LIB.SKX_EXT_B(CHIPS)':
 'VSS'<646>: CDS_PINID='VSS(646)';
NODE_NAME     U5D1 BC80
 '@BASEBOARD_FAB2_LIB.BASEBOARD_FAB2(SCH_1):PAGE40_I23@CHPSET_LIB.SKX_EXT_B(CHIPS)':
 'VSS'<647>: CDS_PINID='VSS(647)';
NODE_NAME     U5D1 BC78
 '@BASEBOARD_FAB2_LIB.BASEBOARD_FAB2(SCH_1):PAGE40_I23@CHPSET_LIB.SKX_EXT_B(CHIPS)':
 'VSS'<648>: CDS_PINID='VSS(648)';
NODE_NAME     U5D1 BC76
 '@BASEBOARD_FAB2_LIB.BASEBOARD_FAB2(SCH_1):PAGE40_I23@CHPSET_LIB.SKX_EXT_B(CHIPS)':
 'VSS'<649>: CDS_PINID='VSS(649)';
NODE_NAME     U5D1 BC74
 '@BASEBOARD_FAB2_LIB.BASEBOARD_FAB2(SCH_1):PAGE40_I23@CHPSET_LIB.SKX_EXT_B(CHIPS)':
 'VSS'<650>: CDS_PINID='VSS(650)';
NODE_NAME     U5D1 BC72
 '@BASEBOARD_FAB2_LIB.BASEBOARD_FAB2(SCH_1):PAGE40_I23@CHPSET_LIB.SKX_EXT_B(CHIPS)':
 'VSS'<651>: CDS_PINID='VSS(651)';
NODE_NAME     U5D1 BC70
 '@BASEBOARD_FAB2_LIB.BASEBOARD_FAB2(SCH_1):PAGE40_I23@CHPSET_LIB.SKX_EXT_B(CHIPS)':
 'VSS'<652>: CDS_PINID='VSS(652)';
NODE_NAME     U5D1 BC16
 '@BASEBOARD_FAB2_LIB.BASEBOARD_FAB2(SCH_1):PAGE40_I23@CHPSET_LIB.SKX_EXT_B(CHIPS)':
 'VSS'<653>: CDS_PINID='VSS(653)';
NODE_NAME     U5D1 BC12
 '@BASEBOARD_FAB2_LIB.BASEBOARD_FAB2(SCH_1):PAGE40_I23@CHPSET_LIB.SKX_EXT_B(CHIPS)':
 'VSS'<654>: CDS_PINID='VSS(654)';
NODE_NAME     U5D1 BC8
 '@BASEBOARD_FAB2_LIB.BASEBOARD_FAB2(SCH_1):PAGE40_I23@CHPSET_LIB.SKX_EXT_B(CHIPS)':
 'VSS'<655>: CDS_PINID='VSS(655)';
NODE_NAME     U5D1 BC4
 '@BASEBOARD_FAB2_LIB.BASEBOARD_FAB2(SCH_1):PAGE40_I23@CHPSET_LIB.SKX_EXT_B(CHIPS)':
 'VSS'<656>: CDS_PINID='VSS(656)';
NODE_NAME     U5D1 BB83
 '@BASEBOARD_FAB2_LIB.BASEBOARD_FAB2(SCH_1):PAGE40_I23@CHPSET_LIB.SKX_EXT_B(CHIPS)':
 'VSS'<657>: CDS_PINID='VSS(657)';
NODE_NAME     U5D1 BB81
 '@BASEBOARD_FAB2_LIB.BASEBOARD_FAB2(SCH_1):PAGE40_I23@CHPSET_LIB.SKX_EXT_B(CHIPS)':
 'VSS'<658>: CDS_PINID='VSS(658)';
NODE_NAME     U5D1 BB79
 '@BASEBOARD_FAB2_LIB.BASEBOARD_FAB2(SCH_1):PAGE40_I23@CHPSET_LIB.SKX_EXT_B(CHIPS)':
 'VSS'<659>: CDS_PINID='VSS(659)';
NODE_NAME     U5D1 BB77
 '@BASEBOARD_FAB2_LIB.BASEBOARD_FAB2(SCH_1):PAGE40_I23@CHPSET_LIB.SKX_EXT_B(CHIPS)':
 'VSS'<660>: CDS_PINID='VSS(660)';
NODE_NAME     U5D1 BB75
 '@BASEBOARD_FAB2_LIB.BASEBOARD_FAB2(SCH_1):PAGE40_I23@CHPSET_LIB.SKX_EXT_B(CHIPS)':
 'VSS'<661>: CDS_PINID='VSS(661)';
NODE_NAME     U5D1 BB73
 '@BASEBOARD_FAB2_LIB.BASEBOARD_FAB2(SCH_1):PAGE40_I23@CHPSET_LIB.SKX_EXT_B(CHIPS)':
 'VSS'<662>: CDS_PINID='VSS(662)';
NODE_NAME     U5D1 BB69
 '@BASEBOARD_FAB2_LIB.BASEBOARD_FAB2(SCH_1):PAGE40_I23@CHPSET_LIB.SKX_EXT_B(CHIPS)':
 'VSS'<663>: CDS_PINID='VSS(663)';
NODE_NAME     U5D1 BB63
 '@BASEBOARD_FAB2_LIB.BASEBOARD_FAB2(SCH_1):PAGE40_I23@CHPSET_LIB.SKX_EXT_B(CHIPS)':
 'VSS'<664>: CDS_PINID='VSS(664)';
NODE_NAME     U5D1 BB23
 '@BASEBOARD_FAB2_LIB.BASEBOARD_FAB2(SCH_1):PAGE40_I23@CHPSET_LIB.SKX_EXT_B(CHIPS)':
 'VSS'<665>: CDS_PINID='VSS(665)';
NODE_NAME     U5D1 BB19
 '@BASEBOARD_FAB2_LIB.BASEBOARD_FAB2(SCH_1):PAGE40_I23@CHPSET_LIB.SKX_EXT_B(CHIPS)':
 'VSS'<666>: CDS_PINID='VSS(666)';
NODE_NAME     U5D1 BA84
 '@BASEBOARD_FAB2_LIB.BASEBOARD_FAB2(SCH_1):PAGE40_I23@CHPSET_LIB.SKX_EXT_B(CHIPS)':
 'VSS'<667>: CDS_PINID='VSS(667)';
NODE_NAME     U5D1 BA80
 '@BASEBOARD_FAB2_LIB.BASEBOARD_FAB2(SCH_1):PAGE40_I23@CHPSET_LIB.SKX_EXT_B(CHIPS)':
 'VSS'<668>: CDS_PINID='VSS(668)';
NODE_NAME     U5D1 BA74
 '@BASEBOARD_FAB2_LIB.BASEBOARD_FAB2(SCH_1):PAGE40_I23@CHPSET_LIB.SKX_EXT_B(CHIPS)':
 'VSS'<669>: CDS_PINID='VSS(669)';
NODE_NAME     U5D1 BA68
 '@BASEBOARD_FAB2_LIB.BASEBOARD_FAB2(SCH_1):PAGE40_I23@CHPSET_LIB.SKX_EXT_B(CHIPS)':
 'VSS'<670>: CDS_PINID='VSS(670)';
NODE_NAME     U5D1 BA62
 '@BASEBOARD_FAB2_LIB.BASEBOARD_FAB2(SCH_1):PAGE40_I23@CHPSET_LIB.SKX_EXT_B(CHIPS)':
 'VSS'<671>: CDS_PINID='VSS(671)';
NODE_NAME     U5D1 BA12
 '@BASEBOARD_FAB2_LIB.BASEBOARD_FAB2(SCH_1):PAGE40_I23@CHPSET_LIB.SKX_EXT_B(CHIPS)':
 'VSS'<672>: CDS_PINID='VSS(672)';
NODE_NAME     U5D1 BA6
 '@BASEBOARD_FAB2_LIB.BASEBOARD_FAB2(SCH_1):PAGE40_I23@CHPSET_LIB.SKX_EXT_B(CHIPS)':
 'VSS'<673>: CDS_PINID='VSS(673)';
NODE_NAME     U5D1 BA2
 '@BASEBOARD_FAB2_LIB.BASEBOARD_FAB2(SCH_1):PAGE40_I23@CHPSET_LIB.SKX_EXT_B(CHIPS)':
 'VSS'<674>: CDS_PINID='VSS(674)';
NODE_NAME     U5D1 AY81
 '@BASEBOARD_FAB2_LIB.BASEBOARD_FAB2(SCH_1):PAGE40_I23@CHPSET_LIB.SKX_EXT_B(CHIPS)':
 'VSS'<675>: CDS_PINID='VSS(675)';
NODE_NAME     U5D1 AY79
 '@BASEBOARD_FAB2_LIB.BASEBOARD_FAB2(SCH_1):PAGE40_I23@CHPSET_LIB.SKX_EXT_B(CHIPS)':
 'VSS'<676>: CDS_PINID='VSS(676)';
NODE_NAME     U5D1 AY63
 '@BASEBOARD_FAB2_LIB.BASEBOARD_FAB2(SCH_1):PAGE40_I23@CHPSET_LIB.SKX_EXT_B(CHIPS)':
 'VSS'<677>: CDS_PINID='VSS(677)';
NODE_NAME     U5D1 AY25
 '@BASEBOARD_FAB2_LIB.BASEBOARD_FAB2(SCH_1):PAGE40_I23@CHPSET_LIB.SKX_EXT_B(CHIPS)':
 'VSS'<678>: CDS_PINID='VSS(678)';
NODE_NAME     U5D1 AY23
 '@BASEBOARD_FAB2_LIB.BASEBOARD_FAB2(SCH_1):PAGE40_I23@CHPSET_LIB.SKX_EXT_B(CHIPS)':
 'VSS'<679>: CDS_PINID='VSS(679)';
NODE_NAME     U5D1 AY21
 '@BASEBOARD_FAB2_LIB.BASEBOARD_FAB2(SCH_1):PAGE40_I23@CHPSET_LIB.SKX_EXT_B(CHIPS)':
 'VSS'<680>: CDS_PINID='VSS(680)';
NODE_NAME     U5D1 AY17
 '@BASEBOARD_FAB2_LIB.BASEBOARD_FAB2(SCH_1):PAGE40_I23@CHPSET_LIB.SKX_EXT_B(CHIPS)':
 'VSS'<681>: CDS_PINID='VSS(681)';
NODE_NAME     U5D1 AY15
 '@BASEBOARD_FAB2_LIB.BASEBOARD_FAB2(SCH_1):PAGE40_I23@CHPSET_LIB.SKX_EXT_B(CHIPS)':
 'VSS'<682>: CDS_PINID='VSS(682)';
NODE_NAME     U5D1 AY5
 '@BASEBOARD_FAB2_LIB.BASEBOARD_FAB2(SCH_1):PAGE40_I23@CHPSET_LIB.SKX_EXT_B(CHIPS)':
 'VSS'<683>: CDS_PINID='VSS(683)';
NODE_NAME     U5D1 AW84
 '@BASEBOARD_FAB2_LIB.BASEBOARD_FAB2(SCH_1):PAGE40_I23@CHPSET_LIB.SKX_EXT_B(CHIPS)':
 'VSS'<684>: CDS_PINID='VSS(684)';
NODE_NAME     U5D1 AW82
 '@BASEBOARD_FAB2_LIB.BASEBOARD_FAB2(SCH_1):PAGE40_I23@CHPSET_LIB.SKX_EXT_B(CHIPS)':
 'VSS'<685>: CDS_PINID='VSS(685)';
NODE_NAME     U5D1 AW78
 '@BASEBOARD_FAB2_LIB.BASEBOARD_FAB2(SCH_1):PAGE40_I23@CHPSET_LIB.SKX_EXT_B(CHIPS)':
 'VSS'<686>: CDS_PINID='VSS(686)';
NODE_NAME     U5D1 AW74
 '@BASEBOARD_FAB2_LIB.BASEBOARD_FAB2(SCH_1):PAGE40_I23@CHPSET_LIB.SKX_EXT_B(CHIPS)':
 'VSS'<687>: CDS_PINID='VSS(687)';
NODE_NAME     U5D1 AW72
 '@BASEBOARD_FAB2_LIB.BASEBOARD_FAB2(SCH_1):PAGE40_I23@CHPSET_LIB.SKX_EXT_B(CHIPS)':
 'VSS'<688>: CDS_PINID='VSS(688)';
NODE_NAME     U5D1 AW70
 '@BASEBOARD_FAB2_LIB.BASEBOARD_FAB2(SCH_1):PAGE40_I23@CHPSET_LIB.SKX_EXT_B(CHIPS)':
 'VSS'<689>: CDS_PINID='VSS(689)';
NODE_NAME     U5D1 AW68
 '@BASEBOARD_FAB2_LIB.BASEBOARD_FAB2(SCH_1):PAGE40_I23@CHPSET_LIB.SKX_EXT_B(CHIPS)':
 'VSS'<690>: CDS_PINID='VSS(690)';
NODE_NAME     U5D1 AW66
 '@BASEBOARD_FAB2_LIB.BASEBOARD_FAB2(SCH_1):PAGE40_I23@CHPSET_LIB.SKX_EXT_B(CHIPS)':
 'VSS'<691>: CDS_PINID='VSS(691)';
NODE_NAME     U5D1 AW62
 '@BASEBOARD_FAB2_LIB.BASEBOARD_FAB2(SCH_1):PAGE40_I23@CHPSET_LIB.SKX_EXT_B(CHIPS)':
 'VSS'<692>: CDS_PINID='VSS(692)';
NODE_NAME     U5D1 AW10
 '@BASEBOARD_FAB2_LIB.BASEBOARD_FAB2(SCH_1):PAGE40_I23@CHPSET_LIB.SKX_EXT_B(CHIPS)':
 'VSS'<693>: CDS_PINID='VSS(693)';
NODE_NAME     U5D1 AW2
 '@BASEBOARD_FAB2_LIB.BASEBOARD_FAB2(SCH_1):PAGE40_I23@CHPSET_LIB.SKX_EXT_B(CHIPS)':
 'VSS'<694>: CDS_PINID='VSS(694)';
NODE_NAME     U5D1 AV83
 '@BASEBOARD_FAB2_LIB.BASEBOARD_FAB2(SCH_1):PAGE40_I23@CHPSET_LIB.SKX_EXT_B(CHIPS)':
 'VSS'<695>: CDS_PINID='VSS(695)';
NODE_NAME     U5D1 AV75
 '@BASEBOARD_FAB2_LIB.BASEBOARD_FAB2(SCH_1):PAGE40_I23@CHPSET_LIB.SKX_EXT_B(CHIPS)':
 'VSS'<696>: CDS_PINID='VSS(696)';
NODE_NAME     U5D1 AV67
 '@BASEBOARD_FAB2_LIB.BASEBOARD_FAB2(SCH_1):PAGE40_I23@CHPSET_LIB.SKX_EXT_B(CHIPS)':
 'VSS'<697>: CDS_PINID='VSS(697)';
NODE_NAME     U5D1 AV65
 '@BASEBOARD_FAB2_LIB.BASEBOARD_FAB2(SCH_1):PAGE40_I23@CHPSET_LIB.SKX_EXT_B(CHIPS)':
 'VSS'<698>: CDS_PINID='VSS(698)';
NODE_NAME     U5D1 AV63
 '@BASEBOARD_FAB2_LIB.BASEBOARD_FAB2(SCH_1):PAGE40_I23@CHPSET_LIB.SKX_EXT_B(CHIPS)':
 'VSS'<699>: CDS_PINID='VSS(699)';
NODE_NAME     U5D1 AV25
 '@BASEBOARD_FAB2_LIB.BASEBOARD_FAB2(SCH_1):PAGE40_I23@CHPSET_LIB.SKX_EXT_B(CHIPS)':
 'VSS'<700>: CDS_PINID='VSS(700)';
NODE_NAME     U5D1 AV23
 '@BASEBOARD_FAB2_LIB.BASEBOARD_FAB2(SCH_1):PAGE40_I23@CHPSET_LIB.SKX_EXT_B(CHIPS)':
 'VSS'<701>: CDS_PINID='VSS(701)';
NODE_NAME     U5D1 AV19
 '@BASEBOARD_FAB2_LIB.BASEBOARD_FAB2(SCH_1):PAGE40_I23@CHPSET_LIB.SKX_EXT_B(CHIPS)':
 'VSS'<702>: CDS_PINID='VSS(702)';
NODE_NAME     U5D1 AV13
 '@BASEBOARD_FAB2_LIB.BASEBOARD_FAB2(SCH_1):PAGE40_I23@CHPSET_LIB.SKX_EXT_B(CHIPS)':
 'VSS'<703>: CDS_PINID='VSS(703)';
NODE_NAME     U5D1 AV11
 '@BASEBOARD_FAB2_LIB.BASEBOARD_FAB2(SCH_1):PAGE40_I23@CHPSET_LIB.SKX_EXT_B(CHIPS)':
 'VSS'<704>: CDS_PINID='VSS(704)';
NODE_NAME     U5D1 AV7
 '@BASEBOARD_FAB2_LIB.BASEBOARD_FAB2(SCH_1):PAGE40_I23@CHPSET_LIB.SKX_EXT_B(CHIPS)':
 'VSS'<705>: CDS_PINID='VSS(705)';
NODE_NAME     U5D1 AV3
 '@BASEBOARD_FAB2_LIB.BASEBOARD_FAB2(SCH_1):PAGE40_I23@CHPSET_LIB.SKX_EXT_B(CHIPS)':
 'VSS'<706>: CDS_PINID='VSS(706)';
NODE_NAME     U5D1 AV1
 '@BASEBOARD_FAB2_LIB.BASEBOARD_FAB2(SCH_1):PAGE40_I23@CHPSET_LIB.SKX_EXT_B(CHIPS)':
 'VSS'<707>: CDS_PINID='VSS(707)';
NODE_NAME     U5D1 AU86
 '@BASEBOARD_FAB2_LIB.BASEBOARD_FAB2(SCH_1):PAGE40_I23@CHPSET_LIB.SKX_EXT_B(CHIPS)':
 'VSS'<708>: CDS_PINID='VSS(708)';
NODE_NAME     U5D1 AU84
 '@BASEBOARD_FAB2_LIB.BASEBOARD_FAB2(SCH_1):PAGE40_I23@CHPSET_LIB.SKX_EXT_B(CHIPS)':
 'VSS'<709>: CDS_PINID='VSS(709)';
NODE_NAME     U5D1 AU80
 '@BASEBOARD_FAB2_LIB.BASEBOARD_FAB2(SCH_1):PAGE40_I23@CHPSET_LIB.SKX_EXT_B(CHIPS)':
 'VSS'<710>: CDS_PINID='VSS(710)';
NODE_NAME     U5D1 AU78
 '@BASEBOARD_FAB2_LIB.BASEBOARD_FAB2(SCH_1):PAGE40_I23@CHPSET_LIB.SKX_EXT_B(CHIPS)':
 'VSS'<711>: CDS_PINID='VSS(711)';
NODE_NAME     U5D1 AU76
 '@BASEBOARD_FAB2_LIB.BASEBOARD_FAB2(SCH_1):PAGE40_I23@CHPSET_LIB.SKX_EXT_B(CHIPS)':
 'VSS'<712>: CDS_PINID='VSS(712)';
NODE_NAME     U5D1 AU74
 '@BASEBOARD_FAB2_LIB.BASEBOARD_FAB2(SCH_1):PAGE40_I23@CHPSET_LIB.SKX_EXT_B(CHIPS)':
 'VSS'<713>: CDS_PINID='VSS(713)';
NODE_NAME     U5D1 AU68
 '@BASEBOARD_FAB2_LIB.BASEBOARD_FAB2(SCH_1):PAGE40_I23@CHPSET_LIB.SKX_EXT_B(CHIPS)':
 'VSS'<714>: CDS_PINID='VSS(714)';
NODE_NAME     U5D1 AU64
 '@BASEBOARD_FAB2_LIB.BASEBOARD_FAB2(SCH_1):PAGE40_I23@CHPSET_LIB.SKX_EXT_B(CHIPS)':
 'VSS'<715>: CDS_PINID='VSS(715)';
NODE_NAME     U5D1 AU62
 '@BASEBOARD_FAB2_LIB.BASEBOARD_FAB2(SCH_1):PAGE40_I23@CHPSET_LIB.SKX_EXT_B(CHIPS)':
 'VSS'<716>: CDS_PINID='VSS(716)';
NODE_NAME     U5D1 AU28
 '@BASEBOARD_FAB2_LIB.BASEBOARD_FAB2(SCH_1):PAGE40_I23@CHPSET_LIB.SKX_EXT_B(CHIPS)':
 'VSS'<717>: CDS_PINID='VSS(717)';
NODE_NAME     U5D1 AU26
 '@BASEBOARD_FAB2_LIB.BASEBOARD_FAB2(SCH_1):PAGE40_I23@CHPSET_LIB.SKX_EXT_B(CHIPS)':
 'VSS'<718>: CDS_PINID='VSS(718)';
NODE_NAME     U5D1 AU6
 '@BASEBOARD_FAB2_LIB.BASEBOARD_FAB2(SCH_1):PAGE40_I23@CHPSET_LIB.SKX_EXT_B(CHIPS)':
 'VSS'<719>: CDS_PINID='VSS(719)';
NODE_NAME     U5D1 AU2
 '@BASEBOARD_FAB2_LIB.BASEBOARD_FAB2(SCH_1):PAGE40_I23@CHPSET_LIB.SKX_EXT_B(CHIPS)':
 'VSS'<720>: CDS_PINID='VSS(720)';
NODE_NAME     U5D1 AT85
 '@BASEBOARD_FAB2_LIB.BASEBOARD_FAB2(SCH_1):PAGE40_I23@CHPSET_LIB.SKX_EXT_B(CHIPS)':
 'VSS'<721>: CDS_PINID='VSS(721)';
NODE_NAME     U5D1 AT83
 '@BASEBOARD_FAB2_LIB.BASEBOARD_FAB2(SCH_1):PAGE40_I23@CHPSET_LIB.SKX_EXT_B(CHIPS)':
 'VSS'<722>: CDS_PINID='VSS(722)';
NODE_NAME     U5D1 AT77
 '@BASEBOARD_FAB2_LIB.BASEBOARD_FAB2(SCH_1):PAGE40_I23@CHPSET_LIB.SKX_EXT_B(CHIPS)':
 'VSS'<723>: CDS_PINID='VSS(723)';
NODE_NAME     U5D1 AT73
 '@BASEBOARD_FAB2_LIB.BASEBOARD_FAB2(SCH_1):PAGE40_I23@CHPSET_LIB.SKX_EXT_B(CHIPS)':
 'VSS'<724>: CDS_PINID='VSS(724)';
NODE_NAME     U5D1 AT69
 '@BASEBOARD_FAB2_LIB.BASEBOARD_FAB2(SCH_1):PAGE40_I23@CHPSET_LIB.SKX_EXT_B(CHIPS)':
 'VSS'<725>: CDS_PINID='VSS(725)';
NODE_NAME     U5D1 AT63
 '@BASEBOARD_FAB2_LIB.BASEBOARD_FAB2(SCH_1):PAGE40_I23@CHPSET_LIB.SKX_EXT_B(CHIPS)':
 'VSS'<726>: CDS_PINID='VSS(726)';
NODE_NAME     U5D1 AT61
 '@BASEBOARD_FAB2_LIB.BASEBOARD_FAB2(SCH_1):PAGE40_I23@CHPSET_LIB.SKX_EXT_B(CHIPS)':
 'VSS'<727>: CDS_PINID='VSS(727)';
NODE_NAME     U5D1 AT27
 '@BASEBOARD_FAB2_LIB.BASEBOARD_FAB2(SCH_1):PAGE40_I23@CHPSET_LIB.SKX_EXT_B(CHIPS)':
 'VSS'<728>: CDS_PINID='VSS(728)';
NODE_NAME     U5D1 AT21
 '@BASEBOARD_FAB2_LIB.BASEBOARD_FAB2(SCH_1):PAGE40_I23@CHPSET_LIB.SKX_EXT_B(CHIPS)':
 'VSS'<729>: CDS_PINID='VSS(729)';
NODE_NAME     U5D1 AT17
 '@BASEBOARD_FAB2_LIB.BASEBOARD_FAB2(SCH_1):PAGE40_I23@CHPSET_LIB.SKX_EXT_B(CHIPS)':
 'VSS'<730>: CDS_PINID='VSS(730)';
NODE_NAME     U5D1 AT15
 '@BASEBOARD_FAB2_LIB.BASEBOARD_FAB2(SCH_1):PAGE40_I23@CHPSET_LIB.SKX_EXT_B(CHIPS)':
 'VSS'<731>: CDS_PINID='VSS(731)';
NODE_NAME     U5D1 P63
 '@BASEBOARD_FAB2_LIB.BASEBOARD_FAB2(SCH_1):PAGE40_I23@CHPSET_LIB.SKX_EXT_B(CHIPS)':
 'VSS'<732>: CDS_PINID='VSS(732)';
NODE_NAME     U5D1 AC48
 '@BASEBOARD_FAB2_LIB.BASEBOARD_FAB2(SCH_1):PAGE40_I23@CHPSET_LIB.SKX_EXT_B(CHIPS)':
 'VSS'<733>: CDS_PINID='VSS(733)';
NODE_NAME     U5D1 AR78
 '@BASEBOARD_FAB2_LIB.BASEBOARD_FAB2(SCH_1):PAGE40_I23@CHPSET_LIB.SKX_EXT_B(CHIPS)':
 'VSS'<734>: CDS_PINID='VSS(734)';
NODE_NAME     U5D1 AR72
 '@BASEBOARD_FAB2_LIB.BASEBOARD_FAB2(SCH_1):PAGE40_I23@CHPSET_LIB.SKX_EXT_B(CHIPS)':
 'VSS'<735>: CDS_PINID='VSS(735)';
NODE_NAME     U5D1 AR60
 '@BASEBOARD_FAB2_LIB.BASEBOARD_FAB2(SCH_1):PAGE40_I23@CHPSET_LIB.SKX_EXT_B(CHIPS)':
 'VSS'<736>: CDS_PINID='VSS(736)';
NODE_NAME     U5D1 AR30
 '@BASEBOARD_FAB2_LIB.BASEBOARD_FAB2(SCH_1):PAGE40_I23@CHPSET_LIB.SKX_EXT_B(CHIPS)':
 'VSS'<737>: CDS_PINID='VSS(737)';
NODE_NAME     U5D1 AR24
 '@BASEBOARD_FAB2_LIB.BASEBOARD_FAB2(SCH_1):PAGE40_I23@CHPSET_LIB.SKX_EXT_B(CHIPS)':
 'VSS'<738>: CDS_PINID='VSS(738)';
NODE_NAME     U5D1 AR10
 '@BASEBOARD_FAB2_LIB.BASEBOARD_FAB2(SCH_1):PAGE40_I23@CHPSET_LIB.SKX_EXT_B(CHIPS)':
 'VSS'<739>: CDS_PINID='VSS(739)';
NODE_NAME     U5D1 AP85
 '@BASEBOARD_FAB2_LIB.BASEBOARD_FAB2(SCH_1):PAGE40_I23@CHPSET_LIB.SKX_EXT_B(CHIPS)':
 'VSS'<740>: CDS_PINID='VSS(740)';
NODE_NAME     U5D1 AP83
 '@BASEBOARD_FAB2_LIB.BASEBOARD_FAB2(SCH_1):PAGE40_I23@CHPSET_LIB.SKX_EXT_B(CHIPS)':
 'VSS'<741>: CDS_PINID='VSS(741)';
NODE_NAME     U5D1 AP81
 '@BASEBOARD_FAB2_LIB.BASEBOARD_FAB2(SCH_1):PAGE40_I23@CHPSET_LIB.SKX_EXT_B(CHIPS)':
 'VSS'<742>: CDS_PINID='VSS(742)';
NODE_NAME     U5D1 AP75
 '@BASEBOARD_FAB2_LIB.BASEBOARD_FAB2(SCH_1):PAGE40_I23@CHPSET_LIB.SKX_EXT_B(CHIPS)':
 'VSS'<743>: CDS_PINID='VSS(743)';
NODE_NAME     U5D1 AP73
 '@BASEBOARD_FAB2_LIB.BASEBOARD_FAB2(SCH_1):PAGE40_I23@CHPSET_LIB.SKX_EXT_B(CHIPS)':
 'VSS'<744>: CDS_PINID='VSS(744)';
NODE_NAME     U5D1 AP69
 '@BASEBOARD_FAB2_LIB.BASEBOARD_FAB2(SCH_1):PAGE40_I23@CHPSET_LIB.SKX_EXT_B(CHIPS)':
 'VSS'<745>: CDS_PINID='VSS(745)';
NODE_NAME     U5D1 AP67
 '@BASEBOARD_FAB2_LIB.BASEBOARD_FAB2(SCH_1):PAGE40_I23@CHPSET_LIB.SKX_EXT_B(CHIPS)':
 'VSS'<746>: CDS_PINID='VSS(746)';
NODE_NAME     U5D1 AP65
 '@BASEBOARD_FAB2_LIB.BASEBOARD_FAB2(SCH_1):PAGE40_I23@CHPSET_LIB.SKX_EXT_B(CHIPS)':
 'VSS'<747>: CDS_PINID='VSS(747)';
NODE_NAME     U5D1 AP63
 '@BASEBOARD_FAB2_LIB.BASEBOARD_FAB2(SCH_1):PAGE40_I23@CHPSET_LIB.SKX_EXT_B(CHIPS)':
 'VSS'<748>: CDS_PINID='VSS(748)';
NODE_NAME     U5D1 AP59
 '@BASEBOARD_FAB2_LIB.BASEBOARD_FAB2(SCH_1):PAGE40_I23@CHPSET_LIB.SKX_EXT_B(CHIPS)':
 'VSS'<749>: CDS_PINID='VSS(749)';
NODE_NAME     U5D1 AP31
 '@BASEBOARD_FAB2_LIB.BASEBOARD_FAB2(SCH_1):PAGE40_I23@CHPSET_LIB.SKX_EXT_B(CHIPS)':
 'VSS'<750>: CDS_PINID='VSS(750)';
NODE_NAME     U5D1 AP19
 '@BASEBOARD_FAB2_LIB.BASEBOARD_FAB2(SCH_1):PAGE40_I23@CHPSET_LIB.SKX_EXT_B(CHIPS)':
 'VSS'<751>: CDS_PINID='VSS(751)';
NODE_NAME     U5D1 AP13
 '@BASEBOARD_FAB2_LIB.BASEBOARD_FAB2(SCH_1):PAGE40_I23@CHPSET_LIB.SKX_EXT_B(CHIPS)':
 'VSS'<752>: CDS_PINID='VSS(752)';
NODE_NAME     U5D1 AP9
 '@BASEBOARD_FAB2_LIB.BASEBOARD_FAB2(SCH_1):PAGE40_I23@CHPSET_LIB.SKX_EXT_B(CHIPS)':
 'VSS'<753>: CDS_PINID='VSS(753)';
NODE_NAME     U5D1 AP5
 '@BASEBOARD_FAB2_LIB.BASEBOARD_FAB2(SCH_1):PAGE40_I23@CHPSET_LIB.SKX_EXT_B(CHIPS)':
 'VSS'<754>: CDS_PINID='VSS(754)';
NODE_NAME     U5D1 AN78
 '@BASEBOARD_FAB2_LIB.BASEBOARD_FAB2(SCH_1):PAGE40_I23@CHPSET_LIB.SKX_EXT_B(CHIPS)':
 'VSS'<755>: CDS_PINID='VSS(755)';
NODE_NAME     U5D1 AN58
 '@BASEBOARD_FAB2_LIB.BASEBOARD_FAB2(SCH_1):PAGE40_I23@CHPSET_LIB.SKX_EXT_B(CHIPS)':
 'VSS'<756>: CDS_PINID='VSS(756)';
NODE_NAME     U5D1 AN28
 '@BASEBOARD_FAB2_LIB.BASEBOARD_FAB2(SCH_1):PAGE40_I23@CHPSET_LIB.SKX_EXT_B(CHIPS)':
 'VSS'<757>: CDS_PINID='VSS(757)';
NODE_NAME     U5D1 AN6
 '@BASEBOARD_FAB2_LIB.BASEBOARD_FAB2(SCH_1):PAGE40_I23@CHPSET_LIB.SKX_EXT_B(CHIPS)':
 'VSS'<758>: CDS_PINID='VSS(758)';
NODE_NAME     U5D1 AN2
 '@BASEBOARD_FAB2_LIB.BASEBOARD_FAB2(SCH_1):PAGE40_I23@CHPSET_LIB.SKX_EXT_B(CHIPS)':
 'VSS'<759>: CDS_PINID='VSS(759)';
NODE_NAME     U5D1 AM83
 '@BASEBOARD_FAB2_LIB.BASEBOARD_FAB2(SCH_1):PAGE40_I23@CHPSET_LIB.SKX_EXT_B(CHIPS)':
 'VSS'<760>: CDS_PINID='VSS(760)';
NODE_NAME     U5D1 AM79
 '@BASEBOARD_FAB2_LIB.BASEBOARD_FAB2(SCH_1):PAGE40_I23@CHPSET_LIB.SKX_EXT_B(CHIPS)':
 'VSS'<761>: CDS_PINID='VSS(761)';
NODE_NAME     U5D1 AM73
 '@BASEBOARD_FAB2_LIB.BASEBOARD_FAB2(SCH_1):PAGE40_I23@CHPSET_LIB.SKX_EXT_B(CHIPS)':
 'VSS'<762>: CDS_PINID='VSS(762)';
NODE_NAME     U5D1 AM69
 '@BASEBOARD_FAB2_LIB.BASEBOARD_FAB2(SCH_1):PAGE40_I23@CHPSET_LIB.SKX_EXT_B(CHIPS)':
 'VSS'<763>: CDS_PINID='VSS(763)';
NODE_NAME     U5D1 AM63
 '@BASEBOARD_FAB2_LIB.BASEBOARD_FAB2(SCH_1):PAGE40_I23@CHPSET_LIB.SKX_EXT_B(CHIPS)':
 'VSS'<764>: CDS_PINID='VSS(764)';
NODE_NAME     U5D1 AM57
 '@BASEBOARD_FAB2_LIB.BASEBOARD_FAB2(SCH_1):PAGE40_I23@CHPSET_LIB.SKX_EXT_B(CHIPS)':
 'VSS'<765>: CDS_PINID='VSS(765)';
NODE_NAME     U5D1 AM31
 '@BASEBOARD_FAB2_LIB.BASEBOARD_FAB2(SCH_1):PAGE40_I23@CHPSET_LIB.SKX_EXT_B(CHIPS)':
 'VSS'<766>: CDS_PINID='VSS(766)';
NODE_NAME     U5D1 AC50
 '@BASEBOARD_FAB2_LIB.BASEBOARD_FAB2(SCH_1):PAGE40_I23@CHPSET_LIB.SKX_EXT_B(CHIPS)':
 'VSS'<767>: CDS_PINID='VSS(767)';
NODE_NAME     U5D1 AM1
 '@BASEBOARD_FAB2_LIB.BASEBOARD_FAB2(SCH_1):PAGE40_I23@CHPSET_LIB.SKX_EXT_B(CHIPS)':
 'VSS'<768>: CDS_PINID='VSS(768)';
NODE_NAME     U5D1 AL86
 '@BASEBOARD_FAB2_LIB.BASEBOARD_FAB2(SCH_1):PAGE40_I23@CHPSET_LIB.SKX_EXT_B(CHIPS)':
 'VSS'<769>: CDS_PINID='VSS(769)';
NODE_NAME     U5D1 AL82
 '@BASEBOARD_FAB2_LIB.BASEBOARD_FAB2(SCH_1):PAGE40_I23@CHPSET_LIB.SKX_EXT_B(CHIPS)':
 'VSS'<770>: CDS_PINID='VSS(770)';
NODE_NAME     U5D1 AL80
 '@BASEBOARD_FAB2_LIB.BASEBOARD_FAB2(SCH_1):PAGE40_I23@CHPSET_LIB.SKX_EXT_B(CHIPS)':
 'VSS'<771>: CDS_PINID='VSS(771)';
NODE_NAME     U5D1 AL78
 '@BASEBOARD_FAB2_LIB.BASEBOARD_FAB2(SCH_1):PAGE40_I23@CHPSET_LIB.SKX_EXT_B(CHIPS)':
 'VSS'<772>: CDS_PINID='VSS(772)';
NODE_NAME     U5D1 AL76
 '@BASEBOARD_FAB2_LIB.BASEBOARD_FAB2(SCH_1):PAGE40_I23@CHPSET_LIB.SKX_EXT_B(CHIPS)':
 'VSS'<773>: CDS_PINID='VSS(773)';
NODE_NAME     U5D1 P49
 '@BASEBOARD_FAB2_LIB.BASEBOARD_FAB2(SCH_1):PAGE41_I283@CHPSET_LIB.SKX_EXT_B(CHIPS)':
 'VSS'<454>: CDS_PINID='VSS(454)';
NODE_NAME     U5D1 CJ12
 '@BASEBOARD_FAB2_LIB.BASEBOARD_FAB2(SCH_1):PAGE41_I283@CHPSET_LIB.SKX_EXT_B(CHIPS)':
 'VSS'<455>: CDS_PINID='VSS(455)';
NODE_NAME     U5D1 CJ10
 '@BASEBOARD_FAB2_LIB.BASEBOARD_FAB2(SCH_1):PAGE41_I283@CHPSET_LIB.SKX_EXT_B(CHIPS)':
 'VSS'<456>: CDS_PINID='VSS(456)';
NODE_NAME     U5D1 CJ8
 '@BASEBOARD_FAB2_LIB.BASEBOARD_FAB2(SCH_1):PAGE41_I283@CHPSET_LIB.SKX_EXT_B(CHIPS)':
 'VSS'<457>: CDS_PINID='VSS(457)';
NODE_NAME     U5D1 CJ6
 '@BASEBOARD_FAB2_LIB.BASEBOARD_FAB2(SCH_1):PAGE41_I283@CHPSET_LIB.SKX_EXT_B(CHIPS)':
 'VSS'<458>: CDS_PINID='VSS(458)';
NODE_NAME     U5D1 CJ2
 '@BASEBOARD_FAB2_LIB.BASEBOARD_FAB2(SCH_1):PAGE41_I283@CHPSET_LIB.SKX_EXT_B(CHIPS)':
 'VSS'<459>: CDS_PINID='VSS(459)';
NODE_NAME     U5D1 CH83
 '@BASEBOARD_FAB2_LIB.BASEBOARD_FAB2(SCH_1):PAGE41_I283@CHPSET_LIB.SKX_EXT_B(CHIPS)':
 'VSS'<460>: CDS_PINID='VSS(460)';
NODE_NAME     U5D1 CH81
 '@BASEBOARD_FAB2_LIB.BASEBOARD_FAB2(SCH_1):PAGE41_I283@CHPSET_LIB.SKX_EXT_B(CHIPS)':
 'VSS'<461>: CDS_PINID='VSS(461)';
NODE_NAME     U5D1 CH79
 '@BASEBOARD_FAB2_LIB.BASEBOARD_FAB2(SCH_1):PAGE41_I283@CHPSET_LIB.SKX_EXT_B(CHIPS)':
 'VSS'<462>: CDS_PINID='VSS(462)';
NODE_NAME     U5D1 CH73
 '@BASEBOARD_FAB2_LIB.BASEBOARD_FAB2(SCH_1):PAGE41_I283@CHPSET_LIB.SKX_EXT_B(CHIPS)':
 'VSS'<463>: CDS_PINID='VSS(463)';
NODE_NAME     U5D1 CH67
 '@BASEBOARD_FAB2_LIB.BASEBOARD_FAB2(SCH_1):PAGE41_I283@CHPSET_LIB.SKX_EXT_B(CHIPS)':
 'VSS'<464>: CDS_PINID='VSS(464)';
NODE_NAME     U5D1 CH63
 '@BASEBOARD_FAB2_LIB.BASEBOARD_FAB2(SCH_1):PAGE41_I283@CHPSET_LIB.SKX_EXT_B(CHIPS)':
 'VSS'<465>: CDS_PINID='VSS(465)';
NODE_NAME     U5D1 CH19
 '@BASEBOARD_FAB2_LIB.BASEBOARD_FAB2(SCH_1):PAGE41_I283@CHPSET_LIB.SKX_EXT_B(CHIPS)':
 'VSS'<466>: CDS_PINID='VSS(466)';
NODE_NAME     U5D1 CH15
 '@BASEBOARD_FAB2_LIB.BASEBOARD_FAB2(SCH_1):PAGE41_I283@CHPSET_LIB.SKX_EXT_B(CHIPS)':
 'VSS'<467>: CDS_PINID='VSS(467)';
NODE_NAME     U5D1 CH3
 '@BASEBOARD_FAB2_LIB.BASEBOARD_FAB2(SCH_1):PAGE41_I283@CHPSET_LIB.SKX_EXT_B(CHIPS)':
 'VSS'<468>: CDS_PINID='VSS(468)';
NODE_NAME     U5D1 CH1
 '@BASEBOARD_FAB2_LIB.BASEBOARD_FAB2(SCH_1):PAGE41_I283@CHPSET_LIB.SKX_EXT_B(CHIPS)':
 'VSS'<469>: CDS_PINID='VSS(469)';
NODE_NAME     U5D1 CG80
 '@BASEBOARD_FAB2_LIB.BASEBOARD_FAB2(SCH_1):PAGE41_I283@CHPSET_LIB.SKX_EXT_B(CHIPS)':
 'VSS'<470>: CDS_PINID='VSS(470)';
NODE_NAME     U5D1 CG72
 '@BASEBOARD_FAB2_LIB.BASEBOARD_FAB2(SCH_1):PAGE41_I283@CHPSET_LIB.SKX_EXT_B(CHIPS)':
 'VSS'<471>: CDS_PINID='VSS(471)';
NODE_NAME     U5D1 CG68
 '@BASEBOARD_FAB2_LIB.BASEBOARD_FAB2(SCH_1):PAGE41_I283@CHPSET_LIB.SKX_EXT_B(CHIPS)':
 'VSS'<472>: CDS_PINID='VSS(472)';
NODE_NAME     U5D1 CG62
 '@BASEBOARD_FAB2_LIB.BASEBOARD_FAB2(SCH_1):PAGE41_I283@CHPSET_LIB.SKX_EXT_B(CHIPS)':
 'VSS'<473>: CDS_PINID='VSS(473)';
NODE_NAME     U5D1 CG22
 '@BASEBOARD_FAB2_LIB.BASEBOARD_FAB2(SCH_1):PAGE41_I283@CHPSET_LIB.SKX_EXT_B(CHIPS)':
 'VSS'<474>: CDS_PINID='VSS(474)';
NODE_NAME     U5D1 CG18
 '@BASEBOARD_FAB2_LIB.BASEBOARD_FAB2(SCH_1):PAGE41_I283@CHPSET_LIB.SKX_EXT_B(CHIPS)':
 'VSS'<475>: CDS_PINID='VSS(475)';
NODE_NAME     U5D1 P51
 '@BASEBOARD_FAB2_LIB.BASEBOARD_FAB2(SCH_1):PAGE41_I283@CHPSET_LIB.SKX_EXT_B(CHIPS)':
 'VSS'<476>: CDS_PINID='VSS(476)';
NODE_NAME     U5D1 CF83
 '@BASEBOARD_FAB2_LIB.BASEBOARD_FAB2(SCH_1):PAGE41_I283@CHPSET_LIB.SKX_EXT_B(CHIPS)':
 'VSS'<477>: CDS_PINID='VSS(477)';
NODE_NAME     U5D1 CF77
 '@BASEBOARD_FAB2_LIB.BASEBOARD_FAB2(SCH_1):PAGE41_I283@CHPSET_LIB.SKX_EXT_B(CHIPS)':
 'VSS'<478>: CDS_PINID='VSS(478)';
NODE_NAME     U5D1 CF71
 '@BASEBOARD_FAB2_LIB.BASEBOARD_FAB2(SCH_1):PAGE41_I283@CHPSET_LIB.SKX_EXT_B(CHIPS)':
 'VSS'<479>: CDS_PINID='VSS(479)';
NODE_NAME     U5D1 CF69
 '@BASEBOARD_FAB2_LIB.BASEBOARD_FAB2(SCH_1):PAGE41_I283@CHPSET_LIB.SKX_EXT_B(CHIPS)':
 'VSS'<480>: CDS_PINID='VSS(480)';
NODE_NAME     U5D1 CF63
 '@BASEBOARD_FAB2_LIB.BASEBOARD_FAB2(SCH_1):PAGE41_I283@CHPSET_LIB.SKX_EXT_B(CHIPS)':
 'VSS'<481>: CDS_PINID='VSS(481)';
NODE_NAME     U5D1 CF9
 '@BASEBOARD_FAB2_LIB.BASEBOARD_FAB2(SCH_1):PAGE41_I283@CHPSET_LIB.SKX_EXT_B(CHIPS)':
 'VSS'<482>: CDS_PINID='VSS(482)';
NODE_NAME     U5D1 P53
 '@BASEBOARD_FAB2_LIB.BASEBOARD_FAB2(SCH_1):PAGE41_I283@CHPSET_LIB.SKX_EXT_B(CHIPS)':
 'VSS'<483>: CDS_PINID='VSS(483)';
NODE_NAME     U5D1 CE82
 '@BASEBOARD_FAB2_LIB.BASEBOARD_FAB2(SCH_1):PAGE41_I283@CHPSET_LIB.SKX_EXT_B(CHIPS)':
 'VSS'<484>: CDS_PINID='VSS(484)';
NODE_NAME     U5D1 CE70
 '@BASEBOARD_FAB2_LIB.BASEBOARD_FAB2(SCH_1):PAGE41_I283@CHPSET_LIB.SKX_EXT_B(CHIPS)':
 'VSS'<485>: CDS_PINID='VSS(485)';
NODE_NAME     U5D1 CE62
 '@BASEBOARD_FAB2_LIB.BASEBOARD_FAB2(SCH_1):PAGE41_I283@CHPSET_LIB.SKX_EXT_B(CHIPS)':
 'VSS'<486>: CDS_PINID='VSS(486)';
NODE_NAME     U5D1 CE26
 '@BASEBOARD_FAB2_LIB.BASEBOARD_FAB2(SCH_1):PAGE41_I283@CHPSET_LIB.SKX_EXT_B(CHIPS)':
 'VSS'<487>: CDS_PINID='VSS(487)';
NODE_NAME     U5D1 CE20
 '@BASEBOARD_FAB2_LIB.BASEBOARD_FAB2(SCH_1):PAGE41_I283@CHPSET_LIB.SKX_EXT_B(CHIPS)':
 'VSS'<488>: CDS_PINID='VSS(488)';
NODE_NAME     U5D1 CE14
 '@BASEBOARD_FAB2_LIB.BASEBOARD_FAB2(SCH_1):PAGE41_I283@CHPSET_LIB.SKX_EXT_B(CHIPS)':
 'VSS'<489>: CDS_PINID='VSS(489)';
NODE_NAME     U5D1 CE10
 '@BASEBOARD_FAB2_LIB.BASEBOARD_FAB2(SCH_1):PAGE41_I283@CHPSET_LIB.SKX_EXT_B(CHIPS)':
 'VSS'<490>: CDS_PINID='VSS(490)';
NODE_NAME     U5D1 CD81
 '@BASEBOARD_FAB2_LIB.BASEBOARD_FAB2(SCH_1):PAGE41_I283@CHPSET_LIB.SKX_EXT_B(CHIPS)':
 'VSS'<491>: CDS_PINID='VSS(491)';
NODE_NAME     U5D1 CD79
 '@BASEBOARD_FAB2_LIB.BASEBOARD_FAB2(SCH_1):PAGE41_I283@CHPSET_LIB.SKX_EXT_B(CHIPS)':
 'VSS'<492>: CDS_PINID='VSS(492)';
NODE_NAME     U5D1 CD77
 '@BASEBOARD_FAB2_LIB.BASEBOARD_FAB2(SCH_1):PAGE41_I283@CHPSET_LIB.SKX_EXT_B(CHIPS)':
 'VSS'<493>: CDS_PINID='VSS(493)';
NODE_NAME     U5D1 CD75
 '@BASEBOARD_FAB2_LIB.BASEBOARD_FAB2(SCH_1):PAGE41_I283@CHPSET_LIB.SKX_EXT_B(CHIPS)':
 'VSS'<494>: CDS_PINID='VSS(494)';
NODE_NAME     U5D1 CD73
 '@BASEBOARD_FAB2_LIB.BASEBOARD_FAB2(SCH_1):PAGE41_I283@CHPSET_LIB.SKX_EXT_B(CHIPS)':
 'VSS'<495>: CDS_PINID='VSS(495)';
NODE_NAME     U5D1 CD63
 '@BASEBOARD_FAB2_LIB.BASEBOARD_FAB2(SCH_1):PAGE41_I283@CHPSET_LIB.SKX_EXT_B(CHIPS)':
 'VSS'<496>: CDS_PINID='VSS(496)';
NODE_NAME     U5D1 CD13
 '@BASEBOARD_FAB2_LIB.BASEBOARD_FAB2(SCH_1):PAGE41_I283@CHPSET_LIB.SKX_EXT_B(CHIPS)':
 'VSS'<497>: CDS_PINID='VSS(497)';
NODE_NAME     U5D1 CD5
 '@BASEBOARD_FAB2_LIB.BASEBOARD_FAB2(SCH_1):PAGE41_I283@CHPSET_LIB.SKX_EXT_B(CHIPS)':
 'VSS'<498>: CDS_PINID='VSS(498)';
NODE_NAME     U5D1 CC82
 '@BASEBOARD_FAB2_LIB.BASEBOARD_FAB2(SCH_1):PAGE41_I283@CHPSET_LIB.SKX_EXT_B(CHIPS)':
 'VSS'<499>: CDS_PINID='VSS(499)';
NODE_NAME     U5D1 CC80
 '@BASEBOARD_FAB2_LIB.BASEBOARD_FAB2(SCH_1):PAGE41_I283@CHPSET_LIB.SKX_EXT_B(CHIPS)':
 'VSS'<500>: CDS_PINID='VSS(500)';
NODE_NAME     U5D1 CC78
 '@BASEBOARD_FAB2_LIB.BASEBOARD_FAB2(SCH_1):PAGE41_I283@CHPSET_LIB.SKX_EXT_B(CHIPS)':
 'VSS'<501>: CDS_PINID='VSS(501)';
NODE_NAME     U5D1 CC76
 '@BASEBOARD_FAB2_LIB.BASEBOARD_FAB2(SCH_1):PAGE41_I283@CHPSET_LIB.SKX_EXT_B(CHIPS)':
 'VSS'<502>: CDS_PINID='VSS(502)';
NODE_NAME     U5D1 CC74
 '@BASEBOARD_FAB2_LIB.BASEBOARD_FAB2(SCH_1):PAGE41_I283@CHPSET_LIB.SKX_EXT_B(CHIPS)':
 'VSS'<503>: CDS_PINID='VSS(503)';
NODE_NAME     U5D1 CC72
 '@BASEBOARD_FAB2_LIB.BASEBOARD_FAB2(SCH_1):PAGE41_I283@CHPSET_LIB.SKX_EXT_B(CHIPS)':
 'VSS'<504>: CDS_PINID='VSS(504)';
NODE_NAME     U5D1 CC64
 '@BASEBOARD_FAB2_LIB.BASEBOARD_FAB2(SCH_1):PAGE41_I283@CHPSET_LIB.SKX_EXT_B(CHIPS)':
 'VSS'<505>: CDS_PINID='VSS(505)';
NODE_NAME     U5D1 CC24
 '@BASEBOARD_FAB2_LIB.BASEBOARD_FAB2(SCH_1):PAGE41_I283@CHPSET_LIB.SKX_EXT_B(CHIPS)':
 'VSS'<506>: CDS_PINID='VSS(506)';
NODE_NAME     U5D1 CC18
 '@BASEBOARD_FAB2_LIB.BASEBOARD_FAB2(SCH_1):PAGE41_I283@CHPSET_LIB.SKX_EXT_B(CHIPS)':
 'VSS'<507>: CDS_PINID='VSS(507)';
NODE_NAME     U5D1 CC16
 '@BASEBOARD_FAB2_LIB.BASEBOARD_FAB2(SCH_1):PAGE41_I283@CHPSET_LIB.SKX_EXT_B(CHIPS)':
 'VSS'<508>: CDS_PINID='VSS(508)';
NODE_NAME     U5D1 CC4
 '@BASEBOARD_FAB2_LIB.BASEBOARD_FAB2(SCH_1):PAGE41_I283@CHPSET_LIB.SKX_EXT_B(CHIPS)':
 'VSS'<509>: CDS_PINID='VSS(509)';
NODE_NAME     U5D1 CB71
 '@BASEBOARD_FAB2_LIB.BASEBOARD_FAB2(SCH_1):PAGE41_I283@CHPSET_LIB.SKX_EXT_B(CHIPS)':
 'VSS'<510>: CDS_PINID='VSS(510)';
NODE_NAME     U5D1 CB63
 '@BASEBOARD_FAB2_LIB.BASEBOARD_FAB2(SCH_1):PAGE41_I283@CHPSET_LIB.SKX_EXT_B(CHIPS)':
 'VSS'<511>: CDS_PINID='VSS(511)';
NODE_NAME     U5D1 CB27
 '@BASEBOARD_FAB2_LIB.BASEBOARD_FAB2(SCH_1):PAGE41_I283@CHPSET_LIB.SKX_EXT_B(CHIPS)':
 'VSS'<512>: CDS_PINID='VSS(512)';
NODE_NAME     U5D1 CB9
 '@BASEBOARD_FAB2_LIB.BASEBOARD_FAB2(SCH_1):PAGE41_I283@CHPSET_LIB.SKX_EXT_B(CHIPS)':
 'VSS'<513>: CDS_PINID='VSS(513)';
NODE_NAME     U5D1 CB7
 '@BASEBOARD_FAB2_LIB.BASEBOARD_FAB2(SCH_1):PAGE41_I283@CHPSET_LIB.SKX_EXT_B(CHIPS)':
 'VSS'<514>: CDS_PINID='VSS(514)';
NODE_NAME     U5D1 CA70
 '@BASEBOARD_FAB2_LIB.BASEBOARD_FAB2(SCH_1):PAGE41_I283@CHPSET_LIB.SKX_EXT_B(CHIPS)':
 'VSS'<515>: CDS_PINID='VSS(515)';
NODE_NAME     U5D1 CA68
 '@BASEBOARD_FAB2_LIB.BASEBOARD_FAB2(SCH_1):PAGE41_I283@CHPSET_LIB.SKX_EXT_B(CHIPS)':
 'VSS'<516>: CDS_PINID='VSS(516)';
NODE_NAME     U5D1 CA66
 '@BASEBOARD_FAB2_LIB.BASEBOARD_FAB2(SCH_1):PAGE41_I283@CHPSET_LIB.SKX_EXT_B(CHIPS)':
 'VSS'<517>: CDS_PINID='VSS(517)';
NODE_NAME     U5D1 CA64
 '@BASEBOARD_FAB2_LIB.BASEBOARD_FAB2(SCH_1):PAGE41_I283@CHPSET_LIB.SKX_EXT_B(CHIPS)':
 'VSS'<518>: CDS_PINID='VSS(518)';
NODE_NAME     U5D1 CA26
 '@BASEBOARD_FAB2_LIB.BASEBOARD_FAB2(SCH_1):PAGE41_I283@CHPSET_LIB.SKX_EXT_B(CHIPS)':
 'VSS'<519>: CDS_PINID='VSS(519)';
NODE_NAME     U5D1 CA18
 '@BASEBOARD_FAB2_LIB.BASEBOARD_FAB2(SCH_1):PAGE41_I283@CHPSET_LIB.SKX_EXT_B(CHIPS)':
 'VSS'<520>: CDS_PINID='VSS(520)';
NODE_NAME     U5D1 CA14
 '@BASEBOARD_FAB2_LIB.BASEBOARD_FAB2(SCH_1):PAGE41_I283@CHPSET_LIB.SKX_EXT_B(CHIPS)':
 'VSS'<521>: CDS_PINID='VSS(521)';
NODE_NAME     U5D1 CA10
 '@BASEBOARD_FAB2_LIB.BASEBOARD_FAB2(SCH_1):PAGE41_I283@CHPSET_LIB.SKX_EXT_B(CHIPS)':
 'VSS'<522>: CDS_PINID='VSS(522)';
NODE_NAME     U5D1 CA8
 '@BASEBOARD_FAB2_LIB.BASEBOARD_FAB2(SCH_1):PAGE41_I283@CHPSET_LIB.SKX_EXT_B(CHIPS)':
 'VSS'<523>: CDS_PINID='VSS(523)';
NODE_NAME     U5D1 CA6
 '@BASEBOARD_FAB2_LIB.BASEBOARD_FAB2(SCH_1):PAGE41_I283@CHPSET_LIB.SKX_EXT_B(CHIPS)':
 'VSS'<524>: CDS_PINID='VSS(524)';
NODE_NAME     U5D1 CA2
 '@BASEBOARD_FAB2_LIB.BASEBOARD_FAB2(SCH_1):PAGE41_I283@CHPSET_LIB.SKX_EXT_B(CHIPS)':
 'VSS'<525>: CDS_PINID='VSS(525)';
NODE_NAME     U5D1 BY71
 '@BASEBOARD_FAB2_LIB.BASEBOARD_FAB2(SCH_1):PAGE41_I283@CHPSET_LIB.SKX_EXT_B(CHIPS)':
 'VSS'<526>: CDS_PINID='VSS(526)';
NODE_NAME     U5D1 BY69
 '@BASEBOARD_FAB2_LIB.BASEBOARD_FAB2(SCH_1):PAGE41_I283@CHPSET_LIB.SKX_EXT_B(CHIPS)':
 'VSS'<527>: CDS_PINID='VSS(527)';
NODE_NAME     U5D1 BY67
 '@BASEBOARD_FAB2_LIB.BASEBOARD_FAB2(SCH_1):PAGE41_I283@CHPSET_LIB.SKX_EXT_B(CHIPS)':
 'VSS'<528>: CDS_PINID='VSS(528)';
NODE_NAME     U5D1 BY65
 '@BASEBOARD_FAB2_LIB.BASEBOARD_FAB2(SCH_1):PAGE41_I283@CHPSET_LIB.SKX_EXT_B(CHIPS)':
 'VSS'<529>: CDS_PINID='VSS(529)';
NODE_NAME     U5D1 BY63
 '@BASEBOARD_FAB2_LIB.BASEBOARD_FAB2(SCH_1):PAGE41_I283@CHPSET_LIB.SKX_EXT_B(CHIPS)':
 'VSS'<530>: CDS_PINID='VSS(530)';
NODE_NAME     U5D1 BY23
 '@BASEBOARD_FAB2_LIB.BASEBOARD_FAB2(SCH_1):PAGE41_I283@CHPSET_LIB.SKX_EXT_B(CHIPS)':
 'VSS'<531>: CDS_PINID='VSS(531)';
NODE_NAME     U5D1 BY13
 '@BASEBOARD_FAB2_LIB.BASEBOARD_FAB2(SCH_1):PAGE41_I283@CHPSET_LIB.SKX_EXT_B(CHIPS)':
 'VSS'<532>: CDS_PINID='VSS(532)';
NODE_NAME     U5D1 BY11
 '@BASEBOARD_FAB2_LIB.BASEBOARD_FAB2(SCH_1):PAGE41_I283@CHPSET_LIB.SKX_EXT_B(CHIPS)':
 'VSS'<533>: CDS_PINID='VSS(533)';
NODE_NAME     U5D1 BW82
 '@BASEBOARD_FAB2_LIB.BASEBOARD_FAB2(SCH_1):PAGE41_I283@CHPSET_LIB.SKX_EXT_B(CHIPS)':
 'VSS'<534>: CDS_PINID='VSS(534)';
NODE_NAME     U5D1 BW80
 '@BASEBOARD_FAB2_LIB.BASEBOARD_FAB2(SCH_1):PAGE41_I283@CHPSET_LIB.SKX_EXT_B(CHIPS)':
 'VSS'<535>: CDS_PINID='VSS(535)';
NODE_NAME     U5D1 BW78
 '@BASEBOARD_FAB2_LIB.BASEBOARD_FAB2(SCH_1):PAGE41_I283@CHPSET_LIB.SKX_EXT_B(CHIPS)':
 'VSS'<536>: CDS_PINID='VSS(536)';
NODE_NAME     U5D1 BW76
 '@BASEBOARD_FAB2_LIB.BASEBOARD_FAB2(SCH_1):PAGE41_I283@CHPSET_LIB.SKX_EXT_B(CHIPS)':
 'VSS'<537>: CDS_PINID='VSS(537)';
NODE_NAME     U5D1 BW74
 '@BASEBOARD_FAB2_LIB.BASEBOARD_FAB2(SCH_1):PAGE41_I283@CHPSET_LIB.SKX_EXT_B(CHIPS)':
 'VSS'<538>: CDS_PINID='VSS(538)';
NODE_NAME     U5D1 BW72
 '@BASEBOARD_FAB2_LIB.BASEBOARD_FAB2(SCH_1):PAGE41_I283@CHPSET_LIB.SKX_EXT_B(CHIPS)':
 'VSS'<539>: CDS_PINID='VSS(539)';
NODE_NAME     U5D1 BW26
 '@BASEBOARD_FAB2_LIB.BASEBOARD_FAB2(SCH_1):PAGE41_I283@CHPSET_LIB.SKX_EXT_B(CHIPS)':
 'VSS'<540>: CDS_PINID='VSS(540)';
NODE_NAME     U5D1 BW18
 '@BASEBOARD_FAB2_LIB.BASEBOARD_FAB2(SCH_1):PAGE41_I283@CHPSET_LIB.SKX_EXT_B(CHIPS)':
 'VSS'<541>: CDS_PINID='VSS(541)';
NODE_NAME     U5D1 BW16
 '@BASEBOARD_FAB2_LIB.BASEBOARD_FAB2(SCH_1):PAGE41_I283@CHPSET_LIB.SKX_EXT_B(CHIPS)':
 'VSS'<542>: CDS_PINID='VSS(542)';
NODE_NAME     U5D1 BW14
 '@BASEBOARD_FAB2_LIB.BASEBOARD_FAB2(SCH_1):PAGE41_I283@CHPSET_LIB.SKX_EXT_B(CHIPS)':
 'VSS'<543>: CDS_PINID='VSS(543)';
NODE_NAME     U5D1 BW12
 '@BASEBOARD_FAB2_LIB.BASEBOARD_FAB2(SCH_1):PAGE41_I283@CHPSET_LIB.SKX_EXT_B(CHIPS)':
 'VSS'<544>: CDS_PINID='VSS(544)';
NODE_NAME     U5D1 P55
 '@BASEBOARD_FAB2_LIB.BASEBOARD_FAB2(SCH_1):PAGE41_I283@CHPSET_LIB.SKX_EXT_B(CHIPS)':
 'VSS'<545>: CDS_PINID='VSS(545)';
NODE_NAME     U5D1 BW6
 '@BASEBOARD_FAB2_LIB.BASEBOARD_FAB2(SCH_1):PAGE41_I283@CHPSET_LIB.SKX_EXT_B(CHIPS)':
 'VSS'<546>: CDS_PINID='VSS(546)';
NODE_NAME     U5D1 BV25
 '@BASEBOARD_FAB2_LIB.BASEBOARD_FAB2(SCH_1):PAGE41_I283@CHPSET_LIB.SKX_EXT_B(CHIPS)':
 'VSS'<547>: CDS_PINID='VSS(547)';
NODE_NAME     U5D1 BV17
 '@BASEBOARD_FAB2_LIB.BASEBOARD_FAB2(SCH_1):PAGE41_I283@CHPSET_LIB.SKX_EXT_B(CHIPS)':
 'VSS'<548>: CDS_PINID='VSS(548)';
NODE_NAME     U5D1 BU10
 '@BASEBOARD_FAB2_LIB.BASEBOARD_FAB2(SCH_1):PAGE41_I283@CHPSET_LIB.SKX_EXT_B(CHIPS)':
 'VSS'<549>: CDS_PINID='VSS(549)';
NODE_NAME     U5D1 BV5
 '@BASEBOARD_FAB2_LIB.BASEBOARD_FAB2(SCH_1):PAGE41_I283@CHPSET_LIB.SKX_EXT_B(CHIPS)':
 'VSS'<550>: CDS_PINID='VSS(550)';
NODE_NAME     U5D1 BU8
 '@BASEBOARD_FAB2_LIB.BASEBOARD_FAB2(SCH_1):PAGE41_I283@CHPSET_LIB.SKX_EXT_B(CHIPS)':
 'VSS'<551>: CDS_PINID='VSS(551)';
NODE_NAME     U5D1 BT25
 '@BASEBOARD_FAB2_LIB.BASEBOARD_FAB2(SCH_1):PAGE41_I283@CHPSET_LIB.SKX_EXT_B(CHIPS)':
 'VSS'<552>: CDS_PINID='VSS(552)';
NODE_NAME     U5D1 BT23
 '@BASEBOARD_FAB2_LIB.BASEBOARD_FAB2(SCH_1):PAGE41_I283@CHPSET_LIB.SKX_EXT_B(CHIPS)':
 'VSS'<553>: CDS_PINID='VSS(553)';
NODE_NAME     U5D1 BT21
 '@BASEBOARD_FAB2_LIB.BASEBOARD_FAB2(SCH_1):PAGE41_I283@CHPSET_LIB.SKX_EXT_B(CHIPS)':
 'VSS'<554>: CDS_PINID='VSS(554)';
NODE_NAME     U5D1 BT5
 '@BASEBOARD_FAB2_LIB.BASEBOARD_FAB2(SCH_1):PAGE41_I283@CHPSET_LIB.SKX_EXT_B(CHIPS)':
 'VSS'<555>: CDS_PINID='VSS(555)';
NODE_NAME     U5D1 BT3
 '@BASEBOARD_FAB2_LIB.BASEBOARD_FAB2(SCH_1):PAGE41_I283@CHPSET_LIB.SKX_EXT_B(CHIPS)':
 'VSS'<556>: CDS_PINID='VSS(556)';
NODE_NAME     U5D1 BR82
 '@BASEBOARD_FAB2_LIB.BASEBOARD_FAB2(SCH_1):PAGE41_I283@CHPSET_LIB.SKX_EXT_B(CHIPS)':
 'VSS'<557>: CDS_PINID='VSS(557)';
NODE_NAME     U5D1 BR80
 '@BASEBOARD_FAB2_LIB.BASEBOARD_FAB2(SCH_1):PAGE41_I283@CHPSET_LIB.SKX_EXT_B(CHIPS)':
 'VSS'<558>: CDS_PINID='VSS(558)';
NODE_NAME     U5D1 BR78
 '@BASEBOARD_FAB2_LIB.BASEBOARD_FAB2(SCH_1):PAGE41_I283@CHPSET_LIB.SKX_EXT_B(CHIPS)':
 'VSS'<559>: CDS_PINID='VSS(559)';
NODE_NAME     U5D1 BR76
 '@BASEBOARD_FAB2_LIB.BASEBOARD_FAB2(SCH_1):PAGE41_I283@CHPSET_LIB.SKX_EXT_B(CHIPS)':
 'VSS'<560>: CDS_PINID='VSS(560)';
NODE_NAME     U5D1 BR74
 '@BASEBOARD_FAB2_LIB.BASEBOARD_FAB2(SCH_1):PAGE41_I283@CHPSET_LIB.SKX_EXT_B(CHIPS)':
 'VSS'<561>: CDS_PINID='VSS(561)';
NODE_NAME     U5D1 BR72
 '@BASEBOARD_FAB2_LIB.BASEBOARD_FAB2(SCH_1):PAGE41_I283@CHPSET_LIB.SKX_EXT_B(CHIPS)':
 'VSS'<562>: CDS_PINID='VSS(562)';
NODE_NAME     U5D1 BR70
 '@BASEBOARD_FAB2_LIB.BASEBOARD_FAB2(SCH_1):PAGE41_I283@CHPSET_LIB.SKX_EXT_B(CHIPS)':
 'VSS'<563>: CDS_PINID='VSS(563)';
NODE_NAME     U5D1 BR68
 '@BASEBOARD_FAB2_LIB.BASEBOARD_FAB2(SCH_1):PAGE41_I283@CHPSET_LIB.SKX_EXT_B(CHIPS)':
 'VSS'<564>: CDS_PINID='VSS(564)';
NODE_NAME     U5D1 BR66
 '@BASEBOARD_FAB2_LIB.BASEBOARD_FAB2(SCH_1):PAGE41_I283@CHPSET_LIB.SKX_EXT_B(CHIPS)':
 'VSS'<565>: CDS_PINID='VSS(565)';
NODE_NAME     U5D1 BR64
 '@BASEBOARD_FAB2_LIB.BASEBOARD_FAB2(SCH_1):PAGE41_I283@CHPSET_LIB.SKX_EXT_B(CHIPS)':
 'VSS'<566>: CDS_PINID='VSS(566)';
NODE_NAME     U5D1 P57
 '@BASEBOARD_FAB2_LIB.BASEBOARD_FAB2(SCH_1):PAGE41_I283@CHPSET_LIB.SKX_EXT_B(CHIPS)':
 'VSS'<567>: CDS_PINID='VSS(567)';
NODE_NAME     U5D1 BR16
 '@BASEBOARD_FAB2_LIB.BASEBOARD_FAB2(SCH_1):PAGE41_I283@CHPSET_LIB.SKX_EXT_B(CHIPS)':
 'VSS'<568>: CDS_PINID='VSS(568)';
NODE_NAME     U5D1 BR10
 '@BASEBOARD_FAB2_LIB.BASEBOARD_FAB2(SCH_1):PAGE41_I283@CHPSET_LIB.SKX_EXT_B(CHIPS)':
 'VSS'<569>: CDS_PINID='VSS(569)';
NODE_NAME     U5D1 BR6
 '@BASEBOARD_FAB2_LIB.BASEBOARD_FAB2(SCH_1):PAGE41_I283@CHPSET_LIB.SKX_EXT_B(CHIPS)':
 'VSS'<570>: CDS_PINID='VSS(570)';
NODE_NAME     U5D1 BP27
 '@BASEBOARD_FAB2_LIB.BASEBOARD_FAB2(SCH_1):PAGE41_I283@CHPSET_LIB.SKX_EXT_B(CHIPS)':
 'VSS'<571>: CDS_PINID='VSS(571)';
NODE_NAME     U5D1 BP3
 '@BASEBOARD_FAB2_LIB.BASEBOARD_FAB2(SCH_1):PAGE41_I283@CHPSET_LIB.SKX_EXT_B(CHIPS)':
 'VSS'<572>: CDS_PINID='VSS(572)';
NODE_NAME     U5D1 BN26
 '@BASEBOARD_FAB2_LIB.BASEBOARD_FAB2(SCH_1):PAGE41_I283@CHPSET_LIB.SKX_EXT_B(CHIPS)':
 'VSS'<573>: CDS_PINID='VSS(573)';
NODE_NAME     U5D1 BN20
 '@BASEBOARD_FAB2_LIB.BASEBOARD_FAB2(SCH_1):PAGE41_I283@CHPSET_LIB.SKX_EXT_B(CHIPS)':
 'VSS'<574>: CDS_PINID='VSS(574)';
NODE_NAME     U5D1 BN10
 '@BASEBOARD_FAB2_LIB.BASEBOARD_FAB2(SCH_1):PAGE41_I283@CHPSET_LIB.SKX_EXT_B(CHIPS)':
 'VSS'<575>: CDS_PINID='VSS(575)';
NODE_NAME     U5D1 BN6
 '@BASEBOARD_FAB2_LIB.BASEBOARD_FAB2(SCH_1):PAGE41_I283@CHPSET_LIB.SKX_EXT_B(CHIPS)':
 'VSS'<576>: CDS_PINID='VSS(576)';
NODE_NAME     U5D1 BM25
 '@BASEBOARD_FAB2_LIB.BASEBOARD_FAB2(SCH_1):PAGE41_I283@CHPSET_LIB.SKX_EXT_B(CHIPS)':
 'VSS'<577>: CDS_PINID='VSS(577)';
NODE_NAME     U5D1 P59
 '@BASEBOARD_FAB2_LIB.BASEBOARD_FAB2(SCH_1):PAGE41_I283@CHPSET_LIB.SKX_EXT_B(CHIPS)':
 'VSS'<578>: CDS_PINID='VSS(578)';
NODE_NAME     U5D1 BM15
 '@BASEBOARD_FAB2_LIB.BASEBOARD_FAB2(SCH_1):PAGE41_I283@CHPSET_LIB.SKX_EXT_B(CHIPS)':
 'VSS'<579>: CDS_PINID='VSS(579)';
NODE_NAME     U5D1 BM13
 '@BASEBOARD_FAB2_LIB.BASEBOARD_FAB2(SCH_1):PAGE41_I283@CHPSET_LIB.SKX_EXT_B(CHIPS)':
 'VSS'<580>: CDS_PINID='VSS(580)';
NODE_NAME     U5D1 BM9
 '@BASEBOARD_FAB2_LIB.BASEBOARD_FAB2(SCH_1):PAGE41_I283@CHPSET_LIB.SKX_EXT_B(CHIPS)':
 'VSS'<581>: CDS_PINID='VSS(581)';
NODE_NAME     U5D1 BL82
 '@BASEBOARD_FAB2_LIB.BASEBOARD_FAB2(SCH_1):PAGE41_I283@CHPSET_LIB.SKX_EXT_B(CHIPS)':
 'VSS'<582>: CDS_PINID='VSS(582)';
NODE_NAME     U5D1 BL80
 '@BASEBOARD_FAB2_LIB.BASEBOARD_FAB2(SCH_1):PAGE41_I283@CHPSET_LIB.SKX_EXT_B(CHIPS)':
 'VSS'<583>: CDS_PINID='VSS(583)';
NODE_NAME     U5D1 BL78
 '@BASEBOARD_FAB2_LIB.BASEBOARD_FAB2(SCH_1):PAGE41_I283@CHPSET_LIB.SKX_EXT_B(CHIPS)':
 'VSS'<584>: CDS_PINID='VSS(584)';
NODE_NAME     U5D1 BL76
 '@BASEBOARD_FAB2_LIB.BASEBOARD_FAB2(SCH_1):PAGE41_I283@CHPSET_LIB.SKX_EXT_B(CHIPS)':
 'VSS'<585>: CDS_PINID='VSS(585)';
NODE_NAME     U5D1 BL74
 '@BASEBOARD_FAB2_LIB.BASEBOARD_FAB2(SCH_1):PAGE41_I283@CHPSET_LIB.SKX_EXT_B(CHIPS)':
 'VSS'<586>: CDS_PINID='VSS(586)';
NODE_NAME     U5D1 BL72
 '@BASEBOARD_FAB2_LIB.BASEBOARD_FAB2(SCH_1):PAGE41_I283@CHPSET_LIB.SKX_EXT_B(CHIPS)':
 'VSS'<587>: CDS_PINID='VSS(587)';
NODE_NAME     U5D1 BL70
 '@BASEBOARD_FAB2_LIB.BASEBOARD_FAB2(SCH_1):PAGE41_I283@CHPSET_LIB.SKX_EXT_B(CHIPS)':
 'VSS'<588>: CDS_PINID='VSS(588)';
NODE_NAME     U5D1 BL68
 '@BASEBOARD_FAB2_LIB.BASEBOARD_FAB2(SCH_1):PAGE41_I283@CHPSET_LIB.SKX_EXT_B(CHIPS)':
 'VSS'<589>: CDS_PINID='VSS(589)';
NODE_NAME     U5D1 BL66
 '@BASEBOARD_FAB2_LIB.BASEBOARD_FAB2(SCH_1):PAGE41_I283@CHPSET_LIB.SKX_EXT_B(CHIPS)':
 'VSS'<590>: CDS_PINID='VSS(590)';
NODE_NAME     U5D1 BL64
 '@BASEBOARD_FAB2_LIB.BASEBOARD_FAB2(SCH_1):PAGE41_I283@CHPSET_LIB.SKX_EXT_B(CHIPS)':
 'VSS'<591>: CDS_PINID='VSS(591)';
NODE_NAME     U5D1 BL24
 '@BASEBOARD_FAB2_LIB.BASEBOARD_FAB2(SCH_1):PAGE41_I283@CHPSET_LIB.SKX_EXT_B(CHIPS)':
 'VSS'<592>: CDS_PINID='VSS(592)';
NODE_NAME     U5D1 BL22
 '@BASEBOARD_FAB2_LIB.BASEBOARD_FAB2(SCH_1):PAGE41_I283@CHPSET_LIB.SKX_EXT_B(CHIPS)':
 'VSS'<593>: CDS_PINID='VSS(593)';
NODE_NAME     U5D1 P61
 '@BASEBOARD_FAB2_LIB.BASEBOARD_FAB2(SCH_1):PAGE41_I283@CHPSET_LIB.SKX_EXT_B(CHIPS)':
 'VSS'<594>: CDS_PINID='VSS(594)';
NODE_NAME     U5D1 BL12
 '@BASEBOARD_FAB2_LIB.BASEBOARD_FAB2(SCH_1):PAGE41_I283@CHPSET_LIB.SKX_EXT_B(CHIPS)':
 'VSS'<595>: CDS_PINID='VSS(595)';
NODE_NAME     U5D1 BL10
 '@BASEBOARD_FAB2_LIB.BASEBOARD_FAB2(SCH_1):PAGE41_I283@CHPSET_LIB.SKX_EXT_B(CHIPS)':
 'VSS'<596>: CDS_PINID='VSS(596)';
NODE_NAME     U5D1 BL6
 '@BASEBOARD_FAB2_LIB.BASEBOARD_FAB2(SCH_1):PAGE41_I283@CHPSET_LIB.SKX_EXT_B(CHIPS)':
 'VSS'<597>: CDS_PINID='VSS(597)';
NODE_NAME     U5D1 BK19
 '@BASEBOARD_FAB2_LIB.BASEBOARD_FAB2(SCH_1):PAGE41_I283@CHPSET_LIB.SKX_EXT_B(CHIPS)':
 'VSS'<598>: CDS_PINID='VSS(598)';
NODE_NAME     U5D1 BK11
 '@BASEBOARD_FAB2_LIB.BASEBOARD_FAB2(SCH_1):PAGE41_I283@CHPSET_LIB.SKX_EXT_B(CHIPS)':
 'VSS'<599>: CDS_PINID='VSS(599)';
NODE_NAME     U5D1 BK7
 '@BASEBOARD_FAB2_LIB.BASEBOARD_FAB2(SCH_1):PAGE41_I283@CHPSET_LIB.SKX_EXT_B(CHIPS)':
 'VSS'<600>: CDS_PINID='VSS(600)';
NODE_NAME     U5D1 BK3
 '@BASEBOARD_FAB2_LIB.BASEBOARD_FAB2(SCH_1):PAGE41_I283@CHPSET_LIB.SKX_EXT_B(CHIPS)':
 'VSS'<601>: CDS_PINID='VSS(601)';
NODE_NAME     U5D1 BJ6
 '@BASEBOARD_FAB2_LIB.BASEBOARD_FAB2(SCH_1):PAGE41_I283@CHPSET_LIB.SKX_EXT_B(CHIPS)':
 'VSS'<602>: CDS_PINID='VSS(602)';
NODE_NAME     U5D1 BJ4
 '@BASEBOARD_FAB2_LIB.BASEBOARD_FAB2(SCH_1):PAGE41_I283@CHPSET_LIB.SKX_EXT_B(CHIPS)':
 'VSS'<603>: CDS_PINID='VSS(603)';
NODE_NAME     U5D1 BH21
 '@BASEBOARD_FAB2_LIB.BASEBOARD_FAB2(SCH_1):PAGE41_I283@CHPSET_LIB.SKX_EXT_B(CHIPS)':
 'VSS'<604>: CDS_PINID='VSS(604)';
NODE_NAME     U5D1 BH15
 '@BASEBOARD_FAB2_LIB.BASEBOARD_FAB2(SCH_1):PAGE41_I283@CHPSET_LIB.SKX_EXT_B(CHIPS)':
 'VSS'<605>: CDS_PINID='VSS(605)';
NODE_NAME     U5D1 BH11
 '@BASEBOARD_FAB2_LIB.BASEBOARD_FAB2(SCH_1):PAGE41_I283@CHPSET_LIB.SKX_EXT_B(CHIPS)':
 'VSS'<606>: CDS_PINID='VSS(606)';
NODE_NAME     U5D1 BH9
 '@BASEBOARD_FAB2_LIB.BASEBOARD_FAB2(SCH_1):PAGE41_I283@CHPSET_LIB.SKX_EXT_B(CHIPS)':
 'VSS'<607>: CDS_PINID='VSS(607)';
NODE_NAME     U5D1 BH7
 '@BASEBOARD_FAB2_LIB.BASEBOARD_FAB2(SCH_1):PAGE41_I283@CHPSET_LIB.SKX_EXT_B(CHIPS)':
 'VSS'<608>: CDS_PINID='VSS(608)';
NODE_NAME     U5D1 BG82
 '@BASEBOARD_FAB2_LIB.BASEBOARD_FAB2(SCH_1):PAGE41_I283@CHPSET_LIB.SKX_EXT_B(CHIPS)':
 'VSS'<609>: CDS_PINID='VSS(609)';
NODE_NAME     U5D1 BG80
 '@BASEBOARD_FAB2_LIB.BASEBOARD_FAB2(SCH_1):PAGE41_I283@CHPSET_LIB.SKX_EXT_B(CHIPS)':
 'VSS'<610>: CDS_PINID='VSS(610)';
NODE_NAME     U5D1 BG78
 '@BASEBOARD_FAB2_LIB.BASEBOARD_FAB2(SCH_1):PAGE41_I283@CHPSET_LIB.SKX_EXT_B(CHIPS)':
 'VSS'<611>: CDS_PINID='VSS(611)';
NODE_NAME     U5D1 BG76
 '@BASEBOARD_FAB2_LIB.BASEBOARD_FAB2(SCH_1):PAGE41_I283@CHPSET_LIB.SKX_EXT_B(CHIPS)':
 'VSS'<612>: CDS_PINID='VSS(612)';
NODE_NAME     U5D1 BG74
 '@BASEBOARD_FAB2_LIB.BASEBOARD_FAB2(SCH_1):PAGE41_I283@CHPSET_LIB.SKX_EXT_B(CHIPS)':
 'VSS'<613>: CDS_PINID='VSS(613)';
NODE_NAME     U5D1 DA46
 '@BASEBOARD_FAB2_LIB.BASEBOARD_FAB2(SCH_1):PAGE41_I284@CHPSET_LIB.SKX_EXT_B(CHIPS)':
 'VSS'<294>: CDS_PINID='VSS(294)';
NODE_NAME     U5D1 DA44
 '@BASEBOARD_FAB2_LIB.BASEBOARD_FAB2(SCH_1):PAGE41_I284@CHPSET_LIB.SKX_EXT_B(CHIPS)':
 'VSS'<295>: CDS_PINID='VSS(295)';
NODE_NAME     U5D1 DA38
 '@BASEBOARD_FAB2_LIB.BASEBOARD_FAB2(SCH_1):PAGE41_I284@CHPSET_LIB.SKX_EXT_B(CHIPS)':
 'VSS'<296>: CDS_PINID='VSS(296)';
NODE_NAME     U5D1 DA36
 '@BASEBOARD_FAB2_LIB.BASEBOARD_FAB2(SCH_1):PAGE41_I284@CHPSET_LIB.SKX_EXT_B(CHIPS)':
 'VSS'<297>: CDS_PINID='VSS(297)';
NODE_NAME     U5D1 DA34
 '@BASEBOARD_FAB2_LIB.BASEBOARD_FAB2(SCH_1):PAGE41_I284@CHPSET_LIB.SKX_EXT_B(CHIPS)':
 'VSS'<298>: CDS_PINID='VSS(298)';
NODE_NAME     U5D1 DA32
 '@BASEBOARD_FAB2_LIB.BASEBOARD_FAB2(SCH_1):PAGE41_I284@CHPSET_LIB.SKX_EXT_B(CHIPS)':
 'VSS'<299>: CDS_PINID='VSS(299)';
NODE_NAME     U5D1 DA30
 '@BASEBOARD_FAB2_LIB.BASEBOARD_FAB2(SCH_1):PAGE41_I284@CHPSET_LIB.SKX_EXT_B(CHIPS)':
 'VSS'<300>: CDS_PINID='VSS(300)';
NODE_NAME     U5D1 DA28
 '@BASEBOARD_FAB2_LIB.BASEBOARD_FAB2(SCH_1):PAGE41_I284@CHPSET_LIB.SKX_EXT_B(CHIPS)':
 'VSS'<301>: CDS_PINID='VSS(301)';
NODE_NAME     U5D1 DA26
 '@BASEBOARD_FAB2_LIB.BASEBOARD_FAB2(SCH_1):PAGE41_I284@CHPSET_LIB.SKX_EXT_B(CHIPS)':
 'VSS'<302>: CDS_PINID='VSS(302)';
NODE_NAME     U5D1 DA18
 '@BASEBOARD_FAB2_LIB.BASEBOARD_FAB2(SCH_1):PAGE41_I284@CHPSET_LIB.SKX_EXT_B(CHIPS)':
 'VSS'<303>: CDS_PINID='VSS(303)';
NODE_NAME     U5D1 H53
 '@BASEBOARD_FAB2_LIB.BASEBOARD_FAB2(SCH_1):PAGE41_I284@CHPSET_LIB.SKX_EXT_B(CHIPS)':
 'VSS'<304>: CDS_PINID='VSS(304)';
NODE_NAME     U5D1 DA6
 '@BASEBOARD_FAB2_LIB.BASEBOARD_FAB2(SCH_1):PAGE41_I284@CHPSET_LIB.SKX_EXT_B(CHIPS)':
 'VSS'<305>: CDS_PINID='VSS(305)';
NODE_NAME     U5D1 CY85
 '@BASEBOARD_FAB2_LIB.BASEBOARD_FAB2(SCH_1):PAGE41_I284@CHPSET_LIB.SKX_EXT_B(CHIPS)':
 'VSS'<306>: CDS_PINID='VSS(306)';
NODE_NAME     U5D1 CY83
 '@BASEBOARD_FAB2_LIB.BASEBOARD_FAB2(SCH_1):PAGE41_I284@CHPSET_LIB.SKX_EXT_B(CHIPS)':
 'VSS'<307>: CDS_PINID='VSS(307)';
NODE_NAME     U5D1 CY77
 '@BASEBOARD_FAB2_LIB.BASEBOARD_FAB2(SCH_1):PAGE41_I284@CHPSET_LIB.SKX_EXT_B(CHIPS)':
 'VSS'<308>: CDS_PINID='VSS(308)';
NODE_NAME     U5D1 CY75
 '@BASEBOARD_FAB2_LIB.BASEBOARD_FAB2(SCH_1):PAGE41_I284@CHPSET_LIB.SKX_EXT_B(CHIPS)':
 'VSS'<309>: CDS_PINID='VSS(309)';
NODE_NAME     U5D1 CY69
 '@BASEBOARD_FAB2_LIB.BASEBOARD_FAB2(SCH_1):PAGE41_I284@CHPSET_LIB.SKX_EXT_B(CHIPS)':
 'VSS'<310>: CDS_PINID='VSS(310)';
NODE_NAME     U5D1 CY65
 '@BASEBOARD_FAB2_LIB.BASEBOARD_FAB2(SCH_1):PAGE41_I284@CHPSET_LIB.SKX_EXT_B(CHIPS)':
 'VSS'<311>: CDS_PINID='VSS(311)';
NODE_NAME     U5D1 CY61
 '@BASEBOARD_FAB2_LIB.BASEBOARD_FAB2(SCH_1):PAGE41_I284@CHPSET_LIB.SKX_EXT_B(CHIPS)':
 'VSS'<312>: CDS_PINID='VSS(312)';
NODE_NAME     U5D1 CY59
 '@BASEBOARD_FAB2_LIB.BASEBOARD_FAB2(SCH_1):PAGE41_I284@CHPSET_LIB.SKX_EXT_B(CHIPS)':
 'VSS'<313>: CDS_PINID='VSS(313)';
NODE_NAME     U5D1 CY51
 '@BASEBOARD_FAB2_LIB.BASEBOARD_FAB2(SCH_1):PAGE41_I284@CHPSET_LIB.SKX_EXT_B(CHIPS)':
 'VSS'<314>: CDS_PINID='VSS(314)';
NODE_NAME     U5D1 CY45
 '@BASEBOARD_FAB2_LIB.BASEBOARD_FAB2(SCH_1):PAGE41_I284@CHPSET_LIB.SKX_EXT_B(CHIPS)':
 'VSS'<315>: CDS_PINID='VSS(315)';
NODE_NAME     U5D1 CY41
 '@BASEBOARD_FAB2_LIB.BASEBOARD_FAB2(SCH_1):PAGE41_I284@CHPSET_LIB.SKX_EXT_B(CHIPS)':
 'VSS'<316>: CDS_PINID='VSS(316)';
NODE_NAME     U5D1 CY21
 '@BASEBOARD_FAB2_LIB.BASEBOARD_FAB2(SCH_1):PAGE41_I284@CHPSET_LIB.SKX_EXT_B(CHIPS)':
 'VSS'<317>: CDS_PINID='VSS(317)';
NODE_NAME     U5D1 CY15
 '@BASEBOARD_FAB2_LIB.BASEBOARD_FAB2(SCH_1):PAGE41_I284@CHPSET_LIB.SKX_EXT_B(CHIPS)':
 'VSS'<318>: CDS_PINID='VSS(318)';
NODE_NAME     U5D1 CY13
 '@BASEBOARD_FAB2_LIB.BASEBOARD_FAB2(SCH_1):PAGE41_I284@CHPSET_LIB.SKX_EXT_B(CHIPS)':
 'VSS'<319>: CDS_PINID='VSS(319)';
NODE_NAME     U5D1 CY9
 '@BASEBOARD_FAB2_LIB.BASEBOARD_FAB2(SCH_1):PAGE41_I284@CHPSET_LIB.SKX_EXT_B(CHIPS)':
 'VSS'<320>: CDS_PINID='VSS(320)';
NODE_NAME     U5D1 CY1
 '@BASEBOARD_FAB2_LIB.BASEBOARD_FAB2(SCH_1):PAGE41_I284@CHPSET_LIB.SKX_EXT_B(CHIPS)':
 'VSS'<321>: CDS_PINID='VSS(321)';
NODE_NAME     U5D1 CW82
 '@BASEBOARD_FAB2_LIB.BASEBOARD_FAB2(SCH_1):PAGE41_I284@CHPSET_LIB.SKX_EXT_B(CHIPS)':
 'VSS'<322>: CDS_PINID='VSS(322)';
NODE_NAME     U5D1 CW78
 '@BASEBOARD_FAB2_LIB.BASEBOARD_FAB2(SCH_1):PAGE41_I284@CHPSET_LIB.SKX_EXT_B(CHIPS)':
 'VSS'<323>: CDS_PINID='VSS(323)';
NODE_NAME     U5D1 CW74
 '@BASEBOARD_FAB2_LIB.BASEBOARD_FAB2(SCH_1):PAGE41_I284@CHPSET_LIB.SKX_EXT_B(CHIPS)':
 'VSS'<324>: CDS_PINID='VSS(324)';
NODE_NAME     U5D1 CW68
 '@BASEBOARD_FAB2_LIB.BASEBOARD_FAB2(SCH_1):PAGE41_I284@CHPSET_LIB.SKX_EXT_B(CHIPS)':
 'VSS'<325>: CDS_PINID='VSS(325)';
NODE_NAME     U5D1 CW66
 '@BASEBOARD_FAB2_LIB.BASEBOARD_FAB2(SCH_1):PAGE41_I284@CHPSET_LIB.SKX_EXT_B(CHIPS)':
 'VSS'<326>: CDS_PINID='VSS(326)';
NODE_NAME     U5D1 CW64
 '@BASEBOARD_FAB2_LIB.BASEBOARD_FAB2(SCH_1):PAGE41_I284@CHPSET_LIB.SKX_EXT_B(CHIPS)':
 'VSS'<327>: CDS_PINID='VSS(327)';
NODE_NAME     U5D1 CW54
 '@BASEBOARD_FAB2_LIB.BASEBOARD_FAB2(SCH_1):PAGE41_I284@CHPSET_LIB.SKX_EXT_B(CHIPS)':
 'VSS'<328>: CDS_PINID='VSS(328)';
NODE_NAME     U5D1 CW52
 '@BASEBOARD_FAB2_LIB.BASEBOARD_FAB2(SCH_1):PAGE41_I284@CHPSET_LIB.SKX_EXT_B(CHIPS)':
 'VSS'<329>: CDS_PINID='VSS(329)';
NODE_NAME     U5D1 CW42
 '@BASEBOARD_FAB2_LIB.BASEBOARD_FAB2(SCH_1):PAGE41_I284@CHPSET_LIB.SKX_EXT_B(CHIPS)':
 'VSS'<330>: CDS_PINID='VSS(330)';
NODE_NAME     U5D1 CW40
 '@BASEBOARD_FAB2_LIB.BASEBOARD_FAB2(SCH_1):PAGE41_I284@CHPSET_LIB.SKX_EXT_B(CHIPS)':
 'VSS'<331>: CDS_PINID='VSS(331)';
NODE_NAME     U5D1 CW38
 '@BASEBOARD_FAB2_LIB.BASEBOARD_FAB2(SCH_1):PAGE41_I284@CHPSET_LIB.SKX_EXT_B(CHIPS)':
 'VSS'<332>: CDS_PINID='VSS(332)';
NODE_NAME     U5D1 CW32
 '@BASEBOARD_FAB2_LIB.BASEBOARD_FAB2(SCH_1):PAGE41_I284@CHPSET_LIB.SKX_EXT_B(CHIPS)':
 'VSS'<333>: CDS_PINID='VSS(333)';
NODE_NAME     U5D1 CW26
 '@BASEBOARD_FAB2_LIB.BASEBOARD_FAB2(SCH_1):PAGE41_I284@CHPSET_LIB.SKX_EXT_B(CHIPS)':
 'VSS'<334>: CDS_PINID='VSS(334)';
NODE_NAME     U5D1 CW12
 '@BASEBOARD_FAB2_LIB.BASEBOARD_FAB2(SCH_1):PAGE41_I284@CHPSET_LIB.SKX_EXT_B(CHIPS)':
 'VSS'<335>: CDS_PINID='VSS(335)';
NODE_NAME     U5D1 CV83
 '@BASEBOARD_FAB2_LIB.BASEBOARD_FAB2(SCH_1):PAGE41_I284@CHPSET_LIB.SKX_EXT_B(CHIPS)':
 'VSS'<336>: CDS_PINID='VSS(336)';
NODE_NAME     U5D1 CV81
 '@BASEBOARD_FAB2_LIB.BASEBOARD_FAB2(SCH_1):PAGE41_I284@CHPSET_LIB.SKX_EXT_B(CHIPS)':
 'VSS'<337>: CDS_PINID='VSS(337)';
NODE_NAME     U5D1 CV79
 '@BASEBOARD_FAB2_LIB.BASEBOARD_FAB2(SCH_1):PAGE41_I284@CHPSET_LIB.SKX_EXT_B(CHIPS)':
 'VSS'<338>: CDS_PINID='VSS(338)';
NODE_NAME     U5D1 CV73
 '@BASEBOARD_FAB2_LIB.BASEBOARD_FAB2(SCH_1):PAGE41_I284@CHPSET_LIB.SKX_EXT_B(CHIPS)':
 'VSS'<339>: CDS_PINID='VSS(339)';
NODE_NAME     U5D1 CV67
 '@BASEBOARD_FAB2_LIB.BASEBOARD_FAB2(SCH_1):PAGE41_I284@CHPSET_LIB.SKX_EXT_B(CHIPS)':
 'VSS'<340>: CDS_PINID='VSS(340)';
NODE_NAME     U5D1 CV63
 '@BASEBOARD_FAB2_LIB.BASEBOARD_FAB2(SCH_1):PAGE41_I284@CHPSET_LIB.SKX_EXT_B(CHIPS)':
 'VSS'<341>: CDS_PINID='VSS(341)';
NODE_NAME     U5D1 CV55
 '@BASEBOARD_FAB2_LIB.BASEBOARD_FAB2(SCH_1):PAGE41_I284@CHPSET_LIB.SKX_EXT_B(CHIPS)':
 'VSS'<342>: CDS_PINID='VSS(342)';
NODE_NAME     U5D1 CV53
 '@BASEBOARD_FAB2_LIB.BASEBOARD_FAB2(SCH_1):PAGE41_I284@CHPSET_LIB.SKX_EXT_B(CHIPS)':
 'VSS'<343>: CDS_PINID='VSS(343)';
NODE_NAME     U5D1 CV41
 '@BASEBOARD_FAB2_LIB.BASEBOARD_FAB2(SCH_1):PAGE41_I284@CHPSET_LIB.SKX_EXT_B(CHIPS)':
 'VSS'<344>: CDS_PINID='VSS(344)';
NODE_NAME     U5D1 CV39
 '@BASEBOARD_FAB2_LIB.BASEBOARD_FAB2(SCH_1):PAGE41_I284@CHPSET_LIB.SKX_EXT_B(CHIPS)':
 'VSS'<345>: CDS_PINID='VSS(345)';
NODE_NAME     U5D1 CV37
 '@BASEBOARD_FAB2_LIB.BASEBOARD_FAB2(SCH_1):PAGE41_I284@CHPSET_LIB.SKX_EXT_B(CHIPS)':
 'VSS'<346>: CDS_PINID='VSS(346)';
NODE_NAME     U5D1 CV33
 '@BASEBOARD_FAB2_LIB.BASEBOARD_FAB2(SCH_1):PAGE41_I284@CHPSET_LIB.SKX_EXT_B(CHIPS)':
 'VSS'<347>: CDS_PINID='VSS(347)';
NODE_NAME     U5D1 CV31
 '@BASEBOARD_FAB2_LIB.BASEBOARD_FAB2(SCH_1):PAGE41_I284@CHPSET_LIB.SKX_EXT_B(CHIPS)':
 'VSS'<348>: CDS_PINID='VSS(348)';
NODE_NAME     U5D1 CV27
 '@BASEBOARD_FAB2_LIB.BASEBOARD_FAB2(SCH_1):PAGE41_I284@CHPSET_LIB.SKX_EXT_B(CHIPS)':
 'VSS'<349>: CDS_PINID='VSS(349)';
NODE_NAME     U5D1 CV25
 '@BASEBOARD_FAB2_LIB.BASEBOARD_FAB2(SCH_1):PAGE41_I284@CHPSET_LIB.SKX_EXT_B(CHIPS)':
 'VSS'<350>: CDS_PINID='VSS(350)';
NODE_NAME     U5D1 CV17
 '@BASEBOARD_FAB2_LIB.BASEBOARD_FAB2(SCH_1):PAGE41_I284@CHPSET_LIB.SKX_EXT_B(CHIPS)':
 'VSS'<351>: CDS_PINID='VSS(351)';
NODE_NAME     U5D1 H55
 '@BASEBOARD_FAB2_LIB.BASEBOARD_FAB2(SCH_1):PAGE41_I284@CHPSET_LIB.SKX_EXT_B(CHIPS)':
 'VSS'<352>: CDS_PINID='VSS(352)';
NODE_NAME     U5D1 CV1
 '@BASEBOARD_FAB2_LIB.BASEBOARD_FAB2(SCH_1):PAGE41_I284@CHPSET_LIB.SKX_EXT_B(CHIPS)':
 'VSS'<353>: CDS_PINID='VSS(353)';
NODE_NAME     U5D1 CU86
 '@BASEBOARD_FAB2_LIB.BASEBOARD_FAB2(SCH_1):PAGE41_I284@CHPSET_LIB.SKX_EXT_B(CHIPS)':
 'VSS'<354>: CDS_PINID='VSS(354)';
NODE_NAME     U5D1 CU82
 '@BASEBOARD_FAB2_LIB.BASEBOARD_FAB2(SCH_1):PAGE41_I284@CHPSET_LIB.SKX_EXT_B(CHIPS)':
 'VSS'<355>: CDS_PINID='VSS(355)';
NODE_NAME     U5D1 CU80
 '@BASEBOARD_FAB2_LIB.BASEBOARD_FAB2(SCH_1):PAGE41_I284@CHPSET_LIB.SKX_EXT_B(CHIPS)':
 'VSS'<356>: CDS_PINID='VSS(356)';
NODE_NAME     U5D1 CU78
 '@BASEBOARD_FAB2_LIB.BASEBOARD_FAB2(SCH_1):PAGE41_I284@CHPSET_LIB.SKX_EXT_B(CHIPS)':
 'VSS'<357>: CDS_PINID='VSS(357)';
NODE_NAME     U5D1 CU76
 '@BASEBOARD_FAB2_LIB.BASEBOARD_FAB2(SCH_1):PAGE41_I284@CHPSET_LIB.SKX_EXT_B(CHIPS)':
 'VSS'<358>: CDS_PINID='VSS(358)';
NODE_NAME     U5D1 CU68
 '@BASEBOARD_FAB2_LIB.BASEBOARD_FAB2(SCH_1):PAGE41_I284@CHPSET_LIB.SKX_EXT_B(CHIPS)':
 'VSS'<359>: CDS_PINID='VSS(359)';
NODE_NAME     U5D1 CU62
 '@BASEBOARD_FAB2_LIB.BASEBOARD_FAB2(SCH_1):PAGE41_I284@CHPSET_LIB.SKX_EXT_B(CHIPS)':
 'VSS'<360>: CDS_PINID='VSS(360)';
NODE_NAME     U5D1 CU56
 '@BASEBOARD_FAB2_LIB.BASEBOARD_FAB2(SCH_1):PAGE41_I284@CHPSET_LIB.SKX_EXT_B(CHIPS)':
 'VSS'<361>: CDS_PINID='VSS(361)';
NODE_NAME     U5D1 CU36
 '@BASEBOARD_FAB2_LIB.BASEBOARD_FAB2(SCH_1):PAGE41_I284@CHPSET_LIB.SKX_EXT_B(CHIPS)':
 'VSS'<362>: CDS_PINID='VSS(362)';
NODE_NAME     U5D1 CU34
 '@BASEBOARD_FAB2_LIB.BASEBOARD_FAB2(SCH_1):PAGE41_I284@CHPSET_LIB.SKX_EXT_B(CHIPS)':
 'VSS'<363>: CDS_PINID='VSS(363)';
NODE_NAME     U5D1 CU30
 '@BASEBOARD_FAB2_LIB.BASEBOARD_FAB2(SCH_1):PAGE41_I284@CHPSET_LIB.SKX_EXT_B(CHIPS)':
 'VSS'<364>: CDS_PINID='VSS(364)';
NODE_NAME     U5D1 CU28
 '@BASEBOARD_FAB2_LIB.BASEBOARD_FAB2(SCH_1):PAGE41_I284@CHPSET_LIB.SKX_EXT_B(CHIPS)':
 'VSS'<365>: CDS_PINID='VSS(365)';
NODE_NAME     U5D1 CU22
 '@BASEBOARD_FAB2_LIB.BASEBOARD_FAB2(SCH_1):PAGE41_I284@CHPSET_LIB.SKX_EXT_B(CHIPS)':
 'VSS'<366>: CDS_PINID='VSS(366)';
NODE_NAME     U5D1 CU4
 '@BASEBOARD_FAB2_LIB.BASEBOARD_FAB2(SCH_1):PAGE41_I284@CHPSET_LIB.SKX_EXT_B(CHIPS)':
 'VSS'<367>: CDS_PINID='VSS(367)';
NODE_NAME     U5D1 CT85
 '@BASEBOARD_FAB2_LIB.BASEBOARD_FAB2(SCH_1):PAGE41_I284@CHPSET_LIB.SKX_EXT_B(CHIPS)':
 'VSS'<368>: CDS_PINID='VSS(368)';
NODE_NAME     U5D1 CT83
 '@BASEBOARD_FAB2_LIB.BASEBOARD_FAB2(SCH_1):PAGE41_I284@CHPSET_LIB.SKX_EXT_B(CHIPS)':
 'VSS'<369>: CDS_PINID='VSS(369)';
NODE_NAME     U5D1 CT79
 '@BASEBOARD_FAB2_LIB.BASEBOARD_FAB2(SCH_1):PAGE41_I284@CHPSET_LIB.SKX_EXT_B(CHIPS)':
 'VSS'<370>: CDS_PINID='VSS(370)';
NODE_NAME     U5D1 CT73
 '@BASEBOARD_FAB2_LIB.BASEBOARD_FAB2(SCH_1):PAGE41_I284@CHPSET_LIB.SKX_EXT_B(CHIPS)':
 'VSS'<371>: CDS_PINID='VSS(371)';
NODE_NAME     U5D1 CT57
 '@BASEBOARD_FAB2_LIB.BASEBOARD_FAB2(SCH_1):PAGE41_I284@CHPSET_LIB.SKX_EXT_B(CHIPS)':
 'VSS'<372>: CDS_PINID='VSS(372)';
NODE_NAME     U5D1 CT35
 '@BASEBOARD_FAB2_LIB.BASEBOARD_FAB2(SCH_1):PAGE41_I284@CHPSET_LIB.SKX_EXT_B(CHIPS)':
 'VSS'<373>: CDS_PINID='VSS(373)';
NODE_NAME     U5D1 CT33
 '@BASEBOARD_FAB2_LIB.BASEBOARD_FAB2(SCH_1):PAGE41_I284@CHPSET_LIB.SKX_EXT_B(CHIPS)':
 'VSS'<374>: CDS_PINID='VSS(374)';
NODE_NAME     U5D1 CT29
 '@BASEBOARD_FAB2_LIB.BASEBOARD_FAB2(SCH_1):PAGE41_I284@CHPSET_LIB.SKX_EXT_B(CHIPS)':
 'VSS'<375>: CDS_PINID='VSS(375)';
NODE_NAME     U5D1 CT27
 '@BASEBOARD_FAB2_LIB.BASEBOARD_FAB2(SCH_1):PAGE41_I284@CHPSET_LIB.SKX_EXT_B(CHIPS)':
 'VSS'<376>: CDS_PINID='VSS(376)';
NODE_NAME     U5D1 CT19
 '@BASEBOARD_FAB2_LIB.BASEBOARD_FAB2(SCH_1):PAGE41_I284@CHPSET_LIB.SKX_EXT_B(CHIPS)':
 'VSS'<377>: CDS_PINID='VSS(377)';
NODE_NAME     U5D1 CT13
 '@BASEBOARD_FAB2_LIB.BASEBOARD_FAB2(SCH_1):PAGE41_I284@CHPSET_LIB.SKX_EXT_B(CHIPS)':
 'VSS'<378>: CDS_PINID='VSS(378)';
NODE_NAME     U5D1 H57
 '@BASEBOARD_FAB2_LIB.BASEBOARD_FAB2(SCH_1):PAGE41_I284@CHPSET_LIB.SKX_EXT_B(CHIPS)':
 'VSS'<379>: CDS_PINID='VSS(379)';
NODE_NAME     U5D1 CR86
 '@BASEBOARD_FAB2_LIB.BASEBOARD_FAB2(SCH_1):PAGE41_I284@CHPSET_LIB.SKX_EXT_B(CHIPS)':
 'VSS'<380>: CDS_PINID='VSS(380)';
NODE_NAME     U5D1 CR78
 '@BASEBOARD_FAB2_LIB.BASEBOARD_FAB2(SCH_1):PAGE41_I284@CHPSET_LIB.SKX_EXT_B(CHIPS)':
 'VSS'<381>: CDS_PINID='VSS(381)';
NODE_NAME     U5D1 CR68
 '@BASEBOARD_FAB2_LIB.BASEBOARD_FAB2(SCH_1):PAGE41_I284@CHPSET_LIB.SKX_EXT_B(CHIPS)':
 'VSS'<382>: CDS_PINID='VSS(382)';
NODE_NAME     U5D1 CR66
 '@BASEBOARD_FAB2_LIB.BASEBOARD_FAB2(SCH_1):PAGE41_I284@CHPSET_LIB.SKX_EXT_B(CHIPS)':
 'VSS'<383>: CDS_PINID='VSS(383)';
NODE_NAME     U5D1 CR64
 '@BASEBOARD_FAB2_LIB.BASEBOARD_FAB2(SCH_1):PAGE41_I284@CHPSET_LIB.SKX_EXT_B(CHIPS)':
 'VSS'<384>: CDS_PINID='VSS(384)';
NODE_NAME     U5D1 CR62
 '@BASEBOARD_FAB2_LIB.BASEBOARD_FAB2(SCH_1):PAGE41_I284@CHPSET_LIB.SKX_EXT_B(CHIPS)':
 'VSS'<385>: CDS_PINID='VSS(385)';
NODE_NAME     U5D1 CR58
 '@BASEBOARD_FAB2_LIB.BASEBOARD_FAB2(SCH_1):PAGE41_I284@CHPSET_LIB.SKX_EXT_B(CHIPS)':
 'VSS'<386>: CDS_PINID='VSS(386)';
NODE_NAME     U5D1 CR32
 '@BASEBOARD_FAB2_LIB.BASEBOARD_FAB2(SCH_1):PAGE41_I284@CHPSET_LIB.SKX_EXT_B(CHIPS)':
 'VSS'<387>: CDS_PINID='VSS(387)';
NODE_NAME     U5D1 CR24
 '@BASEBOARD_FAB2_LIB.BASEBOARD_FAB2(SCH_1):PAGE41_I284@CHPSET_LIB.SKX_EXT_B(CHIPS)':
 'VSS'<388>: CDS_PINID='VSS(388)';
NODE_NAME     U5D1 CR22
 '@BASEBOARD_FAB2_LIB.BASEBOARD_FAB2(SCH_1):PAGE41_I284@CHPSET_LIB.SKX_EXT_B(CHIPS)':
 'VSS'<389>: CDS_PINID='VSS(389)';
NODE_NAME     U5D1 CR10
 '@BASEBOARD_FAB2_LIB.BASEBOARD_FAB2(SCH_1):PAGE41_I284@CHPSET_LIB.SKX_EXT_B(CHIPS)':
 'VSS'<390>: CDS_PINID='VSS(390)';
NODE_NAME     U5D1 CR6
 '@BASEBOARD_FAB2_LIB.BASEBOARD_FAB2(SCH_1):PAGE41_I284@CHPSET_LIB.SKX_EXT_B(CHIPS)':
 'VSS'<391>: CDS_PINID='VSS(391)';
NODE_NAME     U5D1 CP83
 '@BASEBOARD_FAB2_LIB.BASEBOARD_FAB2(SCH_1):PAGE41_I284@CHPSET_LIB.SKX_EXT_B(CHIPS)':
 'VSS'<392>: CDS_PINID='VSS(392)';
NODE_NAME     U5D1 CP81
 '@BASEBOARD_FAB2_LIB.BASEBOARD_FAB2(SCH_1):PAGE41_I284@CHPSET_LIB.SKX_EXT_B(CHIPS)':
 'VSS'<393>: CDS_PINID='VSS(393)';
NODE_NAME     U5D1 CP75
 '@BASEBOARD_FAB2_LIB.BASEBOARD_FAB2(SCH_1):PAGE41_I284@CHPSET_LIB.SKX_EXT_B(CHIPS)':
 'VSS'<394>: CDS_PINID='VSS(394)';
NODE_NAME     U5D1 CP73
 '@BASEBOARD_FAB2_LIB.BASEBOARD_FAB2(SCH_1):PAGE41_I284@CHPSET_LIB.SKX_EXT_B(CHIPS)':
 'VSS'<395>: CDS_PINID='VSS(395)';
NODE_NAME     U5D1 CP69
 '@BASEBOARD_FAB2_LIB.BASEBOARD_FAB2(SCH_1):PAGE41_I284@CHPSET_LIB.SKX_EXT_B(CHIPS)':
 'VSS'<396>: CDS_PINID='VSS(396)';
NODE_NAME     U5D1 CP59
 '@BASEBOARD_FAB2_LIB.BASEBOARD_FAB2(SCH_1):PAGE41_I284@CHPSET_LIB.SKX_EXT_B(CHIPS)':
 'VSS'<397>: CDS_PINID='VSS(397)';
NODE_NAME     U5D1 CP25
 '@BASEBOARD_FAB2_LIB.BASEBOARD_FAB2(SCH_1):PAGE41_I284@CHPSET_LIB.SKX_EXT_B(CHIPS)':
 'VSS'<398>: CDS_PINID='VSS(398)';
NODE_NAME     U5D1 H59
 '@BASEBOARD_FAB2_LIB.BASEBOARD_FAB2(SCH_1):PAGE41_I284@CHPSET_LIB.SKX_EXT_B(CHIPS)':
 'VSS'<399>: CDS_PINID='VSS(399)';
NODE_NAME     U5D1 CP1
 '@BASEBOARD_FAB2_LIB.BASEBOARD_FAB2(SCH_1):PAGE41_I284@CHPSET_LIB.SKX_EXT_B(CHIPS)':
 'VSS'<400>: CDS_PINID='VSS(400)';
NODE_NAME     U5D1 CN78
 '@BASEBOARD_FAB2_LIB.BASEBOARD_FAB2(SCH_1):PAGE41_I284@CHPSET_LIB.SKX_EXT_B(CHIPS)':
 'VSS'<401>: CDS_PINID='VSS(401)';
NODE_NAME     U5D1 CN68
 '@BASEBOARD_FAB2_LIB.BASEBOARD_FAB2(SCH_1):PAGE41_I284@CHPSET_LIB.SKX_EXT_B(CHIPS)':
 'VSS'<402>: CDS_PINID='VSS(402)';
NODE_NAME     U5D1 CN62
 '@BASEBOARD_FAB2_LIB.BASEBOARD_FAB2(SCH_1):PAGE41_I284@CHPSET_LIB.SKX_EXT_B(CHIPS)':
 'VSS'<403>: CDS_PINID='VSS(403)';
NODE_NAME     U5D1 CN60
 '@BASEBOARD_FAB2_LIB.BASEBOARD_FAB2(SCH_1):PAGE41_I284@CHPSET_LIB.SKX_EXT_B(CHIPS)':
 'VSS'<404>: CDS_PINID='VSS(404)';
NODE_NAME     U5D1 CN32
 '@BASEBOARD_FAB2_LIB.BASEBOARD_FAB2(SCH_1):PAGE41_I284@CHPSET_LIB.SKX_EXT_B(CHIPS)':
 'VSS'<405>: CDS_PINID='VSS(405)';
NODE_NAME     U5D1 CN26
 '@BASEBOARD_FAB2_LIB.BASEBOARD_FAB2(SCH_1):PAGE41_I284@CHPSET_LIB.SKX_EXT_B(CHIPS)':
 'VSS'<406>: CDS_PINID='VSS(406)';
NODE_NAME     U5D1 H61
 '@BASEBOARD_FAB2_LIB.BASEBOARD_FAB2(SCH_1):PAGE41_I284@CHPSET_LIB.SKX_EXT_B(CHIPS)':
 'VSS'<407>: CDS_PINID='VSS(407)';
NODE_NAME     U5D1 CN12
 '@BASEBOARD_FAB2_LIB.BASEBOARD_FAB2(SCH_1):PAGE41_I284@CHPSET_LIB.SKX_EXT_B(CHIPS)':
 'VSS'<408>: CDS_PINID='VSS(408)';
NODE_NAME     U5D1 CN2
 '@BASEBOARD_FAB2_LIB.BASEBOARD_FAB2(SCH_1):PAGE41_I284@CHPSET_LIB.SKX_EXT_B(CHIPS)':
 'VSS'<409>: CDS_PINID='VSS(409)';
NODE_NAME     U5D1 CM85
 '@BASEBOARD_FAB2_LIB.BASEBOARD_FAB2(SCH_1):PAGE41_I284@CHPSET_LIB.SKX_EXT_B(CHIPS)':
 'VSS'<410>: CDS_PINID='VSS(410)';
NODE_NAME     U5D1 CM83
 '@BASEBOARD_FAB2_LIB.BASEBOARD_FAB2(SCH_1):PAGE41_I284@CHPSET_LIB.SKX_EXT_B(CHIPS)':
 'VSS'<411>: CDS_PINID='VSS(411)';
NODE_NAME     U5D1 CM77
 '@BASEBOARD_FAB2_LIB.BASEBOARD_FAB2(SCH_1):PAGE41_I284@CHPSET_LIB.SKX_EXT_B(CHIPS)':
 'VSS'<412>: CDS_PINID='VSS(412)';
NODE_NAME     U5D1 CM73
 '@BASEBOARD_FAB2_LIB.BASEBOARD_FAB2(SCH_1):PAGE41_I284@CHPSET_LIB.SKX_EXT_B(CHIPS)':
 'VSS'<413>: CDS_PINID='VSS(413)';
NODE_NAME     U5D1 CM67
 '@BASEBOARD_FAB2_LIB.BASEBOARD_FAB2(SCH_1):PAGE41_I284@CHPSET_LIB.SKX_EXT_B(CHIPS)':
 'VSS'<414>: CDS_PINID='VSS(414)';
NODE_NAME     U5D1 CM63
 '@BASEBOARD_FAB2_LIB.BASEBOARD_FAB2(SCH_1):PAGE41_I284@CHPSET_LIB.SKX_EXT_B(CHIPS)':
 'VSS'<415>: CDS_PINID='VSS(415)';
NODE_NAME     U5D1 CM61
 '@BASEBOARD_FAB2_LIB.BASEBOARD_FAB2(SCH_1):PAGE41_I284@CHPSET_LIB.SKX_EXT_B(CHIPS)':
 'VSS'<416>: CDS_PINID='VSS(416)';
NODE_NAME     U5D1 CM31
 '@BASEBOARD_FAB2_LIB.BASEBOARD_FAB2(SCH_1):PAGE41_I284@CHPSET_LIB.SKX_EXT_B(CHIPS)':
 'VSS'<417>: CDS_PINID='VSS(417)';
NODE_NAME     U5D1 CM5
 '@BASEBOARD_FAB2_LIB.BASEBOARD_FAB2(SCH_1):PAGE41_I284@CHPSET_LIB.SKX_EXT_B(CHIPS)':
 'VSS'<418>: CDS_PINID='VSS(418)';
NODE_NAME     U5D1 CM29
 '@BASEBOARD_FAB2_LIB.BASEBOARD_FAB2(SCH_1):PAGE41_I284@CHPSET_LIB.SKX_EXT_B(CHIPS)':
 'VSS'<419>: CDS_PINID='VSS(419)';
NODE_NAME     U5D1 CM19
 '@BASEBOARD_FAB2_LIB.BASEBOARD_FAB2(SCH_1):PAGE41_I284@CHPSET_LIB.SKX_EXT_B(CHIPS)':
 'VSS'<420>: CDS_PINID='VSS(420)';
NODE_NAME     U5D1 CL80
 '@BASEBOARD_FAB2_LIB.BASEBOARD_FAB2(SCH_1):PAGE41_I284@CHPSET_LIB.SKX_EXT_B(CHIPS)':
 'VSS'<421>: CDS_PINID='VSS(421)';
NODE_NAME     U5D1 CL78
 '@BASEBOARD_FAB2_LIB.BASEBOARD_FAB2(SCH_1):PAGE41_I284@CHPSET_LIB.SKX_EXT_B(CHIPS)':
 'VSS'<422>: CDS_PINID='VSS(422)';
NODE_NAME     U5D1 CL76
 '@BASEBOARD_FAB2_LIB.BASEBOARD_FAB2(SCH_1):PAGE41_I284@CHPSET_LIB.SKX_EXT_B(CHIPS)':
 'VSS'<423>: CDS_PINID='VSS(423)';
NODE_NAME     U5D1 CL74
 '@BASEBOARD_FAB2_LIB.BASEBOARD_FAB2(SCH_1):PAGE41_I284@CHPSET_LIB.SKX_EXT_B(CHIPS)':
 'VSS'<424>: CDS_PINID='VSS(424)';
NODE_NAME     U5D1 CL66
 '@BASEBOARD_FAB2_LIB.BASEBOARD_FAB2(SCH_1):PAGE41_I284@CHPSET_LIB.SKX_EXT_B(CHIPS)':
 'VSS'<425>: CDS_PINID='VSS(425)';
NODE_NAME     U5D1 CL64
 '@BASEBOARD_FAB2_LIB.BASEBOARD_FAB2(SCH_1):PAGE41_I284@CHPSET_LIB.SKX_EXT_B(CHIPS)':
 'VSS'<426>: CDS_PINID='VSS(426)';
NODE_NAME     U5D1 CL62
 '@BASEBOARD_FAB2_LIB.BASEBOARD_FAB2(SCH_1):PAGE41_I284@CHPSET_LIB.SKX_EXT_B(CHIPS)':
 'VSS'<427>: CDS_PINID='VSS(427)';
NODE_NAME     U5D1 H63
 '@BASEBOARD_FAB2_LIB.BASEBOARD_FAB2(SCH_1):PAGE41_I284@CHPSET_LIB.SKX_EXT_B(CHIPS)':
 'VSS'<428>: CDS_PINID='VSS(428)';
NODE_NAME     U5D1 P45
 '@BASEBOARD_FAB2_LIB.BASEBOARD_FAB2(SCH_1):PAGE41_I284@CHPSET_LIB.SKX_EXT_B(CHIPS)':
 'VSS'<429>: CDS_PINID='VSS(429)';
NODE_NAME     U5D1 CL18
 '@BASEBOARD_FAB2_LIB.BASEBOARD_FAB2(SCH_1):PAGE41_I284@CHPSET_LIB.SKX_EXT_B(CHIPS)':
 'VSS'<430>: CDS_PINID='VSS(430)';
NODE_NAME     U5D1 CL14
 '@BASEBOARD_FAB2_LIB.BASEBOARD_FAB2(SCH_1):PAGE41_I284@CHPSET_LIB.SKX_EXT_B(CHIPS)':
 'VSS'<431>: CDS_PINID='VSS(431)';
NODE_NAME     U5D1 CL8
 '@BASEBOARD_FAB2_LIB.BASEBOARD_FAB2(SCH_1):PAGE41_I284@CHPSET_LIB.SKX_EXT_B(CHIPS)':
 'VSS'<432>: CDS_PINID='VSS(432)';
NODE_NAME     U5D1 CK85
 '@BASEBOARD_FAB2_LIB.BASEBOARD_FAB2(SCH_1):PAGE41_I284@CHPSET_LIB.SKX_EXT_B(CHIPS)':
 'VSS'<433>: CDS_PINID='VSS(433)';
NODE_NAME     U5D1 CK83
 '@BASEBOARD_FAB2_LIB.BASEBOARD_FAB2(SCH_1):PAGE41_I284@CHPSET_LIB.SKX_EXT_B(CHIPS)':
 'VSS'<434>: CDS_PINID='VSS(434)';
NODE_NAME     U5D1 CK75
 '@BASEBOARD_FAB2_LIB.BASEBOARD_FAB2(SCH_1):PAGE41_I284@CHPSET_LIB.SKX_EXT_B(CHIPS)':
 'VSS'<435>: CDS_PINID='VSS(435)';
NODE_NAME     U5D1 CK73
 '@BASEBOARD_FAB2_LIB.BASEBOARD_FAB2(SCH_1):PAGE41_I284@CHPSET_LIB.SKX_EXT_B(CHIPS)':
 'VSS'<436>: CDS_PINID='VSS(436)';
NODE_NAME     U5D1 CK71
 '@BASEBOARD_FAB2_LIB.BASEBOARD_FAB2(SCH_1):PAGE41_I284@CHPSET_LIB.SKX_EXT_B(CHIPS)':
 'VSS'<437>: CDS_PINID='VSS(437)';
NODE_NAME     U5D1 CK69
 '@BASEBOARD_FAB2_LIB.BASEBOARD_FAB2(SCH_1):PAGE41_I284@CHPSET_LIB.SKX_EXT_B(CHIPS)':
 'VSS'<438>: CDS_PINID='VSS(438)';
NODE_NAME     U5D1 CK67
 '@BASEBOARD_FAB2_LIB.BASEBOARD_FAB2(SCH_1):PAGE41_I284@CHPSET_LIB.SKX_EXT_B(CHIPS)':
 'VSS'<439>: CDS_PINID='VSS(439)';
NODE_NAME     U5D1 CK65
 '@BASEBOARD_FAB2_LIB.BASEBOARD_FAB2(SCH_1):PAGE41_I284@CHPSET_LIB.SKX_EXT_B(CHIPS)':
 'VSS'<440>: CDS_PINID='VSS(440)';
NODE_NAME     U5D1 CK63
 '@BASEBOARD_FAB2_LIB.BASEBOARD_FAB2(SCH_1):PAGE41_I284@CHPSET_LIB.SKX_EXT_B(CHIPS)':
 'VSS'<441>: CDS_PINID='VSS(441)';
NODE_NAME     U5D1 CK27
 '@BASEBOARD_FAB2_LIB.BASEBOARD_FAB2(SCH_1):PAGE41_I284@CHPSET_LIB.SKX_EXT_B(CHIPS)':
 'VSS'<442>: CDS_PINID='VSS(442)';
NODE_NAME     U5D1 CK21
 '@BASEBOARD_FAB2_LIB.BASEBOARD_FAB2(SCH_1):PAGE41_I284@CHPSET_LIB.SKX_EXT_B(CHIPS)':
 'VSS'<443>: CDS_PINID='VSS(443)';
NODE_NAME     U5D1 CK15
 '@BASEBOARD_FAB2_LIB.BASEBOARD_FAB2(SCH_1):PAGE41_I284@CHPSET_LIB.SKX_EXT_B(CHIPS)':
 'VSS'<444>: CDS_PINID='VSS(444)';
NODE_NAME     U5D1 CK11
 '@BASEBOARD_FAB2_LIB.BASEBOARD_FAB2(SCH_1):PAGE41_I284@CHPSET_LIB.SKX_EXT_B(CHIPS)':
 'VSS'<445>: CDS_PINID='VSS(445)';
NODE_NAME     U5D1 CJ86
 '@BASEBOARD_FAB2_LIB.BASEBOARD_FAB2(SCH_1):PAGE41_I284@CHPSET_LIB.SKX_EXT_B(CHIPS)':
 'VSS'<446>: CDS_PINID='VSS(446)';
NODE_NAME     U5D1 CJ84
 '@BASEBOARD_FAB2_LIB.BASEBOARD_FAB2(SCH_1):PAGE41_I284@CHPSET_LIB.SKX_EXT_B(CHIPS)':
 'VSS'<447>: CDS_PINID='VSS(447)';
NODE_NAME     U5D1 CJ82
 '@BASEBOARD_FAB2_LIB.BASEBOARD_FAB2(SCH_1):PAGE41_I284@CHPSET_LIB.SKX_EXT_B(CHIPS)':
 'VSS'<448>: CDS_PINID='VSS(448)';
NODE_NAME     U5D1 CJ78
 '@BASEBOARD_FAB2_LIB.BASEBOARD_FAB2(SCH_1):PAGE41_I284@CHPSET_LIB.SKX_EXT_B(CHIPS)':
 'VSS'<449>: CDS_PINID='VSS(449)';
NODE_NAME     U5D1 CJ76
 '@BASEBOARD_FAB2_LIB.BASEBOARD_FAB2(SCH_1):PAGE41_I284@CHPSET_LIB.SKX_EXT_B(CHIPS)':
 'VSS'<450>: CDS_PINID='VSS(450)';
NODE_NAME     U5D1 CJ74
 '@BASEBOARD_FAB2_LIB.BASEBOARD_FAB2(SCH_1):PAGE41_I284@CHPSET_LIB.SKX_EXT_B(CHIPS)':
 'VSS'<451>: CDS_PINID='VSS(451)';
NODE_NAME     U5D1 CJ62
 '@BASEBOARD_FAB2_LIB.BASEBOARD_FAB2(SCH_1):PAGE41_I284@CHPSET_LIB.SKX_EXT_B(CHIPS)':
 'VSS'<452>: CDS_PINID='VSS(452)';
NODE_NAME     U5D1 P47
 '@BASEBOARD_FAB2_LIB.BASEBOARD_FAB2(SCH_1):PAGE41_I284@CHPSET_LIB.SKX_EXT_B(CHIPS)':
 'VSS'<453>: CDS_PINID='VSS(453)';
NODE_NAME     U5D1 DN72
 '@BASEBOARD_FAB2_LIB.BASEBOARD_FAB2(SCH_1):PAGE41_I285@CHPSET_LIB.SKX_EXT_B(CHIPS)':
 'VSS'<134>: CDS_PINID='VSS(134)';
NODE_NAME     U5D1 DN68
 '@BASEBOARD_FAB2_LIB.BASEBOARD_FAB2(SCH_1):PAGE41_I285@CHPSET_LIB.SKX_EXT_B(CHIPS)':
 'VSS'<135>: CDS_PINID='VSS(135)';
NODE_NAME     U5D1 DN38
 '@BASEBOARD_FAB2_LIB.BASEBOARD_FAB2(SCH_1):PAGE41_I285@CHPSET_LIB.SKX_EXT_B(CHIPS)':
 'VSS'<136>: CDS_PINID='VSS(136)';
NODE_NAME     U5D1 DN32
 '@BASEBOARD_FAB2_LIB.BASEBOARD_FAB2(SCH_1):PAGE41_I285@CHPSET_LIB.SKX_EXT_B(CHIPS)':
 'VSS'<137>: CDS_PINID='VSS(137)';
NODE_NAME     U5D1 DN26
 '@BASEBOARD_FAB2_LIB.BASEBOARD_FAB2(SCH_1):PAGE41_I285@CHPSET_LIB.SKX_EXT_B(CHIPS)':
 'VSS'<138>: CDS_PINID='VSS(138)';
NODE_NAME     U5D1 DN22
 '@BASEBOARD_FAB2_LIB.BASEBOARD_FAB2(SCH_1):PAGE41_I285@CHPSET_LIB.SKX_EXT_B(CHIPS)':
 'VSS'<139>: CDS_PINID='VSS(139)';
NODE_NAME     U5D1 DN12
 '@BASEBOARD_FAB2_LIB.BASEBOARD_FAB2(SCH_1):PAGE41_I285@CHPSET_LIB.SKX_EXT_B(CHIPS)':
 'VSS'<140>: CDS_PINID='VSS(140)';
NODE_NAME     U5D1 BH17
 '@BASEBOARD_FAB2_LIB.BASEBOARD_FAB2(SCH_1):PAGE41_I285@CHPSET_LIB.SKX_EXT_B(CHIPS)':
 'VSS'<141>: CDS_PINID='VSS(141)';
NODE_NAME     U5D1 DN2
 '@BASEBOARD_FAB2_LIB.BASEBOARD_FAB2(SCH_1):PAGE41_I285@CHPSET_LIB.SKX_EXT_B(CHIPS)':
 'VSS'<142>: CDS_PINID='VSS(142)';
NODE_NAME     U5D1 DM83
 '@BASEBOARD_FAB2_LIB.BASEBOARD_FAB2(SCH_1):PAGE41_I285@CHPSET_LIB.SKX_EXT_B(CHIPS)':
 'VSS'<143>: CDS_PINID='VSS(143)';
NODE_NAME     U5D1 DM77
 '@BASEBOARD_FAB2_LIB.BASEBOARD_FAB2(SCH_1):PAGE41_I285@CHPSET_LIB.SKX_EXT_B(CHIPS)':
 'VSS'<144>: CDS_PINID='VSS(144)';
NODE_NAME     U5D1 DM73
 '@BASEBOARD_FAB2_LIB.BASEBOARD_FAB2(SCH_1):PAGE41_I285@CHPSET_LIB.SKX_EXT_B(CHIPS)':
 'VSS'<145>: CDS_PINID='VSS(145)';
NODE_NAME     U5D1 DM65
 '@BASEBOARD_FAB2_LIB.BASEBOARD_FAB2(SCH_1):PAGE41_I285@CHPSET_LIB.SKX_EXT_B(CHIPS)':
 'VSS'<146>: CDS_PINID='VSS(146)';
NODE_NAME     U5D1 DM39
 '@BASEBOARD_FAB2_LIB.BASEBOARD_FAB2(SCH_1):PAGE41_I285@CHPSET_LIB.SKX_EXT_B(CHIPS)':
 'VSS'<147>: CDS_PINID='VSS(147)';
NODE_NAME     U5D1 DM37
 '@BASEBOARD_FAB2_LIB.BASEBOARD_FAB2(SCH_1):PAGE41_I285@CHPSET_LIB.SKX_EXT_B(CHIPS)':
 'VSS'<148>: CDS_PINID='VSS(148)';
NODE_NAME     U5D1 DM33
 '@BASEBOARD_FAB2_LIB.BASEBOARD_FAB2(SCH_1):PAGE41_I285@CHPSET_LIB.SKX_EXT_B(CHIPS)':
 'VSS'<149>: CDS_PINID='VSS(149)';
NODE_NAME     U5D1 DM31
 '@BASEBOARD_FAB2_LIB.BASEBOARD_FAB2(SCH_1):PAGE41_I285@CHPSET_LIB.SKX_EXT_B(CHIPS)':
 'VSS'<150>: CDS_PINID='VSS(150)';
NODE_NAME     U5D1 DM27
 '@BASEBOARD_FAB2_LIB.BASEBOARD_FAB2(SCH_1):PAGE41_I285@CHPSET_LIB.SKX_EXT_B(CHIPS)':
 'VSS'<151>: CDS_PINID='VSS(151)';
NODE_NAME     U5D1 DM25
 '@BASEBOARD_FAB2_LIB.BASEBOARD_FAB2(SCH_1):PAGE41_I285@CHPSET_LIB.SKX_EXT_B(CHIPS)':
 'VSS'<152>: CDS_PINID='VSS(152)';
NODE_NAME     U5D1 H45
 '@BASEBOARD_FAB2_LIB.BASEBOARD_FAB2(SCH_1):PAGE41_I285@CHPSET_LIB.SKX_EXT_B(CHIPS)':
 'VSS'<153>: CDS_PINID='VSS(153)';
NODE_NAME     U5D1 DM15
 '@BASEBOARD_FAB2_LIB.BASEBOARD_FAB2(SCH_1):PAGE41_I285@CHPSET_LIB.SKX_EXT_B(CHIPS)':
 'VSS'<154>: CDS_PINID='VSS(154)';
NODE_NAME     U5D1 DL80
 '@BASEBOARD_FAB2_LIB.BASEBOARD_FAB2(SCH_1):PAGE41_I285@CHPSET_LIB.SKX_EXT_B(CHIPS)':
 'VSS'<155>: CDS_PINID='VSS(155)';
NODE_NAME     U5D1 DL78
 '@BASEBOARD_FAB2_LIB.BASEBOARD_FAB2(SCH_1):PAGE41_I285@CHPSET_LIB.SKX_EXT_B(CHIPS)':
 'VSS'<156>: CDS_PINID='VSS(156)';
NODE_NAME     U5D1 DL76
 '@BASEBOARD_FAB2_LIB.BASEBOARD_FAB2(SCH_1):PAGE41_I285@CHPSET_LIB.SKX_EXT_B(CHIPS)':
 'VSS'<157>: CDS_PINID='VSS(157)';
NODE_NAME     U5D1 DL74
 '@BASEBOARD_FAB2_LIB.BASEBOARD_FAB2(SCH_1):PAGE41_I285@CHPSET_LIB.SKX_EXT_B(CHIPS)':
 'VSS'<158>: CDS_PINID='VSS(158)';
NODE_NAME     U5D1 DL70
 '@BASEBOARD_FAB2_LIB.BASEBOARD_FAB2(SCH_1):PAGE41_I285@CHPSET_LIB.SKX_EXT_B(CHIPS)':
 'VSS'<159>: CDS_PINID='VSS(159)';
NODE_NAME     U5D1 DL68
 '@BASEBOARD_FAB2_LIB.BASEBOARD_FAB2(SCH_1):PAGE41_I285@CHPSET_LIB.SKX_EXT_B(CHIPS)':
 'VSS'<160>: CDS_PINID='VSS(160)';
NODE_NAME     U5D1 DL40
 '@BASEBOARD_FAB2_LIB.BASEBOARD_FAB2(SCH_1):PAGE41_I285@CHPSET_LIB.SKX_EXT_B(CHIPS)':
 'VSS'<161>: CDS_PINID='VSS(161)';
NODE_NAME     U5D1 DL36
 '@BASEBOARD_FAB2_LIB.BASEBOARD_FAB2(SCH_1):PAGE41_I285@CHPSET_LIB.SKX_EXT_B(CHIPS)':
 'VSS'<162>: CDS_PINID='VSS(162)';
NODE_NAME     U5D1 DL34
 '@BASEBOARD_FAB2_LIB.BASEBOARD_FAB2(SCH_1):PAGE41_I285@CHPSET_LIB.SKX_EXT_B(CHIPS)':
 'VSS'<163>: CDS_PINID='VSS(163)';
NODE_NAME     U5D1 DL30
 '@BASEBOARD_FAB2_LIB.BASEBOARD_FAB2(SCH_1):PAGE41_I285@CHPSET_LIB.SKX_EXT_B(CHIPS)':
 'VSS'<164>: CDS_PINID='VSS(164)';
NODE_NAME     U5D1 DL28
 '@BASEBOARD_FAB2_LIB.BASEBOARD_FAB2(SCH_1):PAGE41_I285@CHPSET_LIB.SKX_EXT_B(CHIPS)':
 'VSS'<165>: CDS_PINID='VSS(165)';
NODE_NAME     U5D1 DL24
 '@BASEBOARD_FAB2_LIB.BASEBOARD_FAB2(SCH_1):PAGE41_I285@CHPSET_LIB.SKX_EXT_B(CHIPS)':
 'VSS'<166>: CDS_PINID='VSS(166)';
NODE_NAME     U5D1 DL22
 '@BASEBOARD_FAB2_LIB.BASEBOARD_FAB2(SCH_1):PAGE41_I285@CHPSET_LIB.SKX_EXT_B(CHIPS)':
 'VSS'<167>: CDS_PINID='VSS(167)';
NODE_NAME     U5D1 DL4
 '@BASEBOARD_FAB2_LIB.BASEBOARD_FAB2(SCH_1):PAGE41_I285@CHPSET_LIB.SKX_EXT_B(CHIPS)':
 'VSS'<168>: CDS_PINID='VSS(168)';
NODE_NAME     U5D1 DL18
 '@BASEBOARD_FAB2_LIB.BASEBOARD_FAB2(SCH_1):PAGE41_I285@CHPSET_LIB.SKX_EXT_B(CHIPS)':
 'VSS'<169>: CDS_PINID='VSS(169)';
NODE_NAME     U5D1 DL16
 '@BASEBOARD_FAB2_LIB.BASEBOARD_FAB2(SCH_1):PAGE41_I285@CHPSET_LIB.SKX_EXT_B(CHIPS)':
 'VSS'<170>: CDS_PINID='VSS(170)';
NODE_NAME     U5D1 DK85
 '@BASEBOARD_FAB2_LIB.BASEBOARD_FAB2(SCH_1):PAGE41_I285@CHPSET_LIB.SKX_EXT_B(CHIPS)':
 'VSS'<171>: CDS_PINID='VSS(171)';
NODE_NAME     U5D1 DK83
 '@BASEBOARD_FAB2_LIB.BASEBOARD_FAB2(SCH_1):PAGE41_I285@CHPSET_LIB.SKX_EXT_B(CHIPS)':
 'VSS'<172>: CDS_PINID='VSS(172)';
NODE_NAME     U5D1 DK77
 '@BASEBOARD_FAB2_LIB.BASEBOARD_FAB2(SCH_1):PAGE41_I285@CHPSET_LIB.SKX_EXT_B(CHIPS)':
 'VSS'<173>: CDS_PINID='VSS(173)';
NODE_NAME     U5D1 DK75
 '@BASEBOARD_FAB2_LIB.BASEBOARD_FAB2(SCH_1):PAGE41_I285@CHPSET_LIB.SKX_EXT_B(CHIPS)':
 'VSS'<174>: CDS_PINID='VSS(174)';
NODE_NAME     U5D1 DK73
 '@BASEBOARD_FAB2_LIB.BASEBOARD_FAB2(SCH_1):PAGE41_I285@CHPSET_LIB.SKX_EXT_B(CHIPS)':
 'VSS'<175>: CDS_PINID='VSS(175)';
NODE_NAME     U5D1 DK41
 '@BASEBOARD_FAB2_LIB.BASEBOARD_FAB2(SCH_1):PAGE41_I285@CHPSET_LIB.SKX_EXT_B(CHIPS)':
 'VSS'<176>: CDS_PINID='VSS(176)';
NODE_NAME     U5D1 DK39
 '@BASEBOARD_FAB2_LIB.BASEBOARD_FAB2(SCH_1):PAGE41_I285@CHPSET_LIB.SKX_EXT_B(CHIPS)':
 'VSS'<177>: CDS_PINID='VSS(177)';
NODE_NAME     U5D1 DK35
 '@BASEBOARD_FAB2_LIB.BASEBOARD_FAB2(SCH_1):PAGE41_I285@CHPSET_LIB.SKX_EXT_B(CHIPS)':
 'VSS'<178>: CDS_PINID='VSS(178)';
NODE_NAME     U5D1 DK29
 '@BASEBOARD_FAB2_LIB.BASEBOARD_FAB2(SCH_1):PAGE41_I285@CHPSET_LIB.SKX_EXT_B(CHIPS)':
 'VSS'<179>: CDS_PINID='VSS(179)';
NODE_NAME     U5D1 DK23
 '@BASEBOARD_FAB2_LIB.BASEBOARD_FAB2(SCH_1):PAGE41_I285@CHPSET_LIB.SKX_EXT_B(CHIPS)':
 'VSS'<180>: CDS_PINID='VSS(180)';
NODE_NAME     U5D1 DK7
 '@BASEBOARD_FAB2_LIB.BASEBOARD_FAB2(SCH_1):PAGE41_I285@CHPSET_LIB.SKX_EXT_B(CHIPS)':
 'VSS'<181>: CDS_PINID='VSS(181)';
NODE_NAME     U5D1 DJ84
 '@BASEBOARD_FAB2_LIB.BASEBOARD_FAB2(SCH_1):PAGE41_I285@CHPSET_LIB.SKX_EXT_B(CHIPS)':
 'VSS'<182>: CDS_PINID='VSS(182)';
NODE_NAME     U5D1 DJ82
 '@BASEBOARD_FAB2_LIB.BASEBOARD_FAB2(SCH_1):PAGE41_I285@CHPSET_LIB.SKX_EXT_B(CHIPS)':
 'VSS'<183>: CDS_PINID='VSS(183)';
NODE_NAME     U5D1 DJ78
 '@BASEBOARD_FAB2_LIB.BASEBOARD_FAB2(SCH_1):PAGE41_I285@CHPSET_LIB.SKX_EXT_B(CHIPS)':
 'VSS'<184>: CDS_PINID='VSS(184)';
NODE_NAME     U5D1 DJ74
 '@BASEBOARD_FAB2_LIB.BASEBOARD_FAB2(SCH_1):PAGE41_I285@CHPSET_LIB.SKX_EXT_B(CHIPS)':
 'VSS'<185>: CDS_PINID='VSS(185)';
NODE_NAME     U5D1 DJ68
 '@BASEBOARD_FAB2_LIB.BASEBOARD_FAB2(SCH_1):PAGE41_I285@CHPSET_LIB.SKX_EXT_B(CHIPS)':
 'VSS'<186>: CDS_PINID='VSS(186)';
NODE_NAME     U5D1 DJ42
 '@BASEBOARD_FAB2_LIB.BASEBOARD_FAB2(SCH_1):PAGE41_I285@CHPSET_LIB.SKX_EXT_B(CHIPS)':
 'VSS'<187>: CDS_PINID='VSS(187)';
NODE_NAME     U5D1 DJ38
 '@BASEBOARD_FAB2_LIB.BASEBOARD_FAB2(SCH_1):PAGE41_I285@CHPSET_LIB.SKX_EXT_B(CHIPS)':
 'VSS'<188>: CDS_PINID='VSS(188)';
NODE_NAME     U5D1 DJ22
 '@BASEBOARD_FAB2_LIB.BASEBOARD_FAB2(SCH_1):PAGE41_I285@CHPSET_LIB.SKX_EXT_B(CHIPS)':
 'VSS'<189>: CDS_PINID='VSS(189)';
NODE_NAME     U5D1 H47
 '@BASEBOARD_FAB2_LIB.BASEBOARD_FAB2(SCH_1):PAGE41_I285@CHPSET_LIB.SKX_EXT_B(CHIPS)':
 'VSS'<190>: CDS_PINID='VSS(190)';
NODE_NAME     U5D1 DJ10
 '@BASEBOARD_FAB2_LIB.BASEBOARD_FAB2(SCH_1):PAGE41_I285@CHPSET_LIB.SKX_EXT_B(CHIPS)':
 'VSS'<191>: CDS_PINID='VSS(191)';
NODE_NAME     U5D1 DJ2
 '@BASEBOARD_FAB2_LIB.BASEBOARD_FAB2(SCH_1):PAGE41_I285@CHPSET_LIB.SKX_EXT_B(CHIPS)':
 'VSS'<192>: CDS_PINID='VSS(192)';
NODE_NAME     U5D1 DH83
 '@BASEBOARD_FAB2_LIB.BASEBOARD_FAB2(SCH_1):PAGE41_I285@CHPSET_LIB.SKX_EXT_B(CHIPS)':
 'VSS'<193>: CDS_PINID='VSS(193)';
NODE_NAME     U5D1 DH81
 '@BASEBOARD_FAB2_LIB.BASEBOARD_FAB2(SCH_1):PAGE41_I285@CHPSET_LIB.SKX_EXT_B(CHIPS)':
 'VSS'<194>: CDS_PINID='VSS(194)';
NODE_NAME     U5D1 DH79
 '@BASEBOARD_FAB2_LIB.BASEBOARD_FAB2(SCH_1):PAGE41_I285@CHPSET_LIB.SKX_EXT_B(CHIPS)':
 'VSS'<195>: CDS_PINID='VSS(195)';
NODE_NAME     U5D1 DH73
 '@BASEBOARD_FAB2_LIB.BASEBOARD_FAB2(SCH_1):PAGE41_I285@CHPSET_LIB.SKX_EXT_B(CHIPS)':
 'VSS'<196>: CDS_PINID='VSS(196)';
NODE_NAME     U5D1 DH71
 '@BASEBOARD_FAB2_LIB.BASEBOARD_FAB2(SCH_1):PAGE41_I285@CHPSET_LIB.SKX_EXT_B(CHIPS)':
 'VSS'<197>: CDS_PINID='VSS(197)';
NODE_NAME     U5D1 DH67
 '@BASEBOARD_FAB2_LIB.BASEBOARD_FAB2(SCH_1):PAGE41_I285@CHPSET_LIB.SKX_EXT_B(CHIPS)':
 'VSS'<198>: CDS_PINID='VSS(198)';
NODE_NAME     U5D1 DH41
 '@BASEBOARD_FAB2_LIB.BASEBOARD_FAB2(SCH_1):PAGE41_I285@CHPSET_LIB.SKX_EXT_B(CHIPS)':
 'VSS'<199>: CDS_PINID='VSS(199)';
NODE_NAME     U5D1 DH37
 '@BASEBOARD_FAB2_LIB.BASEBOARD_FAB2(SCH_1):PAGE41_I285@CHPSET_LIB.SKX_EXT_B(CHIPS)':
 'VSS'<200>: CDS_PINID='VSS(200)';
NODE_NAME     U5D1 DH35
 '@BASEBOARD_FAB2_LIB.BASEBOARD_FAB2(SCH_1):PAGE41_I285@CHPSET_LIB.SKX_EXT_B(CHIPS)':
 'VSS'<201>: CDS_PINID='VSS(201)';
NODE_NAME     U5D1 DH33
 '@BASEBOARD_FAB2_LIB.BASEBOARD_FAB2(SCH_1):PAGE41_I285@CHPSET_LIB.SKX_EXT_B(CHIPS)':
 'VSS'<202>: CDS_PINID='VSS(202)';
NODE_NAME     U5D1 DH31
 '@BASEBOARD_FAB2_LIB.BASEBOARD_FAB2(SCH_1):PAGE41_I285@CHPSET_LIB.SKX_EXT_B(CHIPS)':
 'VSS'<203>: CDS_PINID='VSS(203)';
NODE_NAME     U5D1 DH29
 '@BASEBOARD_FAB2_LIB.BASEBOARD_FAB2(SCH_1):PAGE41_I285@CHPSET_LIB.SKX_EXT_B(CHIPS)':
 'VSS'<204>: CDS_PINID='VSS(204)';
NODE_NAME     U5D1 DH27
 '@BASEBOARD_FAB2_LIB.BASEBOARD_FAB2(SCH_1):PAGE41_I285@CHPSET_LIB.SKX_EXT_B(CHIPS)':
 'VSS'<205>: CDS_PINID='VSS(205)';
NODE_NAME     U5D1 DH25
 '@BASEBOARD_FAB2_LIB.BASEBOARD_FAB2(SCH_1):PAGE41_I285@CHPSET_LIB.SKX_EXT_B(CHIPS)':
 'VSS'<206>: CDS_PINID='VSS(206)';
NODE_NAME     U5D1 DH23
 '@BASEBOARD_FAB2_LIB.BASEBOARD_FAB2(SCH_1):PAGE41_I285@CHPSET_LIB.SKX_EXT_B(CHIPS)':
 'VSS'<207>: CDS_PINID='VSS(207)';
NODE_NAME     U5D1 DH15
 '@BASEBOARD_FAB2_LIB.BASEBOARD_FAB2(SCH_1):PAGE41_I285@CHPSET_LIB.SKX_EXT_B(CHIPS)':
 'VSS'<208>: CDS_PINID='VSS(208)';
NODE_NAME     U5D1 DH13
 '@BASEBOARD_FAB2_LIB.BASEBOARD_FAB2(SCH_1):PAGE41_I285@CHPSET_LIB.SKX_EXT_B(CHIPS)':
 'VSS'<209>: CDS_PINID='VSS(209)';
NODE_NAME     U5D1 DG82
 '@BASEBOARD_FAB2_LIB.BASEBOARD_FAB2(SCH_1):PAGE41_I285@CHPSET_LIB.SKX_EXT_B(CHIPS)':
 'VSS'<210>: CDS_PINID='VSS(210)';
NODE_NAME     U5D1 DG80
 '@BASEBOARD_FAB2_LIB.BASEBOARD_FAB2(SCH_1):PAGE41_I285@CHPSET_LIB.SKX_EXT_B(CHIPS)':
 'VSS'<211>: CDS_PINID='VSS(211)';
NODE_NAME     U5D1 DG78
 '@BASEBOARD_FAB2_LIB.BASEBOARD_FAB2(SCH_1):PAGE41_I285@CHPSET_LIB.SKX_EXT_B(CHIPS)':
 'VSS'<212>: CDS_PINID='VSS(212)';
NODE_NAME     U5D1 DG76
 '@BASEBOARD_FAB2_LIB.BASEBOARD_FAB2(SCH_1):PAGE41_I285@CHPSET_LIB.SKX_EXT_B(CHIPS)':
 'VSS'<213>: CDS_PINID='VSS(213)';
NODE_NAME     U5D1 DG68
 '@BASEBOARD_FAB2_LIB.BASEBOARD_FAB2(SCH_1):PAGE41_I285@CHPSET_LIB.SKX_EXT_B(CHIPS)':
 'VSS'<214>: CDS_PINID='VSS(214)';
NODE_NAME     U5D1 DG66
 '@BASEBOARD_FAB2_LIB.BASEBOARD_FAB2(SCH_1):PAGE41_I285@CHPSET_LIB.SKX_EXT_B(CHIPS)':
 'VSS'<215>: CDS_PINID='VSS(215)';
NODE_NAME     U5D1 DG24
 '@BASEBOARD_FAB2_LIB.BASEBOARD_FAB2(SCH_1):PAGE41_I285@CHPSET_LIB.SKX_EXT_B(CHIPS)':
 'VSS'<216>: CDS_PINID='VSS(216)';
NODE_NAME     U5D1 DG16
 '@BASEBOARD_FAB2_LIB.BASEBOARD_FAB2(SCH_1):PAGE41_I285@CHPSET_LIB.SKX_EXT_B(CHIPS)':
 'VSS'<217>: CDS_PINID='VSS(217)';
NODE_NAME     U5D1 DG14
 '@BASEBOARD_FAB2_LIB.BASEBOARD_FAB2(SCH_1):PAGE41_I285@CHPSET_LIB.SKX_EXT_B(CHIPS)':
 'VSS'<218>: CDS_PINID='VSS(218)';
NODE_NAME     U5D1 H49
 '@BASEBOARD_FAB2_LIB.BASEBOARD_FAB2(SCH_1):PAGE41_I285@CHPSET_LIB.SKX_EXT_B(CHIPS)':
 'VSS'<219>: CDS_PINID='VSS(219)';
NODE_NAME     U5D1 DG2
 '@BASEBOARD_FAB2_LIB.BASEBOARD_FAB2(SCH_1):PAGE41_I285@CHPSET_LIB.SKX_EXT_B(CHIPS)':
 'VSS'<220>: CDS_PINID='VSS(220)';
NODE_NAME     U5D1 DF85
 '@BASEBOARD_FAB2_LIB.BASEBOARD_FAB2(SCH_1):PAGE41_I285@CHPSET_LIB.SKX_EXT_B(CHIPS)':
 'VSS'<221>: CDS_PINID='VSS(221)';
NODE_NAME     U5D1 DF83
 '@BASEBOARD_FAB2_LIB.BASEBOARD_FAB2(SCH_1):PAGE41_I285@CHPSET_LIB.SKX_EXT_B(CHIPS)':
 'VSS'<222>: CDS_PINID='VSS(222)';
NODE_NAME     U5D1 DF79
 '@BASEBOARD_FAB2_LIB.BASEBOARD_FAB2(SCH_1):PAGE41_I285@CHPSET_LIB.SKX_EXT_B(CHIPS)':
 'VSS'<223>: CDS_PINID='VSS(223)';
NODE_NAME     U5D1 DF73
 '@BASEBOARD_FAB2_LIB.BASEBOARD_FAB2(SCH_1):PAGE41_I285@CHPSET_LIB.SKX_EXT_B(CHIPS)':
 'VSS'<224>: CDS_PINID='VSS(224)';
NODE_NAME     U5D1 DF69
 '@BASEBOARD_FAB2_LIB.BASEBOARD_FAB2(SCH_1):PAGE41_I285@CHPSET_LIB.SKX_EXT_B(CHIPS)':
 'VSS'<225>: CDS_PINID='VSS(225)';
NODE_NAME     U5D1 DF65
 '@BASEBOARD_FAB2_LIB.BASEBOARD_FAB2(SCH_1):PAGE41_I285@CHPSET_LIB.SKX_EXT_B(CHIPS)':
 'VSS'<226>: CDS_PINID='VSS(226)';
NODE_NAME     U5D1 DF41
 '@BASEBOARD_FAB2_LIB.BASEBOARD_FAB2(SCH_1):PAGE41_I285@CHPSET_LIB.SKX_EXT_B(CHIPS)':
 'VSS'<227>: CDS_PINID='VSS(227)';
NODE_NAME     U5D1 DF39
 '@BASEBOARD_FAB2_LIB.BASEBOARD_FAB2(SCH_1):PAGE41_I285@CHPSET_LIB.SKX_EXT_B(CHIPS)':
 'VSS'<228>: CDS_PINID='VSS(228)';
NODE_NAME     U5D1 DF37
 '@BASEBOARD_FAB2_LIB.BASEBOARD_FAB2(SCH_1):PAGE41_I285@CHPSET_LIB.SKX_EXT_B(CHIPS)':
 'VSS'<229>: CDS_PINID='VSS(229)';
NODE_NAME     U5D1 DF35
 '@BASEBOARD_FAB2_LIB.BASEBOARD_FAB2(SCH_1):PAGE41_I285@CHPSET_LIB.SKX_EXT_B(CHIPS)':
 'VSS'<230>: CDS_PINID='VSS(230)';
NODE_NAME     U5D1 DF29
 '@BASEBOARD_FAB2_LIB.BASEBOARD_FAB2(SCH_1):PAGE41_I285@CHPSET_LIB.SKX_EXT_B(CHIPS)':
 'VSS'<231>: CDS_PINID='VSS(231)';
NODE_NAME     U5D1 DF19
 '@BASEBOARD_FAB2_LIB.BASEBOARD_FAB2(SCH_1):PAGE41_I285@CHPSET_LIB.SKX_EXT_B(CHIPS)':
 'VSS'<232>: CDS_PINID='VSS(232)';
NODE_NAME     U5D1 H51
 '@BASEBOARD_FAB2_LIB.BASEBOARD_FAB2(SCH_1):PAGE41_I285@CHPSET_LIB.SKX_EXT_B(CHIPS)':
 'VSS'<233>: CDS_PINID='VSS(233)';
NODE_NAME     U5D1 DF7
 '@BASEBOARD_FAB2_LIB.BASEBOARD_FAB2(SCH_1):PAGE41_I285@CHPSET_LIB.SKX_EXT_B(CHIPS)':
 'VSS'<234>: CDS_PINID='VSS(234)';
NODE_NAME     U5D1 DF5
 '@BASEBOARD_FAB2_LIB.BASEBOARD_FAB2(SCH_1):PAGE41_I285@CHPSET_LIB.SKX_EXT_B(CHIPS)':
 'VSS'<235>: CDS_PINID='VSS(235)';
NODE_NAME     U5D1 DE78
 '@BASEBOARD_FAB2_LIB.BASEBOARD_FAB2(SCH_1):PAGE41_I285@CHPSET_LIB.SKX_EXT_B(CHIPS)':
 'VSS'<236>: CDS_PINID='VSS(236)';
NODE_NAME     U5D1 DE72
 '@BASEBOARD_FAB2_LIB.BASEBOARD_FAB2(SCH_1):PAGE41_I285@CHPSET_LIB.SKX_EXT_B(CHIPS)':
 'VSS'<237>: CDS_PINID='VSS(237)';
NODE_NAME     U5D1 DE70
 '@BASEBOARD_FAB2_LIB.BASEBOARD_FAB2(SCH_1):PAGE41_I285@CHPSET_LIB.SKX_EXT_B(CHIPS)':
 'VSS'<238>: CDS_PINID='VSS(238)';
NODE_NAME     U5D1 DE64
 '@BASEBOARD_FAB2_LIB.BASEBOARD_FAB2(SCH_1):PAGE41_I285@CHPSET_LIB.SKX_EXT_B(CHIPS)':
 'VSS'<239>: CDS_PINID='VSS(239)';
NODE_NAME     U5D1 DE36
 '@BASEBOARD_FAB2_LIB.BASEBOARD_FAB2(SCH_1):PAGE41_I285@CHPSET_LIB.SKX_EXT_B(CHIPS)':
 'VSS'<240>: CDS_PINID='VSS(240)';
NODE_NAME     U5D1 DE34
 '@BASEBOARD_FAB2_LIB.BASEBOARD_FAB2(SCH_1):PAGE41_I285@CHPSET_LIB.SKX_EXT_B(CHIPS)':
 'VSS'<241>: CDS_PINID='VSS(241)';
NODE_NAME     U5D1 DE30
 '@BASEBOARD_FAB2_LIB.BASEBOARD_FAB2(SCH_1):PAGE41_I285@CHPSET_LIB.SKX_EXT_B(CHIPS)':
 'VSS'<242>: CDS_PINID='VSS(242)';
NODE_NAME     U5D1 DE28
 '@BASEBOARD_FAB2_LIB.BASEBOARD_FAB2(SCH_1):PAGE41_I285@CHPSET_LIB.SKX_EXT_B(CHIPS)':
 'VSS'<243>: CDS_PINID='VSS(243)';
NODE_NAME     U5D1 DE24
 '@BASEBOARD_FAB2_LIB.BASEBOARD_FAB2(SCH_1):PAGE41_I285@CHPSET_LIB.SKX_EXT_B(CHIPS)':
 'VSS'<244>: CDS_PINID='VSS(244)';
NODE_NAME     U5D1 DE20
 '@BASEBOARD_FAB2_LIB.BASEBOARD_FAB2(SCH_1):PAGE41_I285@CHPSET_LIB.SKX_EXT_B(CHIPS)':
 'VSS'<245>: CDS_PINID='VSS(245)';
NODE_NAME     U5D1 DE18
 '@BASEBOARD_FAB2_LIB.BASEBOARD_FAB2(SCH_1):PAGE41_I285@CHPSET_LIB.SKX_EXT_B(CHIPS)':
 'VSS'<246>: CDS_PINID='VSS(246)';
NODE_NAME     U5D1 DE8
 '@BASEBOARD_FAB2_LIB.BASEBOARD_FAB2(SCH_1):PAGE41_I285@CHPSET_LIB.SKX_EXT_B(CHIPS)':
 'VSS'<247>: CDS_PINID='VSS(247)';
NODE_NAME     U5D1 DE6
 '@BASEBOARD_FAB2_LIB.BASEBOARD_FAB2(SCH_1):PAGE41_I285@CHPSET_LIB.SKX_EXT_B(CHIPS)':
 'VSS'<248>: CDS_PINID='VSS(248)';
NODE_NAME     U5D1 DD83
 '@BASEBOARD_FAB2_LIB.BASEBOARD_FAB2(SCH_1):PAGE41_I285@CHPSET_LIB.SKX_EXT_B(CHIPS)':
 'VSS'<249>: CDS_PINID='VSS(249)';
NODE_NAME     U5D1 DD81
 '@BASEBOARD_FAB2_LIB.BASEBOARD_FAB2(SCH_1):PAGE41_I285@CHPSET_LIB.SKX_EXT_B(CHIPS)':
 'VSS'<250>: CDS_PINID='VSS(250)';
NODE_NAME     U5D1 DD75
 '@BASEBOARD_FAB2_LIB.BASEBOARD_FAB2(SCH_1):PAGE41_I285@CHPSET_LIB.SKX_EXT_B(CHIPS)':
 'VSS'<251>: CDS_PINID='VSS(251)';
NODE_NAME     U5D1 DD73
 '@BASEBOARD_FAB2_LIB.BASEBOARD_FAB2(SCH_1):PAGE41_I285@CHPSET_LIB.SKX_EXT_B(CHIPS)':
 'VSS'<252>: CDS_PINID='VSS(252)';
NODE_NAME     U5D1 DD71
 '@BASEBOARD_FAB2_LIB.BASEBOARD_FAB2(SCH_1):PAGE41_I285@CHPSET_LIB.SKX_EXT_B(CHIPS)':
 'VSS'<253>: CDS_PINID='VSS(253)';
NODE_NAME     U5D1 DD37
 '@BASEBOARD_FAB2_LIB.BASEBOARD_FAB2(SCH_1):PAGE41_I285@CHPSET_LIB.SKX_EXT_B(CHIPS)':
 'VSS'<254>: CDS_PINID='VSS(254)';
NODE_NAME     U5D1 DD33
 '@BASEBOARD_FAB2_LIB.BASEBOARD_FAB2(SCH_1):PAGE41_I285@CHPSET_LIB.SKX_EXT_B(CHIPS)':
 'VSS'<255>: CDS_PINID='VSS(255)';
NODE_NAME     U5D1 DD31
 '@BASEBOARD_FAB2_LIB.BASEBOARD_FAB2(SCH_1):PAGE41_I285@CHPSET_LIB.SKX_EXT_B(CHIPS)':
 'VSS'<256>: CDS_PINID='VSS(256)';
NODE_NAME     U5D1 DD27
 '@BASEBOARD_FAB2_LIB.BASEBOARD_FAB2(SCH_1):PAGE41_I285@CHPSET_LIB.SKX_EXT_B(CHIPS)':
 'VSS'<257>: CDS_PINID='VSS(257)';
NODE_NAME     U5D1 DD23
 '@BASEBOARD_FAB2_LIB.BASEBOARD_FAB2(SCH_1):PAGE41_I285@CHPSET_LIB.SKX_EXT_B(CHIPS)':
 'VSS'<258>: CDS_PINID='VSS(258)';
NODE_NAME     U5D1 DD11
 '@BASEBOARD_FAB2_LIB.BASEBOARD_FAB2(SCH_1):PAGE41_I285@CHPSET_LIB.SKX_EXT_B(CHIPS)':
 'VSS'<259>: CDS_PINID='VSS(259)';
NODE_NAME     U5D1 DC86
 '@BASEBOARD_FAB2_LIB.BASEBOARD_FAB2(SCH_1):PAGE41_I285@CHPSET_LIB.SKX_EXT_B(CHIPS)':
 'VSS'<260>: CDS_PINID='VSS(260)';
NODE_NAME     U5D1 DC84
 '@BASEBOARD_FAB2_LIB.BASEBOARD_FAB2(SCH_1):PAGE41_I285@CHPSET_LIB.SKX_EXT_B(CHIPS)':
 'VSS'<261>: CDS_PINID='VSS(261)';
NODE_NAME     U5D1 DC78
 '@BASEBOARD_FAB2_LIB.BASEBOARD_FAB2(SCH_1):PAGE41_I285@CHPSET_LIB.SKX_EXT_B(CHIPS)':
 'VSS'<262>: CDS_PINID='VSS(262)';
NODE_NAME     U5D1 DC70
 '@BASEBOARD_FAB2_LIB.BASEBOARD_FAB2(SCH_1):PAGE41_I285@CHPSET_LIB.SKX_EXT_B(CHIPS)':
 'VSS'<263>: CDS_PINID='VSS(263)';
NODE_NAME     U5D1 DC68
 '@BASEBOARD_FAB2_LIB.BASEBOARD_FAB2(SCH_1):PAGE41_I285@CHPSET_LIB.SKX_EXT_B(CHIPS)':
 'VSS'<264>: CDS_PINID='VSS(264)';
NODE_NAME     U5D1 DC66
 '@BASEBOARD_FAB2_LIB.BASEBOARD_FAB2(SCH_1):PAGE41_I285@CHPSET_LIB.SKX_EXT_B(CHIPS)':
 'VSS'<265>: CDS_PINID='VSS(265)';
NODE_NAME     U5D1 DC64
 '@BASEBOARD_FAB2_LIB.BASEBOARD_FAB2(SCH_1):PAGE41_I285@CHPSET_LIB.SKX_EXT_B(CHIPS)':
 'VSS'<266>: CDS_PINID='VSS(266)';
NODE_NAME     U5D1 DC42
 '@BASEBOARD_FAB2_LIB.BASEBOARD_FAB2(SCH_1):PAGE41_I285@CHPSET_LIB.SKX_EXT_B(CHIPS)':
 'VSS'<267>: CDS_PINID='VSS(267)';
NODE_NAME     U5D1 DC38
 '@BASEBOARD_FAB2_LIB.BASEBOARD_FAB2(SCH_1):PAGE41_I285@CHPSET_LIB.SKX_EXT_B(CHIPS)':
 'VSS'<268>: CDS_PINID='VSS(268)';
NODE_NAME     U5D1 DC32
 '@BASEBOARD_FAB2_LIB.BASEBOARD_FAB2(SCH_1):PAGE41_I285@CHPSET_LIB.SKX_EXT_B(CHIPS)':
 'VSS'<269>: CDS_PINID='VSS(269)';
NODE_NAME     U5D1 DC26
 '@BASEBOARD_FAB2_LIB.BASEBOARD_FAB2(SCH_1):PAGE41_I285@CHPSET_LIB.SKX_EXT_B(CHIPS)':
 'VSS'<270>: CDS_PINID='VSS(270)';
NODE_NAME     U5D1 DC24
 '@BASEBOARD_FAB2_LIB.BASEBOARD_FAB2(SCH_1):PAGE41_I285@CHPSET_LIB.SKX_EXT_B(CHIPS)':
 'VSS'<271>: CDS_PINID='VSS(271)';
NODE_NAME     U5D1 DC14
 '@BASEBOARD_FAB2_LIB.BASEBOARD_FAB2(SCH_1):PAGE41_I285@CHPSET_LIB.SKX_EXT_B(CHIPS)':
 'VSS'<272>: CDS_PINID='VSS(272)';
NODE_NAME     U5D1 DB85
 '@BASEBOARD_FAB2_LIB.BASEBOARD_FAB2(SCH_1):PAGE41_I285@CHPSET_LIB.SKX_EXT_B(CHIPS)':
 'VSS'<273>: CDS_PINID='VSS(273)';
NODE_NAME     U5D1 DB83
 '@BASEBOARD_FAB2_LIB.BASEBOARD_FAB2(SCH_1):PAGE41_I285@CHPSET_LIB.SKX_EXT_B(CHIPS)':
 'VSS'<274>: CDS_PINID='VSS(274)';
NODE_NAME     U5D1 DB77
 '@BASEBOARD_FAB2_LIB.BASEBOARD_FAB2(SCH_1):PAGE41_I285@CHPSET_LIB.SKX_EXT_B(CHIPS)':
 'VSS'<275>: CDS_PINID='VSS(275)';
NODE_NAME     U5D1 DB73
 '@BASEBOARD_FAB2_LIB.BASEBOARD_FAB2(SCH_1):PAGE41_I285@CHPSET_LIB.SKX_EXT_B(CHIPS)':
 'VSS'<276>: CDS_PINID='VSS(276)';
NODE_NAME     U5D1 DB49
 '@BASEBOARD_FAB2_LIB.BASEBOARD_FAB2(SCH_1):PAGE41_I285@CHPSET_LIB.SKX_EXT_B(CHIPS)':
 'VSS'<277>: CDS_PINID='VSS(277)';
NODE_NAME     U5D1 DB47
 '@BASEBOARD_FAB2_LIB.BASEBOARD_FAB2(SCH_1):PAGE41_I285@CHPSET_LIB.SKX_EXT_B(CHIPS)':
 'VSS'<278>: CDS_PINID='VSS(278)';
NODE_NAME     U5D1 DB41
 '@BASEBOARD_FAB2_LIB.BASEBOARD_FAB2(SCH_1):PAGE41_I285@CHPSET_LIB.SKX_EXT_B(CHIPS)':
 'VSS'<279>: CDS_PINID='VSS(279)';
NODE_NAME     U5D1 DB39
 '@BASEBOARD_FAB2_LIB.BASEBOARD_FAB2(SCH_1):PAGE41_I285@CHPSET_LIB.SKX_EXT_B(CHIPS)':
 'VSS'<280>: CDS_PINID='VSS(280)';
NODE_NAME     U5D1 DB25
 '@BASEBOARD_FAB2_LIB.BASEBOARD_FAB2(SCH_1):PAGE41_I285@CHPSET_LIB.SKX_EXT_B(CHIPS)':
 'VSS'<281>: CDS_PINID='VSS(281)';
NODE_NAME     U5D1 DB23
 '@BASEBOARD_FAB2_LIB.BASEBOARD_FAB2(SCH_1):PAGE41_I285@CHPSET_LIB.SKX_EXT_B(CHIPS)':
 'VSS'<282>: CDS_PINID='VSS(282)';
NODE_NAME     U5D1 DB17
 '@BASEBOARD_FAB2_LIB.BASEBOARD_FAB2(SCH_1):PAGE41_I285@CHPSET_LIB.SKX_EXT_B(CHIPS)':
 'VSS'<283>: CDS_PINID='VSS(283)';
NODE_NAME     U5D1 DB13
 '@BASEBOARD_FAB2_LIB.BASEBOARD_FAB2(SCH_1):PAGE41_I285@CHPSET_LIB.SKX_EXT_B(CHIPS)':
 'VSS'<284>: CDS_PINID='VSS(284)';
NODE_NAME     U5D1 DB3
 '@BASEBOARD_FAB2_LIB.BASEBOARD_FAB2(SCH_1):PAGE41_I285@CHPSET_LIB.SKX_EXT_B(CHIPS)':
 'VSS'<285>: CDS_PINID='VSS(285)';
NODE_NAME     U5D1 DA80
 '@BASEBOARD_FAB2_LIB.BASEBOARD_FAB2(SCH_1):PAGE41_I285@CHPSET_LIB.SKX_EXT_B(CHIPS)':
 'VSS'<286>: CDS_PINID='VSS(286)';
NODE_NAME     U5D1 DA78
 '@BASEBOARD_FAB2_LIB.BASEBOARD_FAB2(SCH_1):PAGE41_I285@CHPSET_LIB.SKX_EXT_B(CHIPS)':
 'VSS'<287>: CDS_PINID='VSS(287)';
NODE_NAME     U5D1 DA76
 '@BASEBOARD_FAB2_LIB.BASEBOARD_FAB2(SCH_1):PAGE41_I285@CHPSET_LIB.SKX_EXT_B(CHIPS)':
 'VSS'<288>: CDS_PINID='VSS(288)';
NODE_NAME     U5D1 DA74
 '@BASEBOARD_FAB2_LIB.BASEBOARD_FAB2(SCH_1):PAGE41_I285@CHPSET_LIB.SKX_EXT_B(CHIPS)':
 'VSS'<289>: CDS_PINID='VSS(289)';
NODE_NAME     U5D1 DA70
 '@BASEBOARD_FAB2_LIB.BASEBOARD_FAB2(SCH_1):PAGE41_I285@CHPSET_LIB.SKX_EXT_B(CHIPS)':
 'VSS'<290>: CDS_PINID='VSS(290)';
NODE_NAME     U5D1 DA64
 '@BASEBOARD_FAB2_LIB.BASEBOARD_FAB2(SCH_1):PAGE41_I285@CHPSET_LIB.SKX_EXT_B(CHIPS)':
 'VSS'<291>: CDS_PINID='VSS(291)';
NODE_NAME     U5D1 DA50
 '@BASEBOARD_FAB2_LIB.BASEBOARD_FAB2(SCH_1):PAGE41_I285@CHPSET_LIB.SKX_EXT_B(CHIPS)':
 'VSS'<292>: CDS_PINID='VSS(292)';
NODE_NAME     U5D1 DA48
 '@BASEBOARD_FAB2_LIB.BASEBOARD_FAB2(SCH_1):PAGE41_I285@CHPSET_LIB.SKX_EXT_B(CHIPS)':
 'VSS'<293>: CDS_PINID='VSS(293)';
NODE_NAME     U5D1 EF79
 '@BASEBOARD_FAB2_LIB.BASEBOARD_FAB2(SCH_1):PAGE41_I286@CHPSET_LIB.SKX_EXT_B(CHIPS)':
 'VSS'<0>: CDS_PINID='VSS(0)';
NODE_NAME     U5D1 EF75
 '@BASEBOARD_FAB2_LIB.BASEBOARD_FAB2(SCH_1):PAGE41_I286@CHPSET_LIB.SKX_EXT_B(CHIPS)':
 'VSS'<1>: CDS_PINID='VSS(1)';
NODE_NAME     U5D1 EF71
 '@BASEBOARD_FAB2_LIB.BASEBOARD_FAB2(SCH_1):PAGE41_I286@CHPSET_LIB.SKX_EXT_B(CHIPS)':
 'VSS'<2>: CDS_PINID='VSS(2)';
NODE_NAME     U5D1 EE78
 '@BASEBOARD_FAB2_LIB.BASEBOARD_FAB2(SCH_1):PAGE41_I286@CHPSET_LIB.SKX_EXT_B(CHIPS)':
 'VSS'<3>: CDS_PINID='VSS(3)';
NODE_NAME     U5D1 EE76
 '@BASEBOARD_FAB2_LIB.BASEBOARD_FAB2(SCH_1):PAGE41_I286@CHPSET_LIB.SKX_EXT_B(CHIPS)':
 'VSS'<4>: CDS_PINID='VSS(4)';
NODE_NAME     U5D1 EE70
 '@BASEBOARD_FAB2_LIB.BASEBOARD_FAB2(SCH_1):PAGE41_I286@CHPSET_LIB.SKX_EXT_B(CHIPS)':
 'VSS'<5>: CDS_PINID='VSS(5)';
NODE_NAME     U5D1 EE36
 '@BASEBOARD_FAB2_LIB.BASEBOARD_FAB2(SCH_1):PAGE41_I286@CHPSET_LIB.SKX_EXT_B(CHIPS)':
 'VSS'<6>: CDS_PINID='VSS(6)';
NODE_NAME     U5D1 EE34
 '@BASEBOARD_FAB2_LIB.BASEBOARD_FAB2(SCH_1):PAGE41_I286@CHPSET_LIB.SKX_EXT_B(CHIPS)':
 'VSS'<7>: CDS_PINID='VSS(7)';
NODE_NAME     U5D1 EE30
 '@BASEBOARD_FAB2_LIB.BASEBOARD_FAB2(SCH_1):PAGE41_I286@CHPSET_LIB.SKX_EXT_B(CHIPS)':
 'VSS'<8>: CDS_PINID='VSS(8)';
NODE_NAME     U5D1 EE28
 '@BASEBOARD_FAB2_LIB.BASEBOARD_FAB2(SCH_1):PAGE41_I286@CHPSET_LIB.SKX_EXT_B(CHIPS)':
 'VSS'<9>: CDS_PINID='VSS(9)';
NODE_NAME     U5D1 EE24
 '@BASEBOARD_FAB2_LIB.BASEBOARD_FAB2(SCH_1):PAGE41_I286@CHPSET_LIB.SKX_EXT_B(CHIPS)':
 'VSS'<10>: CDS_PINID='VSS(10)';
NODE_NAME     U5D1 ED77
 '@BASEBOARD_FAB2_LIB.BASEBOARD_FAB2(SCH_1):PAGE41_I286@CHPSET_LIB.SKX_EXT_B(CHIPS)':
 'VSS'<11>: CDS_PINID='VSS(11)';
NODE_NAME     U5D1 ED35
 '@BASEBOARD_FAB2_LIB.BASEBOARD_FAB2(SCH_1):PAGE41_I286@CHPSET_LIB.SKX_EXT_B(CHIPS)':
 'VSS'<12>: CDS_PINID='VSS(12)';
NODE_NAME     U5D1 ED29
 '@BASEBOARD_FAB2_LIB.BASEBOARD_FAB2(SCH_1):PAGE41_I286@CHPSET_LIB.SKX_EXT_B(CHIPS)':
 'VSS'<13>: CDS_PINID='VSS(13)';
NODE_NAME     U5D1 ED23
 '@BASEBOARD_FAB2_LIB.BASEBOARD_FAB2(SCH_1):PAGE41_I286@CHPSET_LIB.SKX_EXT_B(CHIPS)':
 'VSS'<14>: CDS_PINID='VSS(14)';
NODE_NAME     U5D1 ED15
 '@BASEBOARD_FAB2_LIB.BASEBOARD_FAB2(SCH_1):PAGE41_I286@CHPSET_LIB.SKX_EXT_B(CHIPS)':
 'VSS'<15>: CDS_PINID='VSS(15)';
NODE_NAME     U5D1 ED11
 '@BASEBOARD_FAB2_LIB.BASEBOARD_FAB2(SCH_1):PAGE41_I286@CHPSET_LIB.SKX_EXT_B(CHIPS)':
 'VSS'<16>: CDS_PINID='VSS(16)';
NODE_NAME     U5D1 EC76
 '@BASEBOARD_FAB2_LIB.BASEBOARD_FAB2(SCH_1):PAGE41_I286@CHPSET_LIB.SKX_EXT_B(CHIPS)':
 'VSS'<17>: CDS_PINID='VSS(17)';
NODE_NAME     U5D1 EC74
 '@BASEBOARD_FAB2_LIB.BASEBOARD_FAB2(SCH_1):PAGE41_I286@CHPSET_LIB.SKX_EXT_B(CHIPS)':
 'VSS'<18>: CDS_PINID='VSS(18)';
NODE_NAME     U5D1 EC72
 '@BASEBOARD_FAB2_LIB.BASEBOARD_FAB2(SCH_1):PAGE41_I286@CHPSET_LIB.SKX_EXT_B(CHIPS)':
 'VSS'<19>: CDS_PINID='VSS(19)';
NODE_NAME     U5D1 EC70
 '@BASEBOARD_FAB2_LIB.BASEBOARD_FAB2(SCH_1):PAGE41_I286@CHPSET_LIB.SKX_EXT_B(CHIPS)':
 'VSS'<20>: CDS_PINID='VSS(20)';
NODE_NAME     U5D1 EC10
 '@BASEBOARD_FAB2_LIB.BASEBOARD_FAB2(SCH_1):PAGE41_I286@CHPSET_LIB.SKX_EXT_B(CHIPS)':
 'VSS'<21>: CDS_PINID='VSS(21)';
NODE_NAME     U5D1 EB69
 '@BASEBOARD_FAB2_LIB.BASEBOARD_FAB2(SCH_1):PAGE41_I286@CHPSET_LIB.SKX_EXT_B(CHIPS)':
 'VSS'<22>: CDS_PINID='VSS(22)';
NODE_NAME     U5D1 EB65
 '@BASEBOARD_FAB2_LIB.BASEBOARD_FAB2(SCH_1):PAGE41_I286@CHPSET_LIB.SKX_EXT_B(CHIPS)':
 'VSS'<23>: CDS_PINID='VSS(23)';
NODE_NAME     U5D1 EB41
 '@BASEBOARD_FAB2_LIB.BASEBOARD_FAB2(SCH_1):PAGE41_I286@CHPSET_LIB.SKX_EXT_B(CHIPS)':
 'VSS'<24>: CDS_PINID='VSS(24)';
NODE_NAME     U5D1 EB39
 '@BASEBOARD_FAB2_LIB.BASEBOARD_FAB2(SCH_1):PAGE41_I286@CHPSET_LIB.SKX_EXT_B(CHIPS)':
 'VSS'<25>: CDS_PINID='VSS(25)';
NODE_NAME     U5D1 EB37
 '@BASEBOARD_FAB2_LIB.BASEBOARD_FAB2(SCH_1):PAGE41_I286@CHPSET_LIB.SKX_EXT_B(CHIPS)':
 'VSS'<26>: CDS_PINID='VSS(26)';
NODE_NAME     U5D1 EB35
 '@BASEBOARD_FAB2_LIB.BASEBOARD_FAB2(SCH_1):PAGE41_I286@CHPSET_LIB.SKX_EXT_B(CHIPS)':
 'VSS'<27>: CDS_PINID='VSS(27)';
NODE_NAME     U5D1 EB33
 '@BASEBOARD_FAB2_LIB.BASEBOARD_FAB2(SCH_1):PAGE41_I286@CHPSET_LIB.SKX_EXT_B(CHIPS)':
 'VSS'<28>: CDS_PINID='VSS(28)';
NODE_NAME     U5D1 EB31
 '@BASEBOARD_FAB2_LIB.BASEBOARD_FAB2(SCH_1):PAGE41_I286@CHPSET_LIB.SKX_EXT_B(CHIPS)':
 'VSS'<29>: CDS_PINID='VSS(29)';
NODE_NAME     U5D1 EB29
 '@BASEBOARD_FAB2_LIB.BASEBOARD_FAB2(SCH_1):PAGE41_I286@CHPSET_LIB.SKX_EXT_B(CHIPS)':
 'VSS'<30>: CDS_PINID='VSS(30)';
NODE_NAME     U5D1 EB27
 '@BASEBOARD_FAB2_LIB.BASEBOARD_FAB2(SCH_1):PAGE41_I286@CHPSET_LIB.SKX_EXT_B(CHIPS)':
 'VSS'<31>: CDS_PINID='VSS(31)';
NODE_NAME     U5D1 EB25
 '@BASEBOARD_FAB2_LIB.BASEBOARD_FAB2(SCH_1):PAGE41_I286@CHPSET_LIB.SKX_EXT_B(CHIPS)':
 'VSS'<32>: CDS_PINID='VSS(32)';
NODE_NAME     U5D1 EB23
 '@BASEBOARD_FAB2_LIB.BASEBOARD_FAB2(SCH_1):PAGE41_I286@CHPSET_LIB.SKX_EXT_B(CHIPS)':
 'VSS'<33>: CDS_PINID='VSS(33)';
NODE_NAME     U5D1 BR18
 '@BASEBOARD_FAB2_LIB.BASEBOARD_FAB2(SCH_1):PAGE41_I286@CHPSET_LIB.SKX_EXT_B(CHIPS)':
 'VSS'<34>: CDS_PINID='VSS(34)';
NODE_NAME     U5D1 EB13
 '@BASEBOARD_FAB2_LIB.BASEBOARD_FAB2(SCH_1):PAGE41_I286@CHPSET_LIB.SKX_EXT_B(CHIPS)':
 'VSS'<35>: CDS_PINID='VSS(35)';
NODE_NAME     U5D1 EA82
 '@BASEBOARD_FAB2_LIB.BASEBOARD_FAB2(SCH_1):PAGE41_I286@CHPSET_LIB.SKX_EXT_B(CHIPS)':
 'VSS'<36>: CDS_PINID='VSS(36)';
NODE_NAME     U5D1 EA80
 '@BASEBOARD_FAB2_LIB.BASEBOARD_FAB2(SCH_1):PAGE41_I286@CHPSET_LIB.SKX_EXT_B(CHIPS)':
 'VSS'<37>: CDS_PINID='VSS(37)';
NODE_NAME     U5D1 EA78
 '@BASEBOARD_FAB2_LIB.BASEBOARD_FAB2(SCH_1):PAGE41_I286@CHPSET_LIB.SKX_EXT_B(CHIPS)':
 'VSS'<38>: CDS_PINID='VSS(38)';
NODE_NAME     U5D1 EA76
 '@BASEBOARD_FAB2_LIB.BASEBOARD_FAB2(SCH_1):PAGE41_I286@CHPSET_LIB.SKX_EXT_B(CHIPS)':
 'VSS'<39>: CDS_PINID='VSS(39)';
NODE_NAME     U5D1 EA70
 '@BASEBOARD_FAB2_LIB.BASEBOARD_FAB2(SCH_1):PAGE41_I286@CHPSET_LIB.SKX_EXT_B(CHIPS)':
 'VSS'<40>: CDS_PINID='VSS(40)';
NODE_NAME     U5D1 EA64
 '@BASEBOARD_FAB2_LIB.BASEBOARD_FAB2(SCH_1):PAGE41_I286@CHPSET_LIB.SKX_EXT_B(CHIPS)':
 'VSS'<41>: CDS_PINID='VSS(41)';
NODE_NAME     U5D1 EA42
 '@BASEBOARD_FAB2_LIB.BASEBOARD_FAB2(SCH_1):PAGE41_I286@CHPSET_LIB.SKX_EXT_B(CHIPS)':
 'VSS'<42>: CDS_PINID='VSS(42)';
NODE_NAME     U5D1 EA22
 '@BASEBOARD_FAB2_LIB.BASEBOARD_FAB2(SCH_1):PAGE41_I286@CHPSET_LIB.SKX_EXT_B(CHIPS)':
 'VSS'<43>: CDS_PINID='VSS(43)';
NODE_NAME     U5D1 EA20
 '@BASEBOARD_FAB2_LIB.BASEBOARD_FAB2(SCH_1):PAGE41_I286@CHPSET_LIB.SKX_EXT_B(CHIPS)':
 'VSS'<44>: CDS_PINID='VSS(44)';
NODE_NAME     U5D1 EA16
 '@BASEBOARD_FAB2_LIB.BASEBOARD_FAB2(SCH_1):PAGE41_I286@CHPSET_LIB.SKX_EXT_B(CHIPS)':
 'VSS'<45>: CDS_PINID='VSS(45)';
NODE_NAME     U5D1 J16
 '@BASEBOARD_FAB2_LIB.BASEBOARD_FAB2(SCH_1):PAGE41_I286@CHPSET_LIB.SKX_EXT_B(CHIPS)':
 'VSS'<46>: CDS_PINID='VSS(46)';
NODE_NAME     U5D1 EA6
 '@BASEBOARD_FAB2_LIB.BASEBOARD_FAB2(SCH_1):PAGE41_I286@CHPSET_LIB.SKX_EXT_B(CHIPS)':
 'VSS'<47>: CDS_PINID='VSS(47)';
NODE_NAME     U5D1 DY75
 '@BASEBOARD_FAB2_LIB.BASEBOARD_FAB2(SCH_1):PAGE41_I286@CHPSET_LIB.SKX_EXT_B(CHIPS)':
 'VSS'<48>: CDS_PINID='VSS(48)';
NODE_NAME     U5D1 DY71
 '@BASEBOARD_FAB2_LIB.BASEBOARD_FAB2(SCH_1):PAGE41_I286@CHPSET_LIB.SKX_EXT_B(CHIPS)':
 'VSS'<49>: CDS_PINID='VSS(49)';
NODE_NAME     U5D1 DY41
 '@BASEBOARD_FAB2_LIB.BASEBOARD_FAB2(SCH_1):PAGE41_I286@CHPSET_LIB.SKX_EXT_B(CHIPS)':
 'VSS'<50>: CDS_PINID='VSS(50)';
NODE_NAME     U5D1 DY35
 '@BASEBOARD_FAB2_LIB.BASEBOARD_FAB2(SCH_1):PAGE41_I286@CHPSET_LIB.SKX_EXT_B(CHIPS)':
 'VSS'<51>: CDS_PINID='VSS(51)';
NODE_NAME     U5D1 DY29
 '@BASEBOARD_FAB2_LIB.BASEBOARD_FAB2(SCH_1):PAGE41_I286@CHPSET_LIB.SKX_EXT_B(CHIPS)':
 'VSS'<52>: CDS_PINID='VSS(52)';
NODE_NAME     U5D1 DY23
 '@BASEBOARD_FAB2_LIB.BASEBOARD_FAB2(SCH_1):PAGE41_I286@CHPSET_LIB.SKX_EXT_B(CHIPS)':
 'VSS'<53>: CDS_PINID='VSS(53)';
NODE_NAME     U5D1 DY19
 '@BASEBOARD_FAB2_LIB.BASEBOARD_FAB2(SCH_1):PAGE41_I286@CHPSET_LIB.SKX_EXT_B(CHIPS)':
 'VSS'<54>: CDS_PINID='VSS(54)';
NODE_NAME     U5D1 DY5
 '@BASEBOARD_FAB2_LIB.BASEBOARD_FAB2(SCH_1):PAGE41_I286@CHPSET_LIB.SKX_EXT_B(CHIPS)':
 'VSS'<55>: CDS_PINID='VSS(55)';
NODE_NAME     U5D1 DW84
 '@BASEBOARD_FAB2_LIB.BASEBOARD_FAB2(SCH_1):PAGE41_I286@CHPSET_LIB.SKX_EXT_B(CHIPS)':
 'VSS'<56>: CDS_PINID='VSS(56)';
NODE_NAME     U5D1 DW82
 '@BASEBOARD_FAB2_LIB.BASEBOARD_FAB2(SCH_1):PAGE41_I286@CHPSET_LIB.SKX_EXT_B(CHIPS)':
 'VSS'<57>: CDS_PINID='VSS(57)';
NODE_NAME     U5D1 DW8
 '@BASEBOARD_FAB2_LIB.BASEBOARD_FAB2(SCH_1):PAGE41_I286@CHPSET_LIB.SKX_EXT_B(CHIPS)':
 'VSS'<58>: CDS_PINID='VSS(58)';
NODE_NAME     U5D1 DW76
 '@BASEBOARD_FAB2_LIB.BASEBOARD_FAB2(SCH_1):PAGE41_I286@CHPSET_LIB.SKX_EXT_B(CHIPS)':
 'VSS'<59>: CDS_PINID='VSS(59)';
NODE_NAME     U5D1 DW74
 '@BASEBOARD_FAB2_LIB.BASEBOARD_FAB2(SCH_1):PAGE41_I286@CHPSET_LIB.SKX_EXT_B(CHIPS)':
 'VSS'<60>: CDS_PINID='VSS(60)';
NODE_NAME     U5D1 DW72
 '@BASEBOARD_FAB2_LIB.BASEBOARD_FAB2(SCH_1):PAGE41_I286@CHPSET_LIB.SKX_EXT_B(CHIPS)':
 'VSS'<61>: CDS_PINID='VSS(61)';
NODE_NAME     U5D1 DW70
 '@BASEBOARD_FAB2_LIB.BASEBOARD_FAB2(SCH_1):PAGE41_I286@CHPSET_LIB.SKX_EXT_B(CHIPS)':
 'VSS'<62>: CDS_PINID='VSS(62)';
NODE_NAME     U5D1 DW68
 '@BASEBOARD_FAB2_LIB.BASEBOARD_FAB2(SCH_1):PAGE41_I286@CHPSET_LIB.SKX_EXT_B(CHIPS)':
 'VSS'<63>: CDS_PINID='VSS(63)';
NODE_NAME     U5D1 DW66
 '@BASEBOARD_FAB2_LIB.BASEBOARD_FAB2(SCH_1):PAGE41_I286@CHPSET_LIB.SKX_EXT_B(CHIPS)':
 'VSS'<64>: CDS_PINID='VSS(64)';
NODE_NAME     U5D1 DW64
 '@BASEBOARD_FAB2_LIB.BASEBOARD_FAB2(SCH_1):PAGE41_I286@CHPSET_LIB.SKX_EXT_B(CHIPS)':
 'VSS'<65>: CDS_PINID='VSS(65)';
NODE_NAME     U5D1 DW40
 '@BASEBOARD_FAB2_LIB.BASEBOARD_FAB2(SCH_1):PAGE41_I286@CHPSET_LIB.SKX_EXT_B(CHIPS)':
 'VSS'<66>: CDS_PINID='VSS(66)';
NODE_NAME     U5D1 DW36
 '@BASEBOARD_FAB2_LIB.BASEBOARD_FAB2(SCH_1):PAGE41_I286@CHPSET_LIB.SKX_EXT_B(CHIPS)':
 'VSS'<67>: CDS_PINID='VSS(67)';
NODE_NAME     U5D1 DW34
 '@BASEBOARD_FAB2_LIB.BASEBOARD_FAB2(SCH_1):PAGE41_I286@CHPSET_LIB.SKX_EXT_B(CHIPS)':
 'VSS'<68>: CDS_PINID='VSS(68)';
NODE_NAME     U5D1 DW30
 '@BASEBOARD_FAB2_LIB.BASEBOARD_FAB2(SCH_1):PAGE41_I286@CHPSET_LIB.SKX_EXT_B(CHIPS)':
 'VSS'<69>: CDS_PINID='VSS(69)';
NODE_NAME     U5D1 DW28
 '@BASEBOARD_FAB2_LIB.BASEBOARD_FAB2(SCH_1):PAGE41_I286@CHPSET_LIB.SKX_EXT_B(CHIPS)':
 'VSS'<70>: CDS_PINID='VSS(70)';
NODE_NAME     U5D1 DW24
 '@BASEBOARD_FAB2_LIB.BASEBOARD_FAB2(SCH_1):PAGE41_I286@CHPSET_LIB.SKX_EXT_B(CHIPS)':
 'VSS'<71>: CDS_PINID='VSS(71)';
NODE_NAME     U5D1 DW20
 '@BASEBOARD_FAB2_LIB.BASEBOARD_FAB2(SCH_1):PAGE41_I286@CHPSET_LIB.SKX_EXT_B(CHIPS)':
 'VSS'<72>: CDS_PINID='VSS(72)';
NODE_NAME     U5D1 DW12
 '@BASEBOARD_FAB2_LIB.BASEBOARD_FAB2(SCH_1):PAGE41_I286@CHPSET_LIB.SKX_EXT_B(CHIPS)':
 'VSS'<73>: CDS_PINID='VSS(73)';
NODE_NAME     U5D1 DV81
 '@BASEBOARD_FAB2_LIB.BASEBOARD_FAB2(SCH_1):PAGE41_I286@CHPSET_LIB.SKX_EXT_B(CHIPS)':
 'VSS'<74>: CDS_PINID='VSS(74)';
NODE_NAME     U5D1 DV77
 '@BASEBOARD_FAB2_LIB.BASEBOARD_FAB2(SCH_1):PAGE41_I286@CHPSET_LIB.SKX_EXT_B(CHIPS)':
 'VSS'<75>: CDS_PINID='VSS(75)';
NODE_NAME     U5D1 DV73
 '@BASEBOARD_FAB2_LIB.BASEBOARD_FAB2(SCH_1):PAGE41_I286@CHPSET_LIB.SKX_EXT_B(CHIPS)':
 'VSS'<76>: CDS_PINID='VSS(76)';
NODE_NAME     U5D1 DV39
 '@BASEBOARD_FAB2_LIB.BASEBOARD_FAB2(SCH_1):PAGE41_I286@CHPSET_LIB.SKX_EXT_B(CHIPS)':
 'VSS'<77>: CDS_PINID='VSS(77)';
NODE_NAME     U5D1 DV37
 '@BASEBOARD_FAB2_LIB.BASEBOARD_FAB2(SCH_1):PAGE41_I286@CHPSET_LIB.SKX_EXT_B(CHIPS)':
 'VSS'<78>: CDS_PINID='VSS(78)';
NODE_NAME     U5D1 DV33
 '@BASEBOARD_FAB2_LIB.BASEBOARD_FAB2(SCH_1):PAGE41_I286@CHPSET_LIB.SKX_EXT_B(CHIPS)':
 'VSS'<79>: CDS_PINID='VSS(79)';
NODE_NAME     U5D1 DV31
 '@BASEBOARD_FAB2_LIB.BASEBOARD_FAB2(SCH_1):PAGE41_I286@CHPSET_LIB.SKX_EXT_B(CHIPS)':
 'VSS'<80>: CDS_PINID='VSS(80)';
NODE_NAME     U5D1 DV27
 '@BASEBOARD_FAB2_LIB.BASEBOARD_FAB2(SCH_1):PAGE41_I286@CHPSET_LIB.SKX_EXT_B(CHIPS)':
 'VSS'<81>: CDS_PINID='VSS(81)';
NODE_NAME     U5D1 DV25
 '@BASEBOARD_FAB2_LIB.BASEBOARD_FAB2(SCH_1):PAGE41_I286@CHPSET_LIB.SKX_EXT_B(CHIPS)':
 'VSS'<82>: CDS_PINID='VSS(82)';
NODE_NAME     U5D1 DV21
 '@BASEBOARD_FAB2_LIB.BASEBOARD_FAB2(SCH_1):PAGE41_I286@CHPSET_LIB.SKX_EXT_B(CHIPS)':
 'VSS'<83>: CDS_PINID='VSS(83)';
NODE_NAME     U5D1 DU84
 '@BASEBOARD_FAB2_LIB.BASEBOARD_FAB2(SCH_1):PAGE41_I286@CHPSET_LIB.SKX_EXT_B(CHIPS)':
 'VSS'<84>: CDS_PINID='VSS(84)';
NODE_NAME     U5D1 DU82
 '@BASEBOARD_FAB2_LIB.BASEBOARD_FAB2(SCH_1):PAGE41_I286@CHPSET_LIB.SKX_EXT_B(CHIPS)':
 'VSS'<85>: CDS_PINID='VSS(85)';
NODE_NAME     U5D1 DU80
 '@BASEBOARD_FAB2_LIB.BASEBOARD_FAB2(SCH_1):PAGE41_I286@CHPSET_LIB.SKX_EXT_B(CHIPS)':
 'VSS'<86>: CDS_PINID='VSS(86)';
NODE_NAME     U5D1 DU78
 '@BASEBOARD_FAB2_LIB.BASEBOARD_FAB2(SCH_1):PAGE41_I286@CHPSET_LIB.SKX_EXT_B(CHIPS)':
 'VSS'<87>: CDS_PINID='VSS(87)';
NODE_NAME     U5D1 DU72
 '@BASEBOARD_FAB2_LIB.BASEBOARD_FAB2(SCH_1):PAGE41_I286@CHPSET_LIB.SKX_EXT_B(CHIPS)':
 'VSS'<88>: CDS_PINID='VSS(88)';
NODE_NAME     U5D1 DU70
 '@BASEBOARD_FAB2_LIB.BASEBOARD_FAB2(SCH_1):PAGE41_I286@CHPSET_LIB.SKX_EXT_B(CHIPS)':
 'VSS'<89>: CDS_PINID='VSS(89)';
NODE_NAME     U5D1 DU38
 '@BASEBOARD_FAB2_LIB.BASEBOARD_FAB2(SCH_1):PAGE41_I286@CHPSET_LIB.SKX_EXT_B(CHIPS)':
 'VSS'<90>: CDS_PINID='VSS(90)';
NODE_NAME     U5D1 DU32
 '@BASEBOARD_FAB2_LIB.BASEBOARD_FAB2(SCH_1):PAGE41_I286@CHPSET_LIB.SKX_EXT_B(CHIPS)':
 'VSS'<91>: CDS_PINID='VSS(91)';
NODE_NAME     U5D1 DU26
 '@BASEBOARD_FAB2_LIB.BASEBOARD_FAB2(SCH_1):PAGE41_I286@CHPSET_LIB.SKX_EXT_B(CHIPS)':
 'VSS'<92>: CDS_PINID='VSS(92)';
NODE_NAME     U5D1 DU22
 '@BASEBOARD_FAB2_LIB.BASEBOARD_FAB2(SCH_1):PAGE41_I286@CHPSET_LIB.SKX_EXT_B(CHIPS)':
 'VSS'<93>: CDS_PINID='VSS(93)';
NODE_NAME     U5D1 CN14
 '@BASEBOARD_FAB2_LIB.BASEBOARD_FAB2(SCH_1):PAGE41_I286@CHPSET_LIB.SKX_EXT_B(CHIPS)':
 'VSS'<94>: CDS_PINID='VSS(94)';
NODE_NAME     U5D1 DU14
 '@BASEBOARD_FAB2_LIB.BASEBOARD_FAB2(SCH_1):PAGE41_I286@CHPSET_LIB.SKX_EXT_B(CHIPS)':
 'VSS'<95>: CDS_PINID='VSS(95)';
NODE_NAME     U5D1 DU10
 '@BASEBOARD_FAB2_LIB.BASEBOARD_FAB2(SCH_1):PAGE41_I286@CHPSET_LIB.SKX_EXT_B(CHIPS)':
 'VSS'<96>: CDS_PINID='VSS(96)';
NODE_NAME     U5D1 DT85
 '@BASEBOARD_FAB2_LIB.BASEBOARD_FAB2(SCH_1):PAGE41_I286@CHPSET_LIB.SKX_EXT_B(CHIPS)':
 'VSS'<97>: CDS_PINID='VSS(97)';
NODE_NAME     U5D1 DT83
 '@BASEBOARD_FAB2_LIB.BASEBOARD_FAB2(SCH_1):PAGE41_I286@CHPSET_LIB.SKX_EXT_B(CHIPS)':
 'VSS'<98>: CDS_PINID='VSS(98)';
NODE_NAME     U5D1 DT79
 '@BASEBOARD_FAB2_LIB.BASEBOARD_FAB2(SCH_1):PAGE41_I286@CHPSET_LIB.SKX_EXT_B(CHIPS)':
 'VSS'<99>: CDS_PINID='VSS(99)';
NODE_NAME     U5D1 DT69
 '@BASEBOARD_FAB2_LIB.BASEBOARD_FAB2(SCH_1):PAGE41_I286@CHPSET_LIB.SKX_EXT_B(CHIPS)':
 'VSS'<100>: CDS_PINID='VSS(100)';
NODE_NAME     U5D1 DT65
 '@BASEBOARD_FAB2_LIB.BASEBOARD_FAB2(SCH_1):PAGE41_I286@CHPSET_LIB.SKX_EXT_B(CHIPS)':
 'VSS'<101>: CDS_PINID='VSS(101)';
NODE_NAME     U5D1 DH21
 '@BASEBOARD_FAB2_LIB.BASEBOARD_FAB2(SCH_1):PAGE41_I286@CHPSET_LIB.SKX_EXT_B(CHIPS)':
 'VSS'<102>: CDS_PINID='VSS(102)';
NODE_NAME     U5D1 DT17
 '@BASEBOARD_FAB2_LIB.BASEBOARD_FAB2(SCH_1):PAGE41_I286@CHPSET_LIB.SKX_EXT_B(CHIPS)':
 'VSS'<103>: CDS_PINID='VSS(103)';
NODE_NAME     U5D1 DT3
 '@BASEBOARD_FAB2_LIB.BASEBOARD_FAB2(SCH_1):PAGE41_I286@CHPSET_LIB.SKX_EXT_B(CHIPS)':
 'VSS'<104>: CDS_PINID='VSS(104)';
NODE_NAME     U5D1 DR78
 '@BASEBOARD_FAB2_LIB.BASEBOARD_FAB2(SCH_1):PAGE41_I286@CHPSET_LIB.SKX_EXT_B(CHIPS)':
 'VSS'<105>: CDS_PINID='VSS(105)';
NODE_NAME     U5D1 DR76
 '@BASEBOARD_FAB2_LIB.BASEBOARD_FAB2(SCH_1):PAGE41_I286@CHPSET_LIB.SKX_EXT_B(CHIPS)':
 'VSS'<106>: CDS_PINID='VSS(106)';
NODE_NAME     U5D1 DR74
 '@BASEBOARD_FAB2_LIB.BASEBOARD_FAB2(SCH_1):PAGE41_I286@CHPSET_LIB.SKX_EXT_B(CHIPS)':
 'VSS'<107>: CDS_PINID='VSS(107)';
NODE_NAME     U5D1 DR72
 '@BASEBOARD_FAB2_LIB.BASEBOARD_FAB2(SCH_1):PAGE41_I286@CHPSET_LIB.SKX_EXT_B(CHIPS)':
 'VSS'<108>: CDS_PINID='VSS(108)';
NODE_NAME     U5D1 DR70
 '@BASEBOARD_FAB2_LIB.BASEBOARD_FAB2(SCH_1):PAGE41_I286@CHPSET_LIB.SKX_EXT_B(CHIPS)':
 'VSS'<109>: CDS_PINID='VSS(109)';
NODE_NAME     U5D1 DR68
 '@BASEBOARD_FAB2_LIB.BASEBOARD_FAB2(SCH_1):PAGE41_I286@CHPSET_LIB.SKX_EXT_B(CHIPS)':
 'VSS'<110>: CDS_PINID='VSS(110)';
NODE_NAME     U5D1 DR66
 '@BASEBOARD_FAB2_LIB.BASEBOARD_FAB2(SCH_1):PAGE41_I286@CHPSET_LIB.SKX_EXT_B(CHIPS)':
 'VSS'<111>: CDS_PINID='VSS(111)';
NODE_NAME     U5D1 DR42
 '@BASEBOARD_FAB2_LIB.BASEBOARD_FAB2(SCH_1):PAGE41_I286@CHPSET_LIB.SKX_EXT_B(CHIPS)':
 'VSS'<112>: CDS_PINID='VSS(112)';
NODE_NAME     U5D1 DR40
 '@BASEBOARD_FAB2_LIB.BASEBOARD_FAB2(SCH_1):PAGE41_I286@CHPSET_LIB.SKX_EXT_B(CHIPS)':
 'VSS'<113>: CDS_PINID='VSS(113)';
NODE_NAME     U5D1 DR38
 '@BASEBOARD_FAB2_LIB.BASEBOARD_FAB2(SCH_1):PAGE41_I286@CHPSET_LIB.SKX_EXT_B(CHIPS)':
 'VSS'<114>: CDS_PINID='VSS(114)';
NODE_NAME     U5D1 DR36
 '@BASEBOARD_FAB2_LIB.BASEBOARD_FAB2(SCH_1):PAGE41_I286@CHPSET_LIB.SKX_EXT_B(CHIPS)':
 'VSS'<115>: CDS_PINID='VSS(115)';
NODE_NAME     U5D1 DR34
 '@BASEBOARD_FAB2_LIB.BASEBOARD_FAB2(SCH_1):PAGE41_I286@CHPSET_LIB.SKX_EXT_B(CHIPS)':
 'VSS'<116>: CDS_PINID='VSS(116)';
NODE_NAME     U5D1 DR32
 '@BASEBOARD_FAB2_LIB.BASEBOARD_FAB2(SCH_1):PAGE41_I286@CHPSET_LIB.SKX_EXT_B(CHIPS)':
 'VSS'<117>: CDS_PINID='VSS(117)';
NODE_NAME     U5D1 DR30
 '@BASEBOARD_FAB2_LIB.BASEBOARD_FAB2(SCH_1):PAGE41_I286@CHPSET_LIB.SKX_EXT_B(CHIPS)':
 'VSS'<118>: CDS_PINID='VSS(118)';
NODE_NAME     U5D1 DR28
 '@BASEBOARD_FAB2_LIB.BASEBOARD_FAB2(SCH_1):PAGE41_I286@CHPSET_LIB.SKX_EXT_B(CHIPS)':
 'VSS'<119>: CDS_PINID='VSS(119)';
NODE_NAME     U5D1 DR26
 '@BASEBOARD_FAB2_LIB.BASEBOARD_FAB2(SCH_1):PAGE41_I286@CHPSET_LIB.SKX_EXT_B(CHIPS)':
 'VSS'<120>: CDS_PINID='VSS(120)';
NODE_NAME     U5D1 DR24
 '@BASEBOARD_FAB2_LIB.BASEBOARD_FAB2(SCH_1):PAGE41_I286@CHPSET_LIB.SKX_EXT_B(CHIPS)':
 'VSS'<121>: CDS_PINID='VSS(121)';
NODE_NAME     U5D1 DR22
 '@BASEBOARD_FAB2_LIB.BASEBOARD_FAB2(SCH_1):PAGE41_I286@CHPSET_LIB.SKX_EXT_B(CHIPS)':
 'VSS'<122>: CDS_PINID='VSS(122)';
NODE_NAME     U5D1 DR20
 '@BASEBOARD_FAB2_LIB.BASEBOARD_FAB2(SCH_1):PAGE41_I286@CHPSET_LIB.SKX_EXT_B(CHIPS)':
 'VSS'<123>: CDS_PINID='VSS(123)';
NODE_NAME     U5D1 CL22
 '@BASEBOARD_FAB2_LIB.BASEBOARD_FAB2(SCH_1):PAGE41_I286@CHPSET_LIB.SKX_EXT_B(CHIPS)':
 'VSS'<124>: CDS_PINID='VSS(124)';
NODE_NAME     U5D1 CA20
 '@BASEBOARD_FAB2_LIB.BASEBOARD_FAB2(SCH_1):PAGE41_I286@CHPSET_LIB.SKX_EXT_B(CHIPS)':
 'VSS'<125>: CDS_PINID='VSS(125)';
NODE_NAME     U5D1 DR6
 '@BASEBOARD_FAB2_LIB.BASEBOARD_FAB2(SCH_1):PAGE41_I286@CHPSET_LIB.SKX_EXT_B(CHIPS)':
 'VSS'<126>: CDS_PINID='VSS(126)';
NODE_NAME     U5D1 BR26
 '@BASEBOARD_FAB2_LIB.BASEBOARD_FAB2(SCH_1):PAGE41_I286@CHPSET_LIB.SKX_EXT_B(CHIPS)':
 'VSS'<127>: CDS_PINID='VSS(127)';
NODE_NAME     U5D1 DP83
 '@BASEBOARD_FAB2_LIB.BASEBOARD_FAB2(SCH_1):PAGE41_I286@CHPSET_LIB.SKX_EXT_B(CHIPS)':
 'VSS'<128>: CDS_PINID='VSS(128)';
NODE_NAME     U5D1 DP81
 '@BASEBOARD_FAB2_LIB.BASEBOARD_FAB2(SCH_1):PAGE41_I286@CHPSET_LIB.SKX_EXT_B(CHIPS)':
 'VSS'<129>: CDS_PINID='VSS(129)';
NODE_NAME     U5D1 DP71
 '@BASEBOARD_FAB2_LIB.BASEBOARD_FAB2(SCH_1):PAGE41_I286@CHPSET_LIB.SKX_EXT_B(CHIPS)':
 'VSS'<130>: CDS_PINID='VSS(130)';
NODE_NAME     U5D1 DP69
 '@BASEBOARD_FAB2_LIB.BASEBOARD_FAB2(SCH_1):PAGE41_I286@CHPSET_LIB.SKX_EXT_B(CHIPS)':
 'VSS'<131>: CDS_PINID='VSS(131)';
NODE_NAME     U5D1 DP67
 '@BASEBOARD_FAB2_LIB.BASEBOARD_FAB2(SCH_1):PAGE41_I286@CHPSET_LIB.SKX_EXT_B(CHIPS)':
 'VSS'<132>: CDS_PINID='VSS(132)';
NODE_NAME     U5D1 DN78
 '@BASEBOARD_FAB2_LIB.BASEBOARD_FAB2(SCH_1):PAGE41_I286@CHPSET_LIB.SKX_EXT_B(CHIPS)':
 'VSS'<133>: CDS_PINID='VSS(133)';
NODE_NAME     C4P1 2
 '@BASEBOARD_FAB2_LIB.BASEBOARD_FAB2(SCH_1):PAGE42_I10@MSTR_DISCRETE.CAP(CHIPS)':
 'B': CDS_PINID='B';
NODE_NAME     C4P9 2
 '@BASEBOARD_FAB2_LIB.BASEBOARD_FAB2(SCH_1):PAGE42_I12@MSTR_DISCRETE.CAP(CHIPS)':
 'B': CDS_PINID='B';
NODE_NAME     C4P10 2
 '@BASEBOARD_FAB2_LIB.BASEBOARD_FAB2(SCH_1):PAGE42_I17@MSTR_DISCRETE.CAP(CHIPS)':
 'B': CDS_PINID='B';
NODE_NAME     C5P7 2
 '@BASEBOARD_FAB2_LIB.BASEBOARD_FAB2(SCH_1):PAGE42_I25@MSTR_DISCRETE.CAP(CHIPS)':
 'B': CDS_PINID='B';
NODE_NAME     C5P23 2
 '@BASEBOARD_FAB2_LIB.BASEBOARD_FAB2(SCH_1):PAGE42_I28@MSTR_DISCRETE.CAP(CHIPS)':
 'B': CDS_PINID='B';
NODE_NAME     C5P24 2
 '@BASEBOARD_FAB2_LIB.BASEBOARD_FAB2(SCH_1):PAGE42_I33@MSTR_DISCRETE.CAP(CHIPS)':
 'B': CDS_PINID='B';
NODE_NAME     C5P25 2
 '@BASEBOARD_FAB2_LIB.BASEBOARD_FAB2(SCH_1):PAGE42_I37@MSTR_DISCRETE.CAP(CHIPS)':
 'B': CDS_PINID='B';
NODE_NAME     C5P14 2
 '@BASEBOARD_FAB2_LIB.BASEBOARD_FAB2(SCH_1):PAGE42_I41@MSTR_DISCRETE.CAP(CHIPS)':
 'B': CDS_PINID='B';
NODE_NAME     C5P27 2
 '@BASEBOARD_FAB2_LIB.BASEBOARD_FAB2(SCH_1):PAGE42_I44@MSTR_DISCRETE.CAP(CHIPS)':
 'B': CDS_PINID='B';
NODE_NAME     C5P33 2
 '@BASEBOARD_FAB2_LIB.BASEBOARD_FAB2(SCH_1):PAGE42_I50@MSTR_DISCRETE.CAP(CHIPS)':
 'B': CDS_PINID='B';
NODE_NAME     C5P35 2
 '@BASEBOARD_FAB2_LIB.BASEBOARD_FAB2(SCH_1):PAGE42_I51@MSTR_DISCRETE.CAP(CHIPS)':
 'B': CDS_PINID='B';
NODE_NAME     C5P32 2
 '@BASEBOARD_FAB2_LIB.BASEBOARD_FAB2(SCH_1):PAGE42_I53@MSTR_DISCRETE.CAP(CHIPS)':
 'B': CDS_PINID='B';
NODE_NAME     C5P34 2
 '@BASEBOARD_FAB2_LIB.BASEBOARD_FAB2(SCH_1):PAGE42_I54@MSTR_DISCRETE.CAP(CHIPS)':
 'B': CDS_PINID='B';
NODE_NAME     C5P22 2
 '@BASEBOARD_FAB2_LIB.BASEBOARD_FAB2(SCH_1):PAGE42_I55@MSTR_DISCRETE.CAP(CHIPS)':
 'B': CDS_PINID='B';
NODE_NAME     C5P26 2
 '@BASEBOARD_FAB2_LIB.BASEBOARD_FAB2(SCH_1):PAGE42_I56@MSTR_DISCRETE.CAP(CHIPS)':
 'B': CDS_PINID='B';
NODE_NAME     C5P40 2
 '@BASEBOARD_FAB2_LIB.BASEBOARD_FAB2(SCH_1):PAGE42_I57@MSTR_DISCRETE.CAP(CHIPS)':
 'B': CDS_PINID='B';
NODE_NAME     C5P37 2
 '@BASEBOARD_FAB2_LIB.BASEBOARD_FAB2(SCH_1):PAGE42_I63@MSTR_DISCRETE.CAP(CHIPS)':
 'B': CDS_PINID='B';
NODE_NAME     C5P36 2
 '@BASEBOARD_FAB2_LIB.BASEBOARD_FAB2(SCH_1):PAGE42_I65@MSTR_DISCRETE.CAP(CHIPS)':
 'B': CDS_PINID='B';
NODE_NAME     C6D8 2
 '@BASEBOARD_FAB2_LIB.BASEBOARD_FAB2(SCH_1):PAGE42_I68@DEV_DISCRETE.CAP_A(CHIPS)':
 'B': CDS_PINID='B';
NODE_NAME     C5D38 2
 '@BASEBOARD_FAB2_LIB.BASEBOARD_FAB2(SCH_1):PAGE42_I69@DEV_DISCRETE.CAP_A(CHIPS)':
 'B': CDS_PINID='B';
NODE_NAME     C5D37 2
 '@BASEBOARD_FAB2_LIB.BASEBOARD_FAB2(SCH_1):PAGE42_I70@DEV_DISCRETE.CAP_A(CHIPS)':
 'B': CDS_PINID='B';
NODE_NAME     C6D7 2
 '@BASEBOARD_FAB2_LIB.BASEBOARD_FAB2(SCH_1):PAGE42_I72@DEV_DISCRETE.CAP_A(CHIPS)':
 'B': CDS_PINID='B';
NODE_NAME     C6D4 2
 '@BASEBOARD_FAB2_LIB.BASEBOARD_FAB2(SCH_1):PAGE42_I74@DEV_DISCRETE.CAP_A(CHIPS)':
 'B': CDS_PINID='B';
NODE_NAME     C6D5 2
 '@BASEBOARD_FAB2_LIB.BASEBOARD_FAB2(SCH_1):PAGE42_I75@DEV_DISCRETE.CAP_A(CHIPS)':
 'B': CDS_PINID='B';
NODE_NAME     C6D2 2
 '@BASEBOARD_FAB2_LIB.BASEBOARD_FAB2(SCH_1):PAGE42_I77@DEV_DISCRETE.CAP_A(CHIPS)':
 'B': CDS_PINID='B';
NODE_NAME     C6D3 2
 '@BASEBOARD_FAB2_LIB.BASEBOARD_FAB2(SCH_1):PAGE42_I80@DEV_DISCRETE.CAP_A(CHIPS)':
 'B': CDS_PINID='B';
NODE_NAME     C6D6 2
 '@BASEBOARD_FAB2_LIB.BASEBOARD_FAB2(SCH_1):PAGE42_I81@DEV_DISCRETE.CAP_A(CHIPS)':
 'B': CDS_PINID='B';
NODE_NAME     C5D51 2
 '@BASEBOARD_FAB2_LIB.BASEBOARD_FAB2(SCH_1):PAGE42_I83@DEV_DISCRETE.CAP_A(CHIPS)':
 'B': CDS_PINID='B';
NODE_NAME     C5D21 2
 '@BASEBOARD_FAB2_LIB.BASEBOARD_FAB2(SCH_1):PAGE42_I88@DEV_DISCRETE.CAP_A(CHIPS)':
 'B': CDS_PINID='B';
NODE_NAME     C5D50 2
 '@BASEBOARD_FAB2_LIB.BASEBOARD_FAB2(SCH_1):PAGE42_I89@DEV_DISCRETE.CAP_A(CHIPS)':
 'B': CDS_PINID='B';
NODE_NAME     C5D48 2
 '@BASEBOARD_FAB2_LIB.BASEBOARD_FAB2(SCH_1):PAGE42_I90@DEV_DISCRETE.CAP_A(CHIPS)':
 'B': CDS_PINID='B';
NODE_NAME     C5D13 2
 '@BASEBOARD_FAB2_LIB.BASEBOARD_FAB2(SCH_1):PAGE42_I91@MSTR_DISCRETE.CAP(CHIPS)':
 'B': CDS_PINID='B';
NODE_NAME     C5D11 2
 '@BASEBOARD_FAB2_LIB.BASEBOARD_FAB2(SCH_1):PAGE42_I93@MSTR_DISCRETE.CAP(CHIPS)':
 'B': CDS_PINID='B';
NODE_NAME     C5D12 2
 '@BASEBOARD_FAB2_LIB.BASEBOARD_FAB2(SCH_1):PAGE42_I94@MSTR_DISCRETE.CAP(CHIPS)':
 'B': CDS_PINID='B';
NODE_NAME     C5D23 2
 '@BASEBOARD_FAB2_LIB.BASEBOARD_FAB2(SCH_1):PAGE42_I98@DEV_DISCRETE.CAP_A(CHIPS)':
 'B': CDS_PINID='B';
NODE_NAME     C5D28 2
 '@BASEBOARD_FAB2_LIB.BASEBOARD_FAB2(SCH_1):PAGE42_I100@DEV_DISCRETE.CAP_A(CHIPS)':
 'B': CDS_PINID='B';
NODE_NAME     C5D29 2
 '@BASEBOARD_FAB2_LIB.BASEBOARD_FAB2(SCH_1):PAGE42_I102@DEV_DISCRETE.CAP_A(CHIPS)':
 'B': CDS_PINID='B';
NODE_NAME     C5D32 2
 '@BASEBOARD_FAB2_LIB.BASEBOARD_FAB2(SCH_1):PAGE42_I103@DEV_DISCRETE.CAP_A(CHIPS)':
 'B': CDS_PINID='B';
NODE_NAME     C5D47 2
 '@BASEBOARD_FAB2_LIB.BASEBOARD_FAB2(SCH_1):PAGE42_I104@DEV_DISCRETE.CAP_A(CHIPS)':
 'B': CDS_PINID='B';
NODE_NAME     C5D31 2
 '@BASEBOARD_FAB2_LIB.BASEBOARD_FAB2(SCH_1):PAGE42_I106@DEV_DISCRETE.CAP_A(CHIPS)':
 'B': CDS_PINID='B';
NODE_NAME     C5D46 2
 '@BASEBOARD_FAB2_LIB.BASEBOARD_FAB2(SCH_1):PAGE42_I107@DEV_DISCRETE.CAP_A(CHIPS)':
 'B': CDS_PINID='B';
NODE_NAME     C5D10 2
 '@BASEBOARD_FAB2_LIB.BASEBOARD_FAB2(SCH_1):PAGE42_I108@MSTR_DISCRETE.CAP(CHIPS)':
 'B': CDS_PINID='B';
NODE_NAME     C5D27 2
 '@BASEBOARD_FAB2_LIB.BASEBOARD_FAB2(SCH_1):PAGE42_I109@DEV_DISCRETE.CAP_A(CHIPS)':
 'B': CDS_PINID='B';
NODE_NAME     C5D30 2
 '@BASEBOARD_FAB2_LIB.BASEBOARD_FAB2(SCH_1):PAGE42_I111@DEV_DISCRETE.CAP_A(CHIPS)':
 'B': CDS_PINID='B';
NODE_NAME     C5D41 2
 '@BASEBOARD_FAB2_LIB.BASEBOARD_FAB2(SCH_1):PAGE42_I114@DEV_DISCRETE.CAP_A(CHIPS)':
 'B': CDS_PINID='B';
NODE_NAME     C5D40 2
 '@BASEBOARD_FAB2_LIB.BASEBOARD_FAB2(SCH_1):PAGE42_I115@DEV_DISCRETE.CAP_A(CHIPS)':
 'B': CDS_PINID='B';
NODE_NAME     C5D14 2
 '@BASEBOARD_FAB2_LIB.BASEBOARD_FAB2(SCH_1):PAGE42_I117@DEV_DISCRETE.CAP_A(CHIPS)':
 'B': CDS_PINID='B';
NODE_NAME     C5D17 2
 '@BASEBOARD_FAB2_LIB.BASEBOARD_FAB2(SCH_1):PAGE42_I118@DEV_DISCRETE.CAP_A(CHIPS)':
 'B': CDS_PINID='B';
NODE_NAME     C5D16 2
 '@BASEBOARD_FAB2_LIB.BASEBOARD_FAB2(SCH_1):PAGE42_I123@DEV_DISCRETE.CAP_A(CHIPS)':
 'B': CDS_PINID='B';
NODE_NAME     C5D5 2
 '@BASEBOARD_FAB2_LIB.BASEBOARD_FAB2(SCH_1):PAGE42_I125@DEV_DISCRETE.CAP_A(CHIPS)':
 'B': CDS_PINID='B';
NODE_NAME     C5D19 2
 '@BASEBOARD_FAB2_LIB.BASEBOARD_FAB2(SCH_1):PAGE42_I128@DEV_DISCRETE.CAP_A(CHIPS)':
 'B': CDS_PINID='B';
NODE_NAME     C5D43 2
 '@BASEBOARD_FAB2_LIB.BASEBOARD_FAB2(SCH_1):PAGE42_I131@DEV_DISCRETE.CAP_A(CHIPS)':
 'B': CDS_PINID='B';
NODE_NAME     C5D15 2
 '@BASEBOARD_FAB2_LIB.BASEBOARD_FAB2(SCH_1):PAGE42_I132@DEV_DISCRETE.CAP_A(CHIPS)':
 'B': CDS_PINID='B';
NODE_NAME     C5D18 2
 '@BASEBOARD_FAB2_LIB.BASEBOARD_FAB2(SCH_1):PAGE42_I134@DEV_DISCRETE.CAP_A(CHIPS)':
 'B': CDS_PINID='B';
NODE_NAME     C5D42 2
 '@BASEBOARD_FAB2_LIB.BASEBOARD_FAB2(SCH_1):PAGE42_I135@DEV_DISCRETE.CAP_A(CHIPS)':
 'B': CDS_PINID='B';
NODE_NAME     C5D24 2
 '@BASEBOARD_FAB2_LIB.BASEBOARD_FAB2(SCH_1):PAGE42_I138@DEV_DISCRETE.CAP_A(CHIPS)':
 'B': CDS_PINID='B';
NODE_NAME     C5D39 2
 '@BASEBOARD_FAB2_LIB.BASEBOARD_FAB2(SCH_1):PAGE42_I140@DEV_DISCRETE.CAP_A(CHIPS)':
 'B': CDS_PINID='B';
NODE_NAME     C5D44 2
 '@BASEBOARD_FAB2_LIB.BASEBOARD_FAB2(SCH_1):PAGE42_I142@DEV_DISCRETE.CAP_A(CHIPS)':
 'B': CDS_PINID='B';
NODE_NAME     C6D9 2
 '@BASEBOARD_FAB2_LIB.BASEBOARD_FAB2(SCH_1):PAGE42_I145@DEV_DISCRETE.CAP_A(CHIPS)':
 'B': CDS_PINID='B';
NODE_NAME     C6D10 2
 '@BASEBOARD_FAB2_LIB.BASEBOARD_FAB2(SCH_1):PAGE42_I147@DEV_DISCRETE.CAP_A(CHIPS)':
 'B': CDS_PINID='B';
NODE_NAME     C5D36 2
 '@BASEBOARD_FAB2_LIB.BASEBOARD_FAB2(SCH_1):PAGE42_I151@DEV_DISCRETE.CAP_A(CHIPS)':
 'B': CDS_PINID='B';
NODE_NAME     C5D49 2
 '@BASEBOARD_FAB2_LIB.BASEBOARD_FAB2(SCH_1):PAGE42_I152@DEV_DISCRETE.CAP_A(CHIPS)':
 'B': CDS_PINID='B';
NODE_NAME     C5D22 2
 '@BASEBOARD_FAB2_LIB.BASEBOARD_FAB2(SCH_1):PAGE42_I153@DEV_DISCRETE.CAP_A(CHIPS)':
 'B': CDS_PINID='B';
NODE_NAME     C5D26 2
 '@BASEBOARD_FAB2_LIB.BASEBOARD_FAB2(SCH_1):PAGE42_I154@DEV_DISCRETE.CAP_A(CHIPS)':
 'B': CDS_PINID='B';
NODE_NAME     C5D25 2
 '@BASEBOARD_FAB2_LIB.BASEBOARD_FAB2(SCH_1):PAGE42_I155@DEV_DISCRETE.CAP_A(CHIPS)':
 'B': CDS_PINID='B';
NODE_NAME     C5D45 2
 '@BASEBOARD_FAB2_LIB.BASEBOARD_FAB2(SCH_1):PAGE42_I156@DEV_DISCRETE.CAP_A(CHIPS)':
 'B': CDS_PINID='B';
NODE_NAME     C4P6 2
 '@BASEBOARD_FAB2_LIB.BASEBOARD_FAB2(SCH_1):PAGE42_I164@DEV_DISCRETE.CAP_A(CHIPS)':
 'B': CDS_PINID='B';
NODE_NAME     C5D20 2
 '@BASEBOARD_FAB2_LIB.BASEBOARD_FAB2(SCH_1):PAGE42_I173@DEV_DISCRETE.CAP_A(CHIPS)':
 'B': CDS_PINID='B';
NODE_NAME     C5D33 2
 '@BASEBOARD_FAB2_LIB.BASEBOARD_FAB2(SCH_1):PAGE42_I174@DEV_DISCRETE.CAP_A(CHIPS)':
 'B': CDS_PINID='B';
NODE_NAME     C5D34 2
 '@BASEBOARD_FAB2_LIB.BASEBOARD_FAB2(SCH_1):PAGE42_I175@DEV_DISCRETE.CAP_A(CHIPS)':
 'B': CDS_PINID='B';
NODE_NAME     C5D35 2
 '@BASEBOARD_FAB2_LIB.BASEBOARD_FAB2(SCH_1):PAGE42_I176@DEV_DISCRETE.CAP_A(CHIPS)':
 'B': CDS_PINID='B';
NODE_NAME     C4P8 2
 '@BASEBOARD_FAB2_LIB.BASEBOARD_FAB2(SCH_1):PAGE42_I178@DEV_DISCRETE.CAP_A(CHIPS)':
 'B': CDS_PINID='B';
NODE_NAME     C5D53 2
 '@BASEBOARD_FAB2_LIB.BASEBOARD_FAB2(SCH_1):PAGE42_I179@DEV_DISCRETE.CAP_A(CHIPS)':
 'B': CDS_PINID='B';
NODE_NAME     C5D52 2
 '@BASEBOARD_FAB2_LIB.BASEBOARD_FAB2(SCH_1):PAGE42_I180@DEV_DISCRETE.CAP_A(CHIPS)':
 'B': CDS_PINID='B';
NODE_NAME     C5P15 2
 '@BASEBOARD_FAB2_LIB.BASEBOARD_FAB2(SCH_1):PAGE42_I187@MSTR_DISCRETE.CAP(CHIPS)':
 'B': CDS_PINID='B';
NODE_NAME     C5P16 2
 '@BASEBOARD_FAB2_LIB.BASEBOARD_FAB2(SCH_1):PAGE42_I188@MSTR_DISCRETE.CAP(CHIPS)':
 'B': CDS_PINID='B';
NODE_NAME     C5P17 2
 '@BASEBOARD_FAB2_LIB.BASEBOARD_FAB2(SCH_1):PAGE42_I190@MSTR_DISCRETE.CAP(CHIPS)':
 'B': CDS_PINID='B';
NODE_NAME     J4G1 139
 '@BASEBOARD_FAB2_LIB.BASEBOARD_FAB2(SCH_1):PAGE43_I1@MSTR_SCONN.SCONN288_H44441004(CHIPS)':
 'SA'<0>: CDS_PINID='SA(0)';
NODE_NAME     J4G1 140
 '@BASEBOARD_FAB2_LIB.BASEBOARD_FAB2(SCH_1):PAGE43_I1@MSTR_SCONN.SCONN288_H44441004(CHIPS)':
 'SA'<1>: CDS_PINID='SA(1)';
NODE_NAME     J4G1 238
 '@BASEBOARD_FAB2_LIB.BASEBOARD_FAB2(SCH_1):PAGE43_I1@MSTR_SCONN.SCONN288_H44441004(CHIPS)':
 'SA'<2>: CDS_PINID='SA(2)';
NODE_NAME     J4G1 283
 '@BASEBOARD_FAB2_LIB.BASEBOARD_FAB2(SCH_1):PAGE43_I259@MSTR_SCONN.SCONN288_H44441004(CHIPS)':
 'VSS'<0>: CDS_PINID='VSS(0)';
NODE_NAME     J4G1 281
 '@BASEBOARD_FAB2_LIB.BASEBOARD_FAB2(SCH_1):PAGE43_I259@MSTR_SCONN.SCONN288_H44441004(CHIPS)':
 'VSS'<1>: CDS_PINID='VSS(1)';
NODE_NAME     J4G1 279
 '@BASEBOARD_FAB2_LIB.BASEBOARD_FAB2(SCH_1):PAGE43_I259@MSTR_SCONN.SCONN288_H44441004(CHIPS)':
 'VSS'<2>: CDS_PINID='VSS(2)';
NODE_NAME     J4G1 276
 '@BASEBOARD_FAB2_LIB.BASEBOARD_FAB2(SCH_1):PAGE43_I259@MSTR_SCONN.SCONN288_H44441004(CHIPS)':
 'VSS'<3>: CDS_PINID='VSS(3)';
NODE_NAME     J4G1 274
 '@BASEBOARD_FAB2_LIB.BASEBOARD_FAB2(SCH_1):PAGE43_I259@MSTR_SCONN.SCONN288_H44441004(CHIPS)':
 'VSS'<4>: CDS_PINID='VSS(4)';
NODE_NAME     J4G1 272
 '@BASEBOARD_FAB2_LIB.BASEBOARD_FAB2(SCH_1):PAGE43_I259@MSTR_SCONN.SCONN288_H44441004(CHIPS)':
 'VSS'<5>: CDS_PINID='VSS(5)';
NODE_NAME     J4G1 270
 '@BASEBOARD_FAB2_LIB.BASEBOARD_FAB2(SCH_1):PAGE43_I259@MSTR_SCONN.SCONN288_H44441004(CHIPS)':
 'VSS'<6>: CDS_PINID='VSS(6)';
NODE_NAME     J4G1 268
 '@BASEBOARD_FAB2_LIB.BASEBOARD_FAB2(SCH_1):PAGE43_I259@MSTR_SCONN.SCONN288_H44441004(CHIPS)':
 'VSS'<7>: CDS_PINID='VSS(7)';
NODE_NAME     J4G1 265
 '@BASEBOARD_FAB2_LIB.BASEBOARD_FAB2(SCH_1):PAGE43_I259@MSTR_SCONN.SCONN288_H44441004(CHIPS)':
 'VSS'<8>: CDS_PINID='VSS(8)';
NODE_NAME     J4G1 263
 '@BASEBOARD_FAB2_LIB.BASEBOARD_FAB2(SCH_1):PAGE43_I259@MSTR_SCONN.SCONN288_H44441004(CHIPS)':
 'VSS'<9>: CDS_PINID='VSS(9)';
NODE_NAME     J4G1 261
 '@BASEBOARD_FAB2_LIB.BASEBOARD_FAB2(SCH_1):PAGE43_I259@MSTR_SCONN.SCONN288_H44441004(CHIPS)':
 'VSS'<10>: CDS_PINID='VSS(10)';
NODE_NAME     J4G1 259
 '@BASEBOARD_FAB2_LIB.BASEBOARD_FAB2(SCH_1):PAGE43_I259@MSTR_SCONN.SCONN288_H44441004(CHIPS)':
 'VSS'<11>: CDS_PINID='VSS(11)';
NODE_NAME     J4G1 257
 '@BASEBOARD_FAB2_LIB.BASEBOARD_FAB2(SCH_1):PAGE43_I259@MSTR_SCONN.SCONN288_H44441004(CHIPS)':
 'VSS'<12>: CDS_PINID='VSS(12)';
NODE_NAME     J4G1 254
 '@BASEBOARD_FAB2_LIB.BASEBOARD_FAB2(SCH_1):PAGE43_I259@MSTR_SCONN.SCONN288_H44441004(CHIPS)':
 'VSS'<13>: CDS_PINID='VSS(13)';
NODE_NAME     J4G1 252
 '@BASEBOARD_FAB2_LIB.BASEBOARD_FAB2(SCH_1):PAGE43_I259@MSTR_SCONN.SCONN288_H44441004(CHIPS)':
 'VSS'<14>: CDS_PINID='VSS(14)';
NODE_NAME     J4G1 250
 '@BASEBOARD_FAB2_LIB.BASEBOARD_FAB2(SCH_1):PAGE43_I259@MSTR_SCONN.SCONN288_H44441004(CHIPS)':
 'VSS'<15>: CDS_PINID='VSS(15)';
NODE_NAME     J4G1 248
 '@BASEBOARD_FAB2_LIB.BASEBOARD_FAB2(SCH_1):PAGE43_I259@MSTR_SCONN.SCONN288_H44441004(CHIPS)':
 'VSS'<16>: CDS_PINID='VSS(16)';
NODE_NAME     J4G1 246
 '@BASEBOARD_FAB2_LIB.BASEBOARD_FAB2(SCH_1):PAGE43_I259@MSTR_SCONN.SCONN288_H44441004(CHIPS)':
 'VSS'<17>: CDS_PINID='VSS(17)';
NODE_NAME     J4G1 243
 '@BASEBOARD_FAB2_LIB.BASEBOARD_FAB2(SCH_1):PAGE43_I259@MSTR_SCONN.SCONN288_H44441004(CHIPS)':
 'VSS'<18>: CDS_PINID='VSS(18)';
NODE_NAME     J4G1 241
 '@BASEBOARD_FAB2_LIB.BASEBOARD_FAB2(SCH_1):PAGE43_I259@MSTR_SCONN.SCONN288_H44441004(CHIPS)':
 'VSS'<19>: CDS_PINID='VSS(19)';
NODE_NAME     J4G1 239
 '@BASEBOARD_FAB2_LIB.BASEBOARD_FAB2(SCH_1):PAGE43_I259@MSTR_SCONN.SCONN288_H44441004(CHIPS)':
 'VSS'<20>: CDS_PINID='VSS(20)';
NODE_NAME     J4G1 202
 '@BASEBOARD_FAB2_LIB.BASEBOARD_FAB2(SCH_1):PAGE43_I259@MSTR_SCONN.SCONN288_H44441004(CHIPS)':
 'VSS'<21>: CDS_PINID='VSS(21)';
NODE_NAME     J4G1 200
 '@BASEBOARD_FAB2_LIB.BASEBOARD_FAB2(SCH_1):PAGE43_I259@MSTR_SCONN.SCONN288_H44441004(CHIPS)':
 'VSS'<22>: CDS_PINID='VSS(22)';
NODE_NAME     J4G1 198
 '@BASEBOARD_FAB2_LIB.BASEBOARD_FAB2(SCH_1):PAGE43_I259@MSTR_SCONN.SCONN288_H44441004(CHIPS)':
 'VSS'<23>: CDS_PINID='VSS(23)';
NODE_NAME     J4G1 195
 '@BASEBOARD_FAB2_LIB.BASEBOARD_FAB2(SCH_1):PAGE43_I259@MSTR_SCONN.SCONN288_H44441004(CHIPS)':
 'VSS'<24>: CDS_PINID='VSS(24)';
NODE_NAME     J4G1 193
 '@BASEBOARD_FAB2_LIB.BASEBOARD_FAB2(SCH_1):PAGE43_I259@MSTR_SCONN.SCONN288_H44441004(CHIPS)':
 'VSS'<25>: CDS_PINID='VSS(25)';
NODE_NAME     J4G1 191
 '@BASEBOARD_FAB2_LIB.BASEBOARD_FAB2(SCH_1):PAGE43_I259@MSTR_SCONN.SCONN288_H44441004(CHIPS)':
 'VSS'<26>: CDS_PINID='VSS(26)';
NODE_NAME     J4G1 189
 '@BASEBOARD_FAB2_LIB.BASEBOARD_FAB2(SCH_1):PAGE43_I259@MSTR_SCONN.SCONN288_H44441004(CHIPS)':
 'VSS'<27>: CDS_PINID='VSS(27)';
NODE_NAME     J4G1 187
 '@BASEBOARD_FAB2_LIB.BASEBOARD_FAB2(SCH_1):PAGE43_I259@MSTR_SCONN.SCONN288_H44441004(CHIPS)':
 'VSS'<28>: CDS_PINID='VSS(28)';
NODE_NAME     J4G1 184
 '@BASEBOARD_FAB2_LIB.BASEBOARD_FAB2(SCH_1):PAGE43_I259@MSTR_SCONN.SCONN288_H44441004(CHIPS)':
 'VSS'<29>: CDS_PINID='VSS(29)';
NODE_NAME     J4G1 182
 '@BASEBOARD_FAB2_LIB.BASEBOARD_FAB2(SCH_1):PAGE43_I259@MSTR_SCONN.SCONN288_H44441004(CHIPS)':
 'VSS'<30>: CDS_PINID='VSS(30)';
NODE_NAME     J4G1 180
 '@BASEBOARD_FAB2_LIB.BASEBOARD_FAB2(SCH_1):PAGE43_I259@MSTR_SCONN.SCONN288_H44441004(CHIPS)':
 'VSS'<31>: CDS_PINID='VSS(31)';
NODE_NAME     J4G1 178
 '@BASEBOARD_FAB2_LIB.BASEBOARD_FAB2(SCH_1):PAGE43_I259@MSTR_SCONN.SCONN288_H44441004(CHIPS)':
 'VSS'<32>: CDS_PINID='VSS(32)';
NODE_NAME     J4G1 176
 '@BASEBOARD_FAB2_LIB.BASEBOARD_FAB2(SCH_1):PAGE43_I259@MSTR_SCONN.SCONN288_H44441004(CHIPS)':
 'VSS'<33>: CDS_PINID='VSS(33)';
NODE_NAME     J4G1 173
 '@BASEBOARD_FAB2_LIB.BASEBOARD_FAB2(SCH_1):PAGE43_I259@MSTR_SCONN.SCONN288_H44441004(CHIPS)':
 'VSS'<34>: CDS_PINID='VSS(34)';
NODE_NAME     J4G1 171
 '@BASEBOARD_FAB2_LIB.BASEBOARD_FAB2(SCH_1):PAGE43_I259@MSTR_SCONN.SCONN288_H44441004(CHIPS)':
 'VSS'<35>: CDS_PINID='VSS(35)';
NODE_NAME     J4G1 169
 '@BASEBOARD_FAB2_LIB.BASEBOARD_FAB2(SCH_1):PAGE43_I259@MSTR_SCONN.SCONN288_H44441004(CHIPS)':
 'VSS'<36>: CDS_PINID='VSS(36)';
NODE_NAME     J4G1 167
 '@BASEBOARD_FAB2_LIB.BASEBOARD_FAB2(SCH_1):PAGE43_I259@MSTR_SCONN.SCONN288_H44441004(CHIPS)':
 'VSS'<37>: CDS_PINID='VSS(37)';
NODE_NAME     J4G1 165
 '@BASEBOARD_FAB2_LIB.BASEBOARD_FAB2(SCH_1):PAGE43_I259@MSTR_SCONN.SCONN288_H44441004(CHIPS)':
 'VSS'<38>: CDS_PINID='VSS(38)';
NODE_NAME     J4G1 162
 '@BASEBOARD_FAB2_LIB.BASEBOARD_FAB2(SCH_1):PAGE43_I259@MSTR_SCONN.SCONN288_H44441004(CHIPS)':
 'VSS'<39>: CDS_PINID='VSS(39)';
NODE_NAME     J4G1 160
 '@BASEBOARD_FAB2_LIB.BASEBOARD_FAB2(SCH_1):PAGE43_I259@MSTR_SCONN.SCONN288_H44441004(CHIPS)':
 'VSS'<40>: CDS_PINID='VSS(40)';
NODE_NAME     J4G1 158
 '@BASEBOARD_FAB2_LIB.BASEBOARD_FAB2(SCH_1):PAGE43_I259@MSTR_SCONN.SCONN288_H44441004(CHIPS)':
 'VSS'<41>: CDS_PINID='VSS(41)';
NODE_NAME     J4G1 156
 '@BASEBOARD_FAB2_LIB.BASEBOARD_FAB2(SCH_1):PAGE43_I259@MSTR_SCONN.SCONN288_H44441004(CHIPS)':
 'VSS'<42>: CDS_PINID='VSS(42)';
NODE_NAME     J4G1 154
 '@BASEBOARD_FAB2_LIB.BASEBOARD_FAB2(SCH_1):PAGE43_I259@MSTR_SCONN.SCONN288_H44441004(CHIPS)':
 'VSS'<43>: CDS_PINID='VSS(43)';
NODE_NAME     J4G1 151
 '@BASEBOARD_FAB2_LIB.BASEBOARD_FAB2(SCH_1):PAGE43_I259@MSTR_SCONN.SCONN288_H44441004(CHIPS)':
 'VSS'<44>: CDS_PINID='VSS(44)';
NODE_NAME     J4G1 149
 '@BASEBOARD_FAB2_LIB.BASEBOARD_FAB2(SCH_1):PAGE43_I259@MSTR_SCONN.SCONN288_H44441004(CHIPS)':
 'VSS'<45>: CDS_PINID='VSS(45)';
NODE_NAME     J4G1 147
 '@BASEBOARD_FAB2_LIB.BASEBOARD_FAB2(SCH_1):PAGE43_I259@MSTR_SCONN.SCONN288_H44441004(CHIPS)':
 'VSS'<46>: CDS_PINID='VSS(46)';
NODE_NAME     J4G1 138
 '@BASEBOARD_FAB2_LIB.BASEBOARD_FAB2(SCH_1):PAGE43_I259@MSTR_SCONN.SCONN288_H44441004(CHIPS)':
 'VSS'<47>: CDS_PINID='VSS(47)';
NODE_NAME     J4G1 136
 '@BASEBOARD_FAB2_LIB.BASEBOARD_FAB2(SCH_1):PAGE43_I259@MSTR_SCONN.SCONN288_H44441004(CHIPS)':
 'VSS'<48>: CDS_PINID='VSS(48)';
NODE_NAME     J4G1 134
 '@BASEBOARD_FAB2_LIB.BASEBOARD_FAB2(SCH_1):PAGE43_I259@MSTR_SCONN.SCONN288_H44441004(CHIPS)':
 'VSS'<49>: CDS_PINID='VSS(49)';
NODE_NAME     J4G1 131
 '@BASEBOARD_FAB2_LIB.BASEBOARD_FAB2(SCH_1):PAGE43_I259@MSTR_SCONN.SCONN288_H44441004(CHIPS)':
 'VSS'<50>: CDS_PINID='VSS(50)';
NODE_NAME     J4G1 129
 '@BASEBOARD_FAB2_LIB.BASEBOARD_FAB2(SCH_1):PAGE43_I259@MSTR_SCONN.SCONN288_H44441004(CHIPS)':
 'VSS'<51>: CDS_PINID='VSS(51)';
NODE_NAME     J4G1 127
 '@BASEBOARD_FAB2_LIB.BASEBOARD_FAB2(SCH_1):PAGE43_I259@MSTR_SCONN.SCONN288_H44441004(CHIPS)':
 'VSS'<52>: CDS_PINID='VSS(52)';
NODE_NAME     J4G1 125
 '@BASEBOARD_FAB2_LIB.BASEBOARD_FAB2(SCH_1):PAGE43_I259@MSTR_SCONN.SCONN288_H44441004(CHIPS)':
 'VSS'<53>: CDS_PINID='VSS(53)';
NODE_NAME     J4G1 123
 '@BASEBOARD_FAB2_LIB.BASEBOARD_FAB2(SCH_1):PAGE43_I259@MSTR_SCONN.SCONN288_H44441004(CHIPS)':
 'VSS'<54>: CDS_PINID='VSS(54)';
NODE_NAME     J4G1 120
 '@BASEBOARD_FAB2_LIB.BASEBOARD_FAB2(SCH_1):PAGE43_I259@MSTR_SCONN.SCONN288_H44441004(CHIPS)':
 'VSS'<55>: CDS_PINID='VSS(55)';
NODE_NAME     J4G1 118
 '@BASEBOARD_FAB2_LIB.BASEBOARD_FAB2(SCH_1):PAGE43_I259@MSTR_SCONN.SCONN288_H44441004(CHIPS)':
 'VSS'<56>: CDS_PINID='VSS(56)';
NODE_NAME     J4G1 116
 '@BASEBOARD_FAB2_LIB.BASEBOARD_FAB2(SCH_1):PAGE43_I259@MSTR_SCONN.SCONN288_H44441004(CHIPS)':
 'VSS'<57>: CDS_PINID='VSS(57)';
NODE_NAME     J4G1 114
 '@BASEBOARD_FAB2_LIB.BASEBOARD_FAB2(SCH_1):PAGE43_I259@MSTR_SCONN.SCONN288_H44441004(CHIPS)':
 'VSS'<58>: CDS_PINID='VSS(58)';
NODE_NAME     J4G1 112
 '@BASEBOARD_FAB2_LIB.BASEBOARD_FAB2(SCH_1):PAGE43_I259@MSTR_SCONN.SCONN288_H44441004(CHIPS)':
 'VSS'<59>: CDS_PINID='VSS(59)';
NODE_NAME     J4G1 109
 '@BASEBOARD_FAB2_LIB.BASEBOARD_FAB2(SCH_1):PAGE43_I259@MSTR_SCONN.SCONN288_H44441004(CHIPS)':
 'VSS'<60>: CDS_PINID='VSS(60)';
NODE_NAME     J4G1 107
 '@BASEBOARD_FAB2_LIB.BASEBOARD_FAB2(SCH_1):PAGE43_I259@MSTR_SCONN.SCONN288_H44441004(CHIPS)':
 'VSS'<61>: CDS_PINID='VSS(61)';
NODE_NAME     J4G1 105
 '@BASEBOARD_FAB2_LIB.BASEBOARD_FAB2(SCH_1):PAGE43_I259@MSTR_SCONN.SCONN288_H44441004(CHIPS)':
 'VSS'<62>: CDS_PINID='VSS(62)';
NODE_NAME     J4G1 103
 '@BASEBOARD_FAB2_LIB.BASEBOARD_FAB2(SCH_1):PAGE43_I259@MSTR_SCONN.SCONN288_H44441004(CHIPS)':
 'VSS'<63>: CDS_PINID='VSS(63)';
NODE_NAME     J4G1 101
 '@BASEBOARD_FAB2_LIB.BASEBOARD_FAB2(SCH_1):PAGE43_I259@MSTR_SCONN.SCONN288_H44441004(CHIPS)':
 'VSS'<64>: CDS_PINID='VSS(64)';
NODE_NAME     J4G1 98
 '@BASEBOARD_FAB2_LIB.BASEBOARD_FAB2(SCH_1):PAGE43_I259@MSTR_SCONN.SCONN288_H44441004(CHIPS)':
 'VSS'<65>: CDS_PINID='VSS(65)';
NODE_NAME     J4G1 96
 '@BASEBOARD_FAB2_LIB.BASEBOARD_FAB2(SCH_1):PAGE43_I259@MSTR_SCONN.SCONN288_H44441004(CHIPS)':
 'VSS'<66>: CDS_PINID='VSS(66)';
NODE_NAME     J4G1 94
 '@BASEBOARD_FAB2_LIB.BASEBOARD_FAB2(SCH_1):PAGE43_I259@MSTR_SCONN.SCONN288_H44441004(CHIPS)':
 'VSS'<67>: CDS_PINID='VSS(67)';
NODE_NAME     J4G1 57
 '@BASEBOARD_FAB2_LIB.BASEBOARD_FAB2(SCH_1):PAGE43_I259@MSTR_SCONN.SCONN288_H44441004(CHIPS)':
 'VSS'<68>: CDS_PINID='VSS(68)';
NODE_NAME     J4G1 55
 '@BASEBOARD_FAB2_LIB.BASEBOARD_FAB2(SCH_1):PAGE43_I259@MSTR_SCONN.SCONN288_H44441004(CHIPS)':
 'VSS'<69>: CDS_PINID='VSS(69)';
NODE_NAME     J4G1 53
 '@BASEBOARD_FAB2_LIB.BASEBOARD_FAB2(SCH_1):PAGE43_I259@MSTR_SCONN.SCONN288_H44441004(CHIPS)':
 'VSS'<70>: CDS_PINID='VSS(70)';
NODE_NAME     J4G1 50
 '@BASEBOARD_FAB2_LIB.BASEBOARD_FAB2(SCH_1):PAGE43_I259@MSTR_SCONN.SCONN288_H44441004(CHIPS)':
 'VSS'<71>: CDS_PINID='VSS(71)';
NODE_NAME     J4G1 48
 '@BASEBOARD_FAB2_LIB.BASEBOARD_FAB2(SCH_1):PAGE43_I259@MSTR_SCONN.SCONN288_H44441004(CHIPS)':
 'VSS'<72>: CDS_PINID='VSS(72)';
NODE_NAME     J4G1 46
 '@BASEBOARD_FAB2_LIB.BASEBOARD_FAB2(SCH_1):PAGE43_I259@MSTR_SCONN.SCONN288_H44441004(CHIPS)':
 'VSS'<73>: CDS_PINID='VSS(73)';
NODE_NAME     J4G1 44
 '@BASEBOARD_FAB2_LIB.BASEBOARD_FAB2(SCH_1):PAGE43_I259@MSTR_SCONN.SCONN288_H44441004(CHIPS)':
 'VSS'<74>: CDS_PINID='VSS(74)';
NODE_NAME     J4G1 42
 '@BASEBOARD_FAB2_LIB.BASEBOARD_FAB2(SCH_1):PAGE43_I259@MSTR_SCONN.SCONN288_H44441004(CHIPS)':
 'VSS'<75>: CDS_PINID='VSS(75)';
NODE_NAME     J4G1 39
 '@BASEBOARD_FAB2_LIB.BASEBOARD_FAB2(SCH_1):PAGE43_I259@MSTR_SCONN.SCONN288_H44441004(CHIPS)':
 'VSS'<76>: CDS_PINID='VSS(76)';
NODE_NAME     J4G1 37
 '@BASEBOARD_FAB2_LIB.BASEBOARD_FAB2(SCH_1):PAGE43_I259@MSTR_SCONN.SCONN288_H44441004(CHIPS)':
 'VSS'<77>: CDS_PINID='VSS(77)';
NODE_NAME     J4G1 35
 '@BASEBOARD_FAB2_LIB.BASEBOARD_FAB2(SCH_1):PAGE43_I259@MSTR_SCONN.SCONN288_H44441004(CHIPS)':
 'VSS'<78>: CDS_PINID='VSS(78)';
NODE_NAME     J4G1 33
 '@BASEBOARD_FAB2_LIB.BASEBOARD_FAB2(SCH_1):PAGE43_I259@MSTR_SCONN.SCONN288_H44441004(CHIPS)':
 'VSS'<79>: CDS_PINID='VSS(79)';
NODE_NAME     J4G1 31
 '@BASEBOARD_FAB2_LIB.BASEBOARD_FAB2(SCH_1):PAGE43_I259@MSTR_SCONN.SCONN288_H44441004(CHIPS)':
 'VSS'<80>: CDS_PINID='VSS(80)';
NODE_NAME     J4G1 28
 '@BASEBOARD_FAB2_LIB.BASEBOARD_FAB2(SCH_1):PAGE43_I259@MSTR_SCONN.SCONN288_H44441004(CHIPS)':
 'VSS'<81>: CDS_PINID='VSS(81)';
NODE_NAME     J4G1 26
 '@BASEBOARD_FAB2_LIB.BASEBOARD_FAB2(SCH_1):PAGE43_I259@MSTR_SCONN.SCONN288_H44441004(CHIPS)':
 'VSS'<82>: CDS_PINID='VSS(82)';
NODE_NAME     J4G1 24
 '@BASEBOARD_FAB2_LIB.BASEBOARD_FAB2(SCH_1):PAGE43_I259@MSTR_SCONN.SCONN288_H44441004(CHIPS)':
 'VSS'<83>: CDS_PINID='VSS(83)';
NODE_NAME     J4G1 22
 '@BASEBOARD_FAB2_LIB.BASEBOARD_FAB2(SCH_1):PAGE43_I259@MSTR_SCONN.SCONN288_H44441004(CHIPS)':
 'VSS'<84>: CDS_PINID='VSS(84)';
NODE_NAME     J4G1 20
 '@BASEBOARD_FAB2_LIB.BASEBOARD_FAB2(SCH_1):PAGE43_I259@MSTR_SCONN.SCONN288_H44441004(CHIPS)':
 'VSS'<85>: CDS_PINID='VSS(85)';
NODE_NAME     J4G1 17
 '@BASEBOARD_FAB2_LIB.BASEBOARD_FAB2(SCH_1):PAGE43_I259@MSTR_SCONN.SCONN288_H44441004(CHIPS)':
 'VSS'<86>: CDS_PINID='VSS(86)';
NODE_NAME     J4G1 15
 '@BASEBOARD_FAB2_LIB.BASEBOARD_FAB2(SCH_1):PAGE43_I259@MSTR_SCONN.SCONN288_H44441004(CHIPS)':
 'VSS'<87>: CDS_PINID='VSS(87)';
NODE_NAME     J4G1 13
 '@BASEBOARD_FAB2_LIB.BASEBOARD_FAB2(SCH_1):PAGE43_I259@MSTR_SCONN.SCONN288_H44441004(CHIPS)':
 'VSS'<88>: CDS_PINID='VSS(88)';
NODE_NAME     J4G1 11
 '@BASEBOARD_FAB2_LIB.BASEBOARD_FAB2(SCH_1):PAGE43_I259@MSTR_SCONN.SCONN288_H44441004(CHIPS)':
 'VSS'<89>: CDS_PINID='VSS(89)';
NODE_NAME     J4G1 9
 '@BASEBOARD_FAB2_LIB.BASEBOARD_FAB2(SCH_1):PAGE43_I259@MSTR_SCONN.SCONN288_H44441004(CHIPS)':
 'VSS'<90>: CDS_PINID='VSS(90)';
NODE_NAME     J4G1 6
 '@BASEBOARD_FAB2_LIB.BASEBOARD_FAB2(SCH_1):PAGE43_I259@MSTR_SCONN.SCONN288_H44441004(CHIPS)':
 'VSS'<91>: CDS_PINID='VSS(91)';
NODE_NAME     J4G1 4
 '@BASEBOARD_FAB2_LIB.BASEBOARD_FAB2(SCH_1):PAGE43_I259@MSTR_SCONN.SCONN288_H44441004(CHIPS)':
 'VSS'<92>: CDS_PINID='VSS(92)';
NODE_NAME     J4G1 2
 '@BASEBOARD_FAB2_LIB.BASEBOARD_FAB2(SCH_1):PAGE43_I259@MSTR_SCONN.SCONN288_H44441004(CHIPS)':
 'VSS'<93>: CDS_PINID='VSS(93)';
NODE_NAME     C4F10 2
 '@BASEBOARD_FAB2_LIB.BASEBOARD_FAB2(SCH_1):PAGE43_I272@DEV_DISCRETE.CAP_A(CHIPS)':
 'B': CDS_PINID='B';
NODE_NAME     C6T1 2
 '@BASEBOARD_FAB2_LIB.BASEBOARD_FAB2(SCH_1):PAGE44_I2@DEV_DISCRETE.CAP_A(CHIPS)':
 'B': CDS_PINID='B';
NODE_NAME     J6T1 140
 '@BASEBOARD_FAB2_LIB.BASEBOARD_FAB2(SCH_1):PAGE44_I13@MSTR_SCONN.SCONN288_H44441003(CHIPS)':
 'SA'<1>: CDS_PINID='SA(1)';
NODE_NAME     J6T1 238
 '@BASEBOARD_FAB2_LIB.BASEBOARD_FAB2(SCH_1):PAGE44_I13@MSTR_SCONN.SCONN288_H44441003(CHIPS)':
 'SA'<2>: CDS_PINID='SA(2)';
NODE_NAME     J6T1 283
 '@BASEBOARD_FAB2_LIB.BASEBOARD_FAB2(SCH_1):PAGE44_I139@MSTR_SCONN.SCONN288_H44441003(CHIPS)':
 'VSS'<0>: CDS_PINID='VSS(0)';
NODE_NAME     J6T1 281
 '@BASEBOARD_FAB2_LIB.BASEBOARD_FAB2(SCH_1):PAGE44_I139@MSTR_SCONN.SCONN288_H44441003(CHIPS)':
 'VSS'<1>: CDS_PINID='VSS(1)';
NODE_NAME     J6T1 279
 '@BASEBOARD_FAB2_LIB.BASEBOARD_FAB2(SCH_1):PAGE44_I139@MSTR_SCONN.SCONN288_H44441003(CHIPS)':
 'VSS'<2>: CDS_PINID='VSS(2)';
NODE_NAME     J6T1 276
 '@BASEBOARD_FAB2_LIB.BASEBOARD_FAB2(SCH_1):PAGE44_I139@MSTR_SCONN.SCONN288_H44441003(CHIPS)':
 'VSS'<3>: CDS_PINID='VSS(3)';
NODE_NAME     J6T1 274
 '@BASEBOARD_FAB2_LIB.BASEBOARD_FAB2(SCH_1):PAGE44_I139@MSTR_SCONN.SCONN288_H44441003(CHIPS)':
 'VSS'<4>: CDS_PINID='VSS(4)';
NODE_NAME     J6T1 272
 '@BASEBOARD_FAB2_LIB.BASEBOARD_FAB2(SCH_1):PAGE44_I139@MSTR_SCONN.SCONN288_H44441003(CHIPS)':
 'VSS'<5>: CDS_PINID='VSS(5)';
NODE_NAME     J6T1 270
 '@BASEBOARD_FAB2_LIB.BASEBOARD_FAB2(SCH_1):PAGE44_I139@MSTR_SCONN.SCONN288_H44441003(CHIPS)':
 'VSS'<6>: CDS_PINID='VSS(6)';
NODE_NAME     J6T1 268
 '@BASEBOARD_FAB2_LIB.BASEBOARD_FAB2(SCH_1):PAGE44_I139@MSTR_SCONN.SCONN288_H44441003(CHIPS)':
 'VSS'<7>: CDS_PINID='VSS(7)';
NODE_NAME     J6T1 265
 '@BASEBOARD_FAB2_LIB.BASEBOARD_FAB2(SCH_1):PAGE44_I139@MSTR_SCONN.SCONN288_H44441003(CHIPS)':
 'VSS'<8>: CDS_PINID='VSS(8)';
NODE_NAME     J6T1 263
 '@BASEBOARD_FAB2_LIB.BASEBOARD_FAB2(SCH_1):PAGE44_I139@MSTR_SCONN.SCONN288_H44441003(CHIPS)':
 'VSS'<9>: CDS_PINID='VSS(9)';
NODE_NAME     J6T1 261
 '@BASEBOARD_FAB2_LIB.BASEBOARD_FAB2(SCH_1):PAGE44_I139@MSTR_SCONN.SCONN288_H44441003(CHIPS)':
 'VSS'<10>: CDS_PINID='VSS(10)';
NODE_NAME     J6T1 259
 '@BASEBOARD_FAB2_LIB.BASEBOARD_FAB2(SCH_1):PAGE44_I139@MSTR_SCONN.SCONN288_H44441003(CHIPS)':
 'VSS'<11>: CDS_PINID='VSS(11)';
NODE_NAME     J6T1 257
 '@BASEBOARD_FAB2_LIB.BASEBOARD_FAB2(SCH_1):PAGE44_I139@MSTR_SCONN.SCONN288_H44441003(CHIPS)':
 'VSS'<12>: CDS_PINID='VSS(12)';
NODE_NAME     J6T1 254
 '@BASEBOARD_FAB2_LIB.BASEBOARD_FAB2(SCH_1):PAGE44_I139@MSTR_SCONN.SCONN288_H44441003(CHIPS)':
 'VSS'<13>: CDS_PINID='VSS(13)';
NODE_NAME     J6T1 252
 '@BASEBOARD_FAB2_LIB.BASEBOARD_FAB2(SCH_1):PAGE44_I139@MSTR_SCONN.SCONN288_H44441003(CHIPS)':
 'VSS'<14>: CDS_PINID='VSS(14)';
NODE_NAME     J6T1 250
 '@BASEBOARD_FAB2_LIB.BASEBOARD_FAB2(SCH_1):PAGE44_I139@MSTR_SCONN.SCONN288_H44441003(CHIPS)':
 'VSS'<15>: CDS_PINID='VSS(15)';
NODE_NAME     J6T1 248
 '@BASEBOARD_FAB2_LIB.BASEBOARD_FAB2(SCH_1):PAGE44_I139@MSTR_SCONN.SCONN288_H44441003(CHIPS)':
 'VSS'<16>: CDS_PINID='VSS(16)';
NODE_NAME     J6T1 246
 '@BASEBOARD_FAB2_LIB.BASEBOARD_FAB2(SCH_1):PAGE44_I139@MSTR_SCONN.SCONN288_H44441003(CHIPS)':
 'VSS'<17>: CDS_PINID='VSS(17)';
NODE_NAME     J6T1 243
 '@BASEBOARD_FAB2_LIB.BASEBOARD_FAB2(SCH_1):PAGE44_I139@MSTR_SCONN.SCONN288_H44441003(CHIPS)':
 'VSS'<18>: CDS_PINID='VSS(18)';
NODE_NAME     J6T1 241
 '@BASEBOARD_FAB2_LIB.BASEBOARD_FAB2(SCH_1):PAGE44_I139@MSTR_SCONN.SCONN288_H44441003(CHIPS)':
 'VSS'<19>: CDS_PINID='VSS(19)';
NODE_NAME     J6T1 239
 '@BASEBOARD_FAB2_LIB.BASEBOARD_FAB2(SCH_1):PAGE44_I139@MSTR_SCONN.SCONN288_H44441003(CHIPS)':
 'VSS'<20>: CDS_PINID='VSS(20)';
NODE_NAME     J6T1 202
 '@BASEBOARD_FAB2_LIB.BASEBOARD_FAB2(SCH_1):PAGE44_I139@MSTR_SCONN.SCONN288_H44441003(CHIPS)':
 'VSS'<21>: CDS_PINID='VSS(21)';
NODE_NAME     J6T1 200
 '@BASEBOARD_FAB2_LIB.BASEBOARD_FAB2(SCH_1):PAGE44_I139@MSTR_SCONN.SCONN288_H44441003(CHIPS)':
 'VSS'<22>: CDS_PINID='VSS(22)';
NODE_NAME     J6T1 198
 '@BASEBOARD_FAB2_LIB.BASEBOARD_FAB2(SCH_1):PAGE44_I139@MSTR_SCONN.SCONN288_H44441003(CHIPS)':
 'VSS'<23>: CDS_PINID='VSS(23)';
NODE_NAME     J6T1 195
 '@BASEBOARD_FAB2_LIB.BASEBOARD_FAB2(SCH_1):PAGE44_I139@MSTR_SCONN.SCONN288_H44441003(CHIPS)':
 'VSS'<24>: CDS_PINID='VSS(24)';
NODE_NAME     J6T1 193
 '@BASEBOARD_FAB2_LIB.BASEBOARD_FAB2(SCH_1):PAGE44_I139@MSTR_SCONN.SCONN288_H44441003(CHIPS)':
 'VSS'<25>: CDS_PINID='VSS(25)';
NODE_NAME     J6T1 191
 '@BASEBOARD_FAB2_LIB.BASEBOARD_FAB2(SCH_1):PAGE44_I139@MSTR_SCONN.SCONN288_H44441003(CHIPS)':
 'VSS'<26>: CDS_PINID='VSS(26)';
NODE_NAME     J6T1 189
 '@BASEBOARD_FAB2_LIB.BASEBOARD_FAB2(SCH_1):PAGE44_I139@MSTR_SCONN.SCONN288_H44441003(CHIPS)':
 'VSS'<27>: CDS_PINID='VSS(27)';
NODE_NAME     J6T1 187
 '@BASEBOARD_FAB2_LIB.BASEBOARD_FAB2(SCH_1):PAGE44_I139@MSTR_SCONN.SCONN288_H44441003(CHIPS)':
 'VSS'<28>: CDS_PINID='VSS(28)';
NODE_NAME     J6T1 184
 '@BASEBOARD_FAB2_LIB.BASEBOARD_FAB2(SCH_1):PAGE44_I139@MSTR_SCONN.SCONN288_H44441003(CHIPS)':
 'VSS'<29>: CDS_PINID='VSS(29)';
NODE_NAME     J6T1 182
 '@BASEBOARD_FAB2_LIB.BASEBOARD_FAB2(SCH_1):PAGE44_I139@MSTR_SCONN.SCONN288_H44441003(CHIPS)':
 'VSS'<30>: CDS_PINID='VSS(30)';
NODE_NAME     J6T1 180
 '@BASEBOARD_FAB2_LIB.BASEBOARD_FAB2(SCH_1):PAGE44_I139@MSTR_SCONN.SCONN288_H44441003(CHIPS)':
 'VSS'<31>: CDS_PINID='VSS(31)';
NODE_NAME     J6T1 178
 '@BASEBOARD_FAB2_LIB.BASEBOARD_FAB2(SCH_1):PAGE44_I139@MSTR_SCONN.SCONN288_H44441003(CHIPS)':
 'VSS'<32>: CDS_PINID='VSS(32)';
NODE_NAME     J6T1 176
 '@BASEBOARD_FAB2_LIB.BASEBOARD_FAB2(SCH_1):PAGE44_I139@MSTR_SCONN.SCONN288_H44441003(CHIPS)':
 'VSS'<33>: CDS_PINID='VSS(33)';
NODE_NAME     J6T1 173
 '@BASEBOARD_FAB2_LIB.BASEBOARD_FAB2(SCH_1):PAGE44_I139@MSTR_SCONN.SCONN288_H44441003(CHIPS)':
 'VSS'<34>: CDS_PINID='VSS(34)';
NODE_NAME     J6T1 171
 '@BASEBOARD_FAB2_LIB.BASEBOARD_FAB2(SCH_1):PAGE44_I139@MSTR_SCONN.SCONN288_H44441003(CHIPS)':
 'VSS'<35>: CDS_PINID='VSS(35)';
NODE_NAME     J6T1 169
 '@BASEBOARD_FAB2_LIB.BASEBOARD_FAB2(SCH_1):PAGE44_I139@MSTR_SCONN.SCONN288_H44441003(CHIPS)':
 'VSS'<36>: CDS_PINID='VSS(36)';
NODE_NAME     J6T1 167
 '@BASEBOARD_FAB2_LIB.BASEBOARD_FAB2(SCH_1):PAGE44_I139@MSTR_SCONN.SCONN288_H44441003(CHIPS)':
 'VSS'<37>: CDS_PINID='VSS(37)';
NODE_NAME     J6T1 165
 '@BASEBOARD_FAB2_LIB.BASEBOARD_FAB2(SCH_1):PAGE44_I139@MSTR_SCONN.SCONN288_H44441003(CHIPS)':
 'VSS'<38>: CDS_PINID='VSS(38)';
NODE_NAME     J6T1 162
 '@BASEBOARD_FAB2_LIB.BASEBOARD_FAB2(SCH_1):PAGE44_I139@MSTR_SCONN.SCONN288_H44441003(CHIPS)':
 'VSS'<39>: CDS_PINID='VSS(39)';
NODE_NAME     J6T1 160
 '@BASEBOARD_FAB2_LIB.BASEBOARD_FAB2(SCH_1):PAGE44_I139@MSTR_SCONN.SCONN288_H44441003(CHIPS)':
 'VSS'<40>: CDS_PINID='VSS(40)';
NODE_NAME     J6T1 158
 '@BASEBOARD_FAB2_LIB.BASEBOARD_FAB2(SCH_1):PAGE44_I139@MSTR_SCONN.SCONN288_H44441003(CHIPS)':
 'VSS'<41>: CDS_PINID='VSS(41)';
NODE_NAME     J6T1 156
 '@BASEBOARD_FAB2_LIB.BASEBOARD_FAB2(SCH_1):PAGE44_I139@MSTR_SCONN.SCONN288_H44441003(CHIPS)':
 'VSS'<42>: CDS_PINID='VSS(42)';
NODE_NAME     J6T1 154
 '@BASEBOARD_FAB2_LIB.BASEBOARD_FAB2(SCH_1):PAGE44_I139@MSTR_SCONN.SCONN288_H44441003(CHIPS)':
 'VSS'<43>: CDS_PINID='VSS(43)';
NODE_NAME     J6T1 151
 '@BASEBOARD_FAB2_LIB.BASEBOARD_FAB2(SCH_1):PAGE44_I139@MSTR_SCONN.SCONN288_H44441003(CHIPS)':
 'VSS'<44>: CDS_PINID='VSS(44)';
NODE_NAME     J6T1 149
 '@BASEBOARD_FAB2_LIB.BASEBOARD_FAB2(SCH_1):PAGE44_I139@MSTR_SCONN.SCONN288_H44441003(CHIPS)':
 'VSS'<45>: CDS_PINID='VSS(45)';
NODE_NAME     J6T1 147
 '@BASEBOARD_FAB2_LIB.BASEBOARD_FAB2(SCH_1):PAGE44_I139@MSTR_SCONN.SCONN288_H44441003(CHIPS)':
 'VSS'<46>: CDS_PINID='VSS(46)';
NODE_NAME     J6T1 138
 '@BASEBOARD_FAB2_LIB.BASEBOARD_FAB2(SCH_1):PAGE44_I139@MSTR_SCONN.SCONN288_H44441003(CHIPS)':
 'VSS'<47>: CDS_PINID='VSS(47)';
NODE_NAME     J6T1 136
 '@BASEBOARD_FAB2_LIB.BASEBOARD_FAB2(SCH_1):PAGE44_I139@MSTR_SCONN.SCONN288_H44441003(CHIPS)':
 'VSS'<48>: CDS_PINID='VSS(48)';
NODE_NAME     J6T1 134
 '@BASEBOARD_FAB2_LIB.BASEBOARD_FAB2(SCH_1):PAGE44_I139@MSTR_SCONN.SCONN288_H44441003(CHIPS)':
 'VSS'<49>: CDS_PINID='VSS(49)';
NODE_NAME     J6T1 131
 '@BASEBOARD_FAB2_LIB.BASEBOARD_FAB2(SCH_1):PAGE44_I139@MSTR_SCONN.SCONN288_H44441003(CHIPS)':
 'VSS'<50>: CDS_PINID='VSS(50)';
NODE_NAME     J6T1 129
 '@BASEBOARD_FAB2_LIB.BASEBOARD_FAB2(SCH_1):PAGE44_I139@MSTR_SCONN.SCONN288_H44441003(CHIPS)':
 'VSS'<51>: CDS_PINID='VSS(51)';
NODE_NAME     J6T1 127
 '@BASEBOARD_FAB2_LIB.BASEBOARD_FAB2(SCH_1):PAGE44_I139@MSTR_SCONN.SCONN288_H44441003(CHIPS)':
 'VSS'<52>: CDS_PINID='VSS(52)';
NODE_NAME     J6T1 125
 '@BASEBOARD_FAB2_LIB.BASEBOARD_FAB2(SCH_1):PAGE44_I139@MSTR_SCONN.SCONN288_H44441003(CHIPS)':
 'VSS'<53>: CDS_PINID='VSS(53)';
NODE_NAME     J6T1 123
 '@BASEBOARD_FAB2_LIB.BASEBOARD_FAB2(SCH_1):PAGE44_I139@MSTR_SCONN.SCONN288_H44441003(CHIPS)':
 'VSS'<54>: CDS_PINID='VSS(54)';
NODE_NAME     J6T1 120
 '@BASEBOARD_FAB2_LIB.BASEBOARD_FAB2(SCH_1):PAGE44_I139@MSTR_SCONN.SCONN288_H44441003(CHIPS)':
 'VSS'<55>: CDS_PINID='VSS(55)';
NODE_NAME     J6T1 118
 '@BASEBOARD_FAB2_LIB.BASEBOARD_FAB2(SCH_1):PAGE44_I139@MSTR_SCONN.SCONN288_H44441003(CHIPS)':
 'VSS'<56>: CDS_PINID='VSS(56)';
NODE_NAME     J6T1 116
 '@BASEBOARD_FAB2_LIB.BASEBOARD_FAB2(SCH_1):PAGE44_I139@MSTR_SCONN.SCONN288_H44441003(CHIPS)':
 'VSS'<57>: CDS_PINID='VSS(57)';
NODE_NAME     J6T1 114
 '@BASEBOARD_FAB2_LIB.BASEBOARD_FAB2(SCH_1):PAGE44_I139@MSTR_SCONN.SCONN288_H44441003(CHIPS)':
 'VSS'<58>: CDS_PINID='VSS(58)';
NODE_NAME     J6T1 112
 '@BASEBOARD_FAB2_LIB.BASEBOARD_FAB2(SCH_1):PAGE44_I139@MSTR_SCONN.SCONN288_H44441003(CHIPS)':
 'VSS'<59>: CDS_PINID='VSS(59)';
NODE_NAME     J6T1 109
 '@BASEBOARD_FAB2_LIB.BASEBOARD_FAB2(SCH_1):PAGE44_I139@MSTR_SCONN.SCONN288_H44441003(CHIPS)':
 'VSS'<60>: CDS_PINID='VSS(60)';
NODE_NAME     J6T1 107
 '@BASEBOARD_FAB2_LIB.BASEBOARD_FAB2(SCH_1):PAGE44_I139@MSTR_SCONN.SCONN288_H44441003(CHIPS)':
 'VSS'<61>: CDS_PINID='VSS(61)';
NODE_NAME     J6T1 105
 '@BASEBOARD_FAB2_LIB.BASEBOARD_FAB2(SCH_1):PAGE44_I139@MSTR_SCONN.SCONN288_H44441003(CHIPS)':
 'VSS'<62>: CDS_PINID='VSS(62)';
NODE_NAME     J6T1 103
 '@BASEBOARD_FAB2_LIB.BASEBOARD_FAB2(SCH_1):PAGE44_I139@MSTR_SCONN.SCONN288_H44441003(CHIPS)':
 'VSS'<63>: CDS_PINID='VSS(63)';
NODE_NAME     J6T1 101
 '@BASEBOARD_FAB2_LIB.BASEBOARD_FAB2(SCH_1):PAGE44_I139@MSTR_SCONN.SCONN288_H44441003(CHIPS)':
 'VSS'<64>: CDS_PINID='VSS(64)';
NODE_NAME     J6T1 98
 '@BASEBOARD_FAB2_LIB.BASEBOARD_FAB2(SCH_1):PAGE44_I139@MSTR_SCONN.SCONN288_H44441003(CHIPS)':
 'VSS'<65>: CDS_PINID='VSS(65)';
NODE_NAME     J6T1 96
 '@BASEBOARD_FAB2_LIB.BASEBOARD_FAB2(SCH_1):PAGE44_I139@MSTR_SCONN.SCONN288_H44441003(CHIPS)':
 'VSS'<66>: CDS_PINID='VSS(66)';
NODE_NAME     J6T1 94
 '@BASEBOARD_FAB2_LIB.BASEBOARD_FAB2(SCH_1):PAGE44_I139@MSTR_SCONN.SCONN288_H44441003(CHIPS)':
 'VSS'<67>: CDS_PINID='VSS(67)';
NODE_NAME     J6T1 57
 '@BASEBOARD_FAB2_LIB.BASEBOARD_FAB2(SCH_1):PAGE44_I139@MSTR_SCONN.SCONN288_H44441003(CHIPS)':
 'VSS'<68>: CDS_PINID='VSS(68)';
NODE_NAME     J6T1 55
 '@BASEBOARD_FAB2_LIB.BASEBOARD_FAB2(SCH_1):PAGE44_I139@MSTR_SCONN.SCONN288_H44441003(CHIPS)':
 'VSS'<69>: CDS_PINID='VSS(69)';
NODE_NAME     J6T1 53
 '@BASEBOARD_FAB2_LIB.BASEBOARD_FAB2(SCH_1):PAGE44_I139@MSTR_SCONN.SCONN288_H44441003(CHIPS)':
 'VSS'<70>: CDS_PINID='VSS(70)';
NODE_NAME     J6T1 50
 '@BASEBOARD_FAB2_LIB.BASEBOARD_FAB2(SCH_1):PAGE44_I139@MSTR_SCONN.SCONN288_H44441003(CHIPS)':
 'VSS'<71>: CDS_PINID='VSS(71)';
NODE_NAME     J6T1 48
 '@BASEBOARD_FAB2_LIB.BASEBOARD_FAB2(SCH_1):PAGE44_I139@MSTR_SCONN.SCONN288_H44441003(CHIPS)':
 'VSS'<72>: CDS_PINID='VSS(72)';
NODE_NAME     J6T1 46
 '@BASEBOARD_FAB2_LIB.BASEBOARD_FAB2(SCH_1):PAGE44_I139@MSTR_SCONN.SCONN288_H44441003(CHIPS)':
 'VSS'<73>: CDS_PINID='VSS(73)';
NODE_NAME     J6T1 44
 '@BASEBOARD_FAB2_LIB.BASEBOARD_FAB2(SCH_1):PAGE44_I139@MSTR_SCONN.SCONN288_H44441003(CHIPS)':
 'VSS'<74>: CDS_PINID='VSS(74)';
NODE_NAME     J6T1 42
 '@BASEBOARD_FAB2_LIB.BASEBOARD_FAB2(SCH_1):PAGE44_I139@MSTR_SCONN.SCONN288_H44441003(CHIPS)':
 'VSS'<75>: CDS_PINID='VSS(75)';
NODE_NAME     J6T1 39
 '@BASEBOARD_FAB2_LIB.BASEBOARD_FAB2(SCH_1):PAGE44_I139@MSTR_SCONN.SCONN288_H44441003(CHIPS)':
 'VSS'<76>: CDS_PINID='VSS(76)';
NODE_NAME     J6T1 37
 '@BASEBOARD_FAB2_LIB.BASEBOARD_FAB2(SCH_1):PAGE44_I139@MSTR_SCONN.SCONN288_H44441003(CHIPS)':
 'VSS'<77>: CDS_PINID='VSS(77)';
NODE_NAME     J6T1 35
 '@BASEBOARD_FAB2_LIB.BASEBOARD_FAB2(SCH_1):PAGE44_I139@MSTR_SCONN.SCONN288_H44441003(CHIPS)':
 'VSS'<78>: CDS_PINID='VSS(78)';
NODE_NAME     J6T1 33
 '@BASEBOARD_FAB2_LIB.BASEBOARD_FAB2(SCH_1):PAGE44_I139@MSTR_SCONN.SCONN288_H44441003(CHIPS)':
 'VSS'<79>: CDS_PINID='VSS(79)';
NODE_NAME     J6T1 31
 '@BASEBOARD_FAB2_LIB.BASEBOARD_FAB2(SCH_1):PAGE44_I139@MSTR_SCONN.SCONN288_H44441003(CHIPS)':
 'VSS'<80>: CDS_PINID='VSS(80)';
NODE_NAME     J6T1 28
 '@BASEBOARD_FAB2_LIB.BASEBOARD_FAB2(SCH_1):PAGE44_I139@MSTR_SCONN.SCONN288_H44441003(CHIPS)':
 'VSS'<81>: CDS_PINID='VSS(81)';
NODE_NAME     J6T1 26
 '@BASEBOARD_FAB2_LIB.BASEBOARD_FAB2(SCH_1):PAGE44_I139@MSTR_SCONN.SCONN288_H44441003(CHIPS)':
 'VSS'<82>: CDS_PINID='VSS(82)';
NODE_NAME     J6T1 24
 '@BASEBOARD_FAB2_LIB.BASEBOARD_FAB2(SCH_1):PAGE44_I139@MSTR_SCONN.SCONN288_H44441003(CHIPS)':
 'VSS'<83>: CDS_PINID='VSS(83)';
NODE_NAME     J6T1 22
 '@BASEBOARD_FAB2_LIB.BASEBOARD_FAB2(SCH_1):PAGE44_I139@MSTR_SCONN.SCONN288_H44441003(CHIPS)':
 'VSS'<84>: CDS_PINID='VSS(84)';
NODE_NAME     J6T1 20
 '@BASEBOARD_FAB2_LIB.BASEBOARD_FAB2(SCH_1):PAGE44_I139@MSTR_SCONN.SCONN288_H44441003(CHIPS)':
 'VSS'<85>: CDS_PINID='VSS(85)';
NODE_NAME     J6T1 17
 '@BASEBOARD_FAB2_LIB.BASEBOARD_FAB2(SCH_1):PAGE44_I139@MSTR_SCONN.SCONN288_H44441003(CHIPS)':
 'VSS'<86>: CDS_PINID='VSS(86)';
NODE_NAME     J6T1 15
 '@BASEBOARD_FAB2_LIB.BASEBOARD_FAB2(SCH_1):PAGE44_I139@MSTR_SCONN.SCONN288_H44441003(CHIPS)':
 'VSS'<87>: CDS_PINID='VSS(87)';
NODE_NAME     J6T1 13
 '@BASEBOARD_FAB2_LIB.BASEBOARD_FAB2(SCH_1):PAGE44_I139@MSTR_SCONN.SCONN288_H44441003(CHIPS)':
 'VSS'<88>: CDS_PINID='VSS(88)';
NODE_NAME     J6T1 11
 '@BASEBOARD_FAB2_LIB.BASEBOARD_FAB2(SCH_1):PAGE44_I139@MSTR_SCONN.SCONN288_H44441003(CHIPS)':
 'VSS'<89>: CDS_PINID='VSS(89)';
NODE_NAME     J6T1 9
 '@BASEBOARD_FAB2_LIB.BASEBOARD_FAB2(SCH_1):PAGE44_I139@MSTR_SCONN.SCONN288_H44441003(CHIPS)':
 'VSS'<90>: CDS_PINID='VSS(90)';
NODE_NAME     J6T1 6
 '@BASEBOARD_FAB2_LIB.BASEBOARD_FAB2(SCH_1):PAGE44_I139@MSTR_SCONN.SCONN288_H44441003(CHIPS)':
 'VSS'<91>: CDS_PINID='VSS(91)';
NODE_NAME     J6T1 4
 '@BASEBOARD_FAB2_LIB.BASEBOARD_FAB2(SCH_1):PAGE44_I139@MSTR_SCONN.SCONN288_H44441003(CHIPS)':
 'VSS'<92>: CDS_PINID='VSS(92)';
NODE_NAME     J6T1 2
 '@BASEBOARD_FAB2_LIB.BASEBOARD_FAB2(SCH_1):PAGE44_I139@MSTR_SCONN.SCONN288_H44441003(CHIPS)':
 'VSS'<93>: CDS_PINID='VSS(93)';
NODE_NAME     J4G2 283
 '@BASEBOARD_FAB2_LIB.BASEBOARD_FAB2(SCH_1):PAGE45_I43@MSTR_SCONN.SCONN288_H44441004(CHIPS)':
 'VSS'<0>: CDS_PINID='VSS(0)';
NODE_NAME     J4G2 281
 '@BASEBOARD_FAB2_LIB.BASEBOARD_FAB2(SCH_1):PAGE45_I43@MSTR_SCONN.SCONN288_H44441004(CHIPS)':
 'VSS'<1>: CDS_PINID='VSS(1)';
NODE_NAME     J4G2 279
 '@BASEBOARD_FAB2_LIB.BASEBOARD_FAB2(SCH_1):PAGE45_I43@MSTR_SCONN.SCONN288_H44441004(CHIPS)':
 'VSS'<2>: CDS_PINID='VSS(2)';
NODE_NAME     J4G2 276
 '@BASEBOARD_FAB2_LIB.BASEBOARD_FAB2(SCH_1):PAGE45_I43@MSTR_SCONN.SCONN288_H44441004(CHIPS)':
 'VSS'<3>: CDS_PINID='VSS(3)';
NODE_NAME     J4G2 274
 '@BASEBOARD_FAB2_LIB.BASEBOARD_FAB2(SCH_1):PAGE45_I43@MSTR_SCONN.SCONN288_H44441004(CHIPS)':
 'VSS'<4>: CDS_PINID='VSS(4)';
NODE_NAME     J4G2 272
 '@BASEBOARD_FAB2_LIB.BASEBOARD_FAB2(SCH_1):PAGE45_I43@MSTR_SCONN.SCONN288_H44441004(CHIPS)':
 'VSS'<5>: CDS_PINID='VSS(5)';
NODE_NAME     J4G2 270
 '@BASEBOARD_FAB2_LIB.BASEBOARD_FAB2(SCH_1):PAGE45_I43@MSTR_SCONN.SCONN288_H44441004(CHIPS)':
 'VSS'<6>: CDS_PINID='VSS(6)';
NODE_NAME     J4G2 268
 '@BASEBOARD_FAB2_LIB.BASEBOARD_FAB2(SCH_1):PAGE45_I43@MSTR_SCONN.SCONN288_H44441004(CHIPS)':
 'VSS'<7>: CDS_PINID='VSS(7)';
NODE_NAME     J4G2 265
 '@BASEBOARD_FAB2_LIB.BASEBOARD_FAB2(SCH_1):PAGE45_I43@MSTR_SCONN.SCONN288_H44441004(CHIPS)':
 'VSS'<8>: CDS_PINID='VSS(8)';
NODE_NAME     J4G2 263
 '@BASEBOARD_FAB2_LIB.BASEBOARD_FAB2(SCH_1):PAGE45_I43@MSTR_SCONN.SCONN288_H44441004(CHIPS)':
 'VSS'<9>: CDS_PINID='VSS(9)';
NODE_NAME     J4G2 261
 '@BASEBOARD_FAB2_LIB.BASEBOARD_FAB2(SCH_1):PAGE45_I43@MSTR_SCONN.SCONN288_H44441004(CHIPS)':
 'VSS'<10>: CDS_PINID='VSS(10)';
NODE_NAME     J4G2 259
 '@BASEBOARD_FAB2_LIB.BASEBOARD_FAB2(SCH_1):PAGE45_I43@MSTR_SCONN.SCONN288_H44441004(CHIPS)':
 'VSS'<11>: CDS_PINID='VSS(11)';
NODE_NAME     J4G2 257
 '@BASEBOARD_FAB2_LIB.BASEBOARD_FAB2(SCH_1):PAGE45_I43@MSTR_SCONN.SCONN288_H44441004(CHIPS)':
 'VSS'<12>: CDS_PINID='VSS(12)';
NODE_NAME     J4G2 254
 '@BASEBOARD_FAB2_LIB.BASEBOARD_FAB2(SCH_1):PAGE45_I43@MSTR_SCONN.SCONN288_H44441004(CHIPS)':
 'VSS'<13>: CDS_PINID='VSS(13)';
NODE_NAME     J4G2 252
 '@BASEBOARD_FAB2_LIB.BASEBOARD_FAB2(SCH_1):PAGE45_I43@MSTR_SCONN.SCONN288_H44441004(CHIPS)':
 'VSS'<14>: CDS_PINID='VSS(14)';
NODE_NAME     J4G2 250
 '@BASEBOARD_FAB2_LIB.BASEBOARD_FAB2(SCH_1):PAGE45_I43@MSTR_SCONN.SCONN288_H44441004(CHIPS)':
 'VSS'<15>: CDS_PINID='VSS(15)';
NODE_NAME     J4G2 248
 '@BASEBOARD_FAB2_LIB.BASEBOARD_FAB2(SCH_1):PAGE45_I43@MSTR_SCONN.SCONN288_H44441004(CHIPS)':
 'VSS'<16>: CDS_PINID='VSS(16)';
NODE_NAME     J4G2 246
 '@BASEBOARD_FAB2_LIB.BASEBOARD_FAB2(SCH_1):PAGE45_I43@MSTR_SCONN.SCONN288_H44441004(CHIPS)':
 'VSS'<17>: CDS_PINID='VSS(17)';
NODE_NAME     J4G2 243
 '@BASEBOARD_FAB2_LIB.BASEBOARD_FAB2(SCH_1):PAGE45_I43@MSTR_SCONN.SCONN288_H44441004(CHIPS)':
 'VSS'<18>: CDS_PINID='VSS(18)';
NODE_NAME     J4G2 241
 '@BASEBOARD_FAB2_LIB.BASEBOARD_FAB2(SCH_1):PAGE45_I43@MSTR_SCONN.SCONN288_H44441004(CHIPS)':
 'VSS'<19>: CDS_PINID='VSS(19)';
NODE_NAME     J4G2 239
 '@BASEBOARD_FAB2_LIB.BASEBOARD_FAB2(SCH_1):PAGE45_I43@MSTR_SCONN.SCONN288_H44441004(CHIPS)':
 'VSS'<20>: CDS_PINID='VSS(20)';
NODE_NAME     J4G2 202
 '@BASEBOARD_FAB2_LIB.BASEBOARD_FAB2(SCH_1):PAGE45_I43@MSTR_SCONN.SCONN288_H44441004(CHIPS)':
 'VSS'<21>: CDS_PINID='VSS(21)';
NODE_NAME     J4G2 200
 '@BASEBOARD_FAB2_LIB.BASEBOARD_FAB2(SCH_1):PAGE45_I43@MSTR_SCONN.SCONN288_H44441004(CHIPS)':
 'VSS'<22>: CDS_PINID='VSS(22)';
NODE_NAME     J4G2 198
 '@BASEBOARD_FAB2_LIB.BASEBOARD_FAB2(SCH_1):PAGE45_I43@MSTR_SCONN.SCONN288_H44441004(CHIPS)':
 'VSS'<23>: CDS_PINID='VSS(23)';
NODE_NAME     J4G2 195
 '@BASEBOARD_FAB2_LIB.BASEBOARD_FAB2(SCH_1):PAGE45_I43@MSTR_SCONN.SCONN288_H44441004(CHIPS)':
 'VSS'<24>: CDS_PINID='VSS(24)';
NODE_NAME     J4G2 193
 '@BASEBOARD_FAB2_LIB.BASEBOARD_FAB2(SCH_1):PAGE45_I43@MSTR_SCONN.SCONN288_H44441004(CHIPS)':
 'VSS'<25>: CDS_PINID='VSS(25)';
NODE_NAME     J4G2 191
 '@BASEBOARD_FAB2_LIB.BASEBOARD_FAB2(SCH_1):PAGE45_I43@MSTR_SCONN.SCONN288_H44441004(CHIPS)':
 'VSS'<26>: CDS_PINID='VSS(26)';
NODE_NAME     J4G2 189
 '@BASEBOARD_FAB2_LIB.BASEBOARD_FAB2(SCH_1):PAGE45_I43@MSTR_SCONN.SCONN288_H44441004(CHIPS)':
 'VSS'<27>: CDS_PINID='VSS(27)';
NODE_NAME     J4G2 187
 '@BASEBOARD_FAB2_LIB.BASEBOARD_FAB2(SCH_1):PAGE45_I43@MSTR_SCONN.SCONN288_H44441004(CHIPS)':
 'VSS'<28>: CDS_PINID='VSS(28)';
NODE_NAME     J4G2 184
 '@BASEBOARD_FAB2_LIB.BASEBOARD_FAB2(SCH_1):PAGE45_I43@MSTR_SCONN.SCONN288_H44441004(CHIPS)':
 'VSS'<29>: CDS_PINID='VSS(29)';
NODE_NAME     J4G2 182
 '@BASEBOARD_FAB2_LIB.BASEBOARD_FAB2(SCH_1):PAGE45_I43@MSTR_SCONN.SCONN288_H44441004(CHIPS)':
 'VSS'<30>: CDS_PINID='VSS(30)';
NODE_NAME     J4G2 180
 '@BASEBOARD_FAB2_LIB.BASEBOARD_FAB2(SCH_1):PAGE45_I43@MSTR_SCONN.SCONN288_H44441004(CHIPS)':
 'VSS'<31>: CDS_PINID='VSS(31)';
NODE_NAME     J4G2 178
 '@BASEBOARD_FAB2_LIB.BASEBOARD_FAB2(SCH_1):PAGE45_I43@MSTR_SCONN.SCONN288_H44441004(CHIPS)':
 'VSS'<32>: CDS_PINID='VSS(32)';
NODE_NAME     J4G2 176
 '@BASEBOARD_FAB2_LIB.BASEBOARD_FAB2(SCH_1):PAGE45_I43@MSTR_SCONN.SCONN288_H44441004(CHIPS)':
 'VSS'<33>: CDS_PINID='VSS(33)';
NODE_NAME     J4G2 173
 '@BASEBOARD_FAB2_LIB.BASEBOARD_FAB2(SCH_1):PAGE45_I43@MSTR_SCONN.SCONN288_H44441004(CHIPS)':
 'VSS'<34>: CDS_PINID='VSS(34)';
NODE_NAME     J4G2 171
 '@BASEBOARD_FAB2_LIB.BASEBOARD_FAB2(SCH_1):PAGE45_I43@MSTR_SCONN.SCONN288_H44441004(CHIPS)':
 'VSS'<35>: CDS_PINID='VSS(35)';
NODE_NAME     J4G2 169
 '@BASEBOARD_FAB2_LIB.BASEBOARD_FAB2(SCH_1):PAGE45_I43@MSTR_SCONN.SCONN288_H44441004(CHIPS)':
 'VSS'<36>: CDS_PINID='VSS(36)';
NODE_NAME     J4G2 167
 '@BASEBOARD_FAB2_LIB.BASEBOARD_FAB2(SCH_1):PAGE45_I43@MSTR_SCONN.SCONN288_H44441004(CHIPS)':
 'VSS'<37>: CDS_PINID='VSS(37)';
NODE_NAME     J4G2 165
 '@BASEBOARD_FAB2_LIB.BASEBOARD_FAB2(SCH_1):PAGE45_I43@MSTR_SCONN.SCONN288_H44441004(CHIPS)':
 'VSS'<38>: CDS_PINID='VSS(38)';
NODE_NAME     J4G2 162
 '@BASEBOARD_FAB2_LIB.BASEBOARD_FAB2(SCH_1):PAGE45_I43@MSTR_SCONN.SCONN288_H44441004(CHIPS)':
 'VSS'<39>: CDS_PINID='VSS(39)';
NODE_NAME     J4G2 160
 '@BASEBOARD_FAB2_LIB.BASEBOARD_FAB2(SCH_1):PAGE45_I43@MSTR_SCONN.SCONN288_H44441004(CHIPS)':
 'VSS'<40>: CDS_PINID='VSS(40)';
NODE_NAME     J4G2 158
 '@BASEBOARD_FAB2_LIB.BASEBOARD_FAB2(SCH_1):PAGE45_I43@MSTR_SCONN.SCONN288_H44441004(CHIPS)':
 'VSS'<41>: CDS_PINID='VSS(41)';
NODE_NAME     J4G2 156
 '@BASEBOARD_FAB2_LIB.BASEBOARD_FAB2(SCH_1):PAGE45_I43@MSTR_SCONN.SCONN288_H44441004(CHIPS)':
 'VSS'<42>: CDS_PINID='VSS(42)';
NODE_NAME     J4G2 154
 '@BASEBOARD_FAB2_LIB.BASEBOARD_FAB2(SCH_1):PAGE45_I43@MSTR_SCONN.SCONN288_H44441004(CHIPS)':
 'VSS'<43>: CDS_PINID='VSS(43)';
NODE_NAME     J4G2 151
 '@BASEBOARD_FAB2_LIB.BASEBOARD_FAB2(SCH_1):PAGE45_I43@MSTR_SCONN.SCONN288_H44441004(CHIPS)':
 'VSS'<44>: CDS_PINID='VSS(44)';
NODE_NAME     J4G2 149
 '@BASEBOARD_FAB2_LIB.BASEBOARD_FAB2(SCH_1):PAGE45_I43@MSTR_SCONN.SCONN288_H44441004(CHIPS)':
 'VSS'<45>: CDS_PINID='VSS(45)';
NODE_NAME     J4G2 147
 '@BASEBOARD_FAB2_LIB.BASEBOARD_FAB2(SCH_1):PAGE45_I43@MSTR_SCONN.SCONN288_H44441004(CHIPS)':
 'VSS'<46>: CDS_PINID='VSS(46)';
NODE_NAME     J4G2 138
 '@BASEBOARD_FAB2_LIB.BASEBOARD_FAB2(SCH_1):PAGE45_I43@MSTR_SCONN.SCONN288_H44441004(CHIPS)':
 'VSS'<47>: CDS_PINID='VSS(47)';
NODE_NAME     J4G2 136
 '@BASEBOARD_FAB2_LIB.BASEBOARD_FAB2(SCH_1):PAGE45_I43@MSTR_SCONN.SCONN288_H44441004(CHIPS)':
 'VSS'<48>: CDS_PINID='VSS(48)';
NODE_NAME     J4G2 134
 '@BASEBOARD_FAB2_LIB.BASEBOARD_FAB2(SCH_1):PAGE45_I43@MSTR_SCONN.SCONN288_H44441004(CHIPS)':
 'VSS'<49>: CDS_PINID='VSS(49)';
NODE_NAME     J4G2 131
 '@BASEBOARD_FAB2_LIB.BASEBOARD_FAB2(SCH_1):PAGE45_I43@MSTR_SCONN.SCONN288_H44441004(CHIPS)':
 'VSS'<50>: CDS_PINID='VSS(50)';
NODE_NAME     J4G2 129
 '@BASEBOARD_FAB2_LIB.BASEBOARD_FAB2(SCH_1):PAGE45_I43@MSTR_SCONN.SCONN288_H44441004(CHIPS)':
 'VSS'<51>: CDS_PINID='VSS(51)';
NODE_NAME     J4G2 127
 '@BASEBOARD_FAB2_LIB.BASEBOARD_FAB2(SCH_1):PAGE45_I43@MSTR_SCONN.SCONN288_H44441004(CHIPS)':
 'VSS'<52>: CDS_PINID='VSS(52)';
NODE_NAME     J4G2 125
 '@BASEBOARD_FAB2_LIB.BASEBOARD_FAB2(SCH_1):PAGE45_I43@MSTR_SCONN.SCONN288_H44441004(CHIPS)':
 'VSS'<53>: CDS_PINID='VSS(53)';
NODE_NAME     J4G2 123
 '@BASEBOARD_FAB2_LIB.BASEBOARD_FAB2(SCH_1):PAGE45_I43@MSTR_SCONN.SCONN288_H44441004(CHIPS)':
 'VSS'<54>: CDS_PINID='VSS(54)';
NODE_NAME     J4G2 120
 '@BASEBOARD_FAB2_LIB.BASEBOARD_FAB2(SCH_1):PAGE45_I43@MSTR_SCONN.SCONN288_H44441004(CHIPS)':
 'VSS'<55>: CDS_PINID='VSS(55)';
NODE_NAME     J4G2 118
 '@BASEBOARD_FAB2_LIB.BASEBOARD_FAB2(SCH_1):PAGE45_I43@MSTR_SCONN.SCONN288_H44441004(CHIPS)':
 'VSS'<56>: CDS_PINID='VSS(56)';
NODE_NAME     J4G2 116
 '@BASEBOARD_FAB2_LIB.BASEBOARD_FAB2(SCH_1):PAGE45_I43@MSTR_SCONN.SCONN288_H44441004(CHIPS)':
 'VSS'<57>: CDS_PINID='VSS(57)';
NODE_NAME     J4G2 114
 '@BASEBOARD_FAB2_LIB.BASEBOARD_FAB2(SCH_1):PAGE45_I43@MSTR_SCONN.SCONN288_H44441004(CHIPS)':
 'VSS'<58>: CDS_PINID='VSS(58)';
NODE_NAME     J4G2 112
 '@BASEBOARD_FAB2_LIB.BASEBOARD_FAB2(SCH_1):PAGE45_I43@MSTR_SCONN.SCONN288_H44441004(CHIPS)':
 'VSS'<59>: CDS_PINID='VSS(59)';
NODE_NAME     J4G2 109
 '@BASEBOARD_FAB2_LIB.BASEBOARD_FAB2(SCH_1):PAGE45_I43@MSTR_SCONN.SCONN288_H44441004(CHIPS)':
 'VSS'<60>: CDS_PINID='VSS(60)';
NODE_NAME     J4G2 107
 '@BASEBOARD_FAB2_LIB.BASEBOARD_FAB2(SCH_1):PAGE45_I43@MSTR_SCONN.SCONN288_H44441004(CHIPS)':
 'VSS'<61>: CDS_PINID='VSS(61)';
NODE_NAME     J4G2 105
 '@BASEBOARD_FAB2_LIB.BASEBOARD_FAB2(SCH_1):PAGE45_I43@MSTR_SCONN.SCONN288_H44441004(CHIPS)':
 'VSS'<62>: CDS_PINID='VSS(62)';
NODE_NAME     J4G2 103
 '@BASEBOARD_FAB2_LIB.BASEBOARD_FAB2(SCH_1):PAGE45_I43@MSTR_SCONN.SCONN288_H44441004(CHIPS)':
 'VSS'<63>: CDS_PINID='VSS(63)';
NODE_NAME     J4G2 101
 '@BASEBOARD_FAB2_LIB.BASEBOARD_FAB2(SCH_1):PAGE45_I43@MSTR_SCONN.SCONN288_H44441004(CHIPS)':
 'VSS'<64>: CDS_PINID='VSS(64)';
NODE_NAME     J4G2 98
 '@BASEBOARD_FAB2_LIB.BASEBOARD_FAB2(SCH_1):PAGE45_I43@MSTR_SCONN.SCONN288_H44441004(CHIPS)':
 'VSS'<65>: CDS_PINID='VSS(65)';
NODE_NAME     J4G2 96
 '@BASEBOARD_FAB2_LIB.BASEBOARD_FAB2(SCH_1):PAGE45_I43@MSTR_SCONN.SCONN288_H44441004(CHIPS)':
 'VSS'<66>: CDS_PINID='VSS(66)';
NODE_NAME     J4G2 94
 '@BASEBOARD_FAB2_LIB.BASEBOARD_FAB2(SCH_1):PAGE45_I43@MSTR_SCONN.SCONN288_H44441004(CHIPS)':
 'VSS'<67>: CDS_PINID='VSS(67)';
NODE_NAME     J4G2 57
 '@BASEBOARD_FAB2_LIB.BASEBOARD_FAB2(SCH_1):PAGE45_I43@MSTR_SCONN.SCONN288_H44441004(CHIPS)':
 'VSS'<68>: CDS_PINID='VSS(68)';
NODE_NAME     J4G2 55
 '@BASEBOARD_FAB2_LIB.BASEBOARD_FAB2(SCH_1):PAGE45_I43@MSTR_SCONN.SCONN288_H44441004(CHIPS)':
 'VSS'<69>: CDS_PINID='VSS(69)';
NODE_NAME     J4G2 53
 '@BASEBOARD_FAB2_LIB.BASEBOARD_FAB2(SCH_1):PAGE45_I43@MSTR_SCONN.SCONN288_H44441004(CHIPS)':
 'VSS'<70>: CDS_PINID='VSS(70)';
NODE_NAME     J4G2 50
 '@BASEBOARD_FAB2_LIB.BASEBOARD_FAB2(SCH_1):PAGE45_I43@MSTR_SCONN.SCONN288_H44441004(CHIPS)':
 'VSS'<71>: CDS_PINID='VSS(71)';
NODE_NAME     J4G2 48
 '@BASEBOARD_FAB2_LIB.BASEBOARD_FAB2(SCH_1):PAGE45_I43@MSTR_SCONN.SCONN288_H44441004(CHIPS)':
 'VSS'<72>: CDS_PINID='VSS(72)';
NODE_NAME     J4G2 46
 '@BASEBOARD_FAB2_LIB.BASEBOARD_FAB2(SCH_1):PAGE45_I43@MSTR_SCONN.SCONN288_H44441004(CHIPS)':
 'VSS'<73>: CDS_PINID='VSS(73)';
NODE_NAME     J4G2 44
 '@BASEBOARD_FAB2_LIB.BASEBOARD_FAB2(SCH_1):PAGE45_I43@MSTR_SCONN.SCONN288_H44441004(CHIPS)':
 'VSS'<74>: CDS_PINID='VSS(74)';
NODE_NAME     J4G2 42
 '@BASEBOARD_FAB2_LIB.BASEBOARD_FAB2(SCH_1):PAGE45_I43@MSTR_SCONN.SCONN288_H44441004(CHIPS)':
 'VSS'<75>: CDS_PINID='VSS(75)';
NODE_NAME     J4G2 39
 '@BASEBOARD_FAB2_LIB.BASEBOARD_FAB2(SCH_1):PAGE45_I43@MSTR_SCONN.SCONN288_H44441004(CHIPS)':
 'VSS'<76>: CDS_PINID='VSS(76)';
NODE_NAME     J4G2 37
 '@BASEBOARD_FAB2_LIB.BASEBOARD_FAB2(SCH_1):PAGE45_I43@MSTR_SCONN.SCONN288_H44441004(CHIPS)':
 'VSS'<77>: CDS_PINID='VSS(77)';
NODE_NAME     J4G2 35
 '@BASEBOARD_FAB2_LIB.BASEBOARD_FAB2(SCH_1):PAGE45_I43@MSTR_SCONN.SCONN288_H44441004(CHIPS)':
 'VSS'<78>: CDS_PINID='VSS(78)';
NODE_NAME     J4G2 33
 '@BASEBOARD_FAB2_LIB.BASEBOARD_FAB2(SCH_1):PAGE45_I43@MSTR_SCONN.SCONN288_H44441004(CHIPS)':
 'VSS'<79>: CDS_PINID='VSS(79)';
NODE_NAME     J4G2 31
 '@BASEBOARD_FAB2_LIB.BASEBOARD_FAB2(SCH_1):PAGE45_I43@MSTR_SCONN.SCONN288_H44441004(CHIPS)':
 'VSS'<80>: CDS_PINID='VSS(80)';
NODE_NAME     J4G2 28
 '@BASEBOARD_FAB2_LIB.BASEBOARD_FAB2(SCH_1):PAGE45_I43@MSTR_SCONN.SCONN288_H44441004(CHIPS)':
 'VSS'<81>: CDS_PINID='VSS(81)';
NODE_NAME     J4G2 26
 '@BASEBOARD_FAB2_LIB.BASEBOARD_FAB2(SCH_1):PAGE45_I43@MSTR_SCONN.SCONN288_H44441004(CHIPS)':
 'VSS'<82>: CDS_PINID='VSS(82)';
NODE_NAME     J4G2 24
 '@BASEBOARD_FAB2_LIB.BASEBOARD_FAB2(SCH_1):PAGE45_I43@MSTR_SCONN.SCONN288_H44441004(CHIPS)':
 'VSS'<83>: CDS_PINID='VSS(83)';
NODE_NAME     J4G2 22
 '@BASEBOARD_FAB2_LIB.BASEBOARD_FAB2(SCH_1):PAGE45_I43@MSTR_SCONN.SCONN288_H44441004(CHIPS)':
 'VSS'<84>: CDS_PINID='VSS(84)';
NODE_NAME     J4G2 20
 '@BASEBOARD_FAB2_LIB.BASEBOARD_FAB2(SCH_1):PAGE45_I43@MSTR_SCONN.SCONN288_H44441004(CHIPS)':
 'VSS'<85>: CDS_PINID='VSS(85)';
NODE_NAME     J4G2 17
 '@BASEBOARD_FAB2_LIB.BASEBOARD_FAB2(SCH_1):PAGE45_I43@MSTR_SCONN.SCONN288_H44441004(CHIPS)':
 'VSS'<86>: CDS_PINID='VSS(86)';
NODE_NAME     J4G2 15
 '@BASEBOARD_FAB2_LIB.BASEBOARD_FAB2(SCH_1):PAGE45_I43@MSTR_SCONN.SCONN288_H44441004(CHIPS)':
 'VSS'<87>: CDS_PINID='VSS(87)';
NODE_NAME     J4G2 13
 '@BASEBOARD_FAB2_LIB.BASEBOARD_FAB2(SCH_1):PAGE45_I43@MSTR_SCONN.SCONN288_H44441004(CHIPS)':
 'VSS'<88>: CDS_PINID='VSS(88)';
NODE_NAME     J4G2 11
 '@BASEBOARD_FAB2_LIB.BASEBOARD_FAB2(SCH_1):PAGE45_I43@MSTR_SCONN.SCONN288_H44441004(CHIPS)':
 'VSS'<89>: CDS_PINID='VSS(89)';
NODE_NAME     J4G2 9
 '@BASEBOARD_FAB2_LIB.BASEBOARD_FAB2(SCH_1):PAGE45_I43@MSTR_SCONN.SCONN288_H44441004(CHIPS)':
 'VSS'<90>: CDS_PINID='VSS(90)';
NODE_NAME     J4G2 6
 '@BASEBOARD_FAB2_LIB.BASEBOARD_FAB2(SCH_1):PAGE45_I43@MSTR_SCONN.SCONN288_H44441004(CHIPS)':
 'VSS'<91>: CDS_PINID='VSS(91)';
NODE_NAME     J4G2 4
 '@BASEBOARD_FAB2_LIB.BASEBOARD_FAB2(SCH_1):PAGE45_I43@MSTR_SCONN.SCONN288_H44441004(CHIPS)':
 'VSS'<92>: CDS_PINID='VSS(92)';
NODE_NAME     J4G2 2
 '@BASEBOARD_FAB2_LIB.BASEBOARD_FAB2(SCH_1):PAGE45_I43@MSTR_SCONN.SCONN288_H44441004(CHIPS)':
 'VSS'<93>: CDS_PINID='VSS(93)';
NODE_NAME     J4G2 139
 '@BASEBOARD_FAB2_LIB.BASEBOARD_FAB2(SCH_1):PAGE45_I111@MSTR_SCONN.SCONN288_H44441004(CHIPS)':
 'SA'<0>: CDS_PINID='SA(0)';
NODE_NAME     J4G2 238
 '@BASEBOARD_FAB2_LIB.BASEBOARD_FAB2(SCH_1):PAGE45_I111@MSTR_SCONN.SCONN288_H44441004(CHIPS)':
 'SA'<2>: CDS_PINID='SA(2)';
NODE_NAME     C4G3 2
 '@BASEBOARD_FAB2_LIB.BASEBOARD_FAB2(SCH_1):PAGE45_I179@DEV_DISCRETE.CAP_A(CHIPS)':
 'B': CDS_PINID='B';
NODE_NAME     C6U9 2
 '@BASEBOARD_FAB2_LIB.BASEBOARD_FAB2(SCH_1):PAGE46_I5@DEV_DISCRETE.CAP_A(CHIPS)':
 'B': CDS_PINID='B';
NODE_NAME     J6U1 238
 '@BASEBOARD_FAB2_LIB.BASEBOARD_FAB2(SCH_1):PAGE46_I14@MSTR_SCONN.SCONN288_H44441003(CHIPS)':
 'SA'<2>: CDS_PINID='SA(2)';
NODE_NAME     J6U1 283
 '@BASEBOARD_FAB2_LIB.BASEBOARD_FAB2(SCH_1):PAGE46_I138@MSTR_SCONN.SCONN288_H44441003(CHIPS)':
 'VSS'<0>: CDS_PINID='VSS(0)';
NODE_NAME     J6U1 281
 '@BASEBOARD_FAB2_LIB.BASEBOARD_FAB2(SCH_1):PAGE46_I138@MSTR_SCONN.SCONN288_H44441003(CHIPS)':
 'VSS'<1>: CDS_PINID='VSS(1)';
NODE_NAME     J6U1 279
 '@BASEBOARD_FAB2_LIB.BASEBOARD_FAB2(SCH_1):PAGE46_I138@MSTR_SCONN.SCONN288_H44441003(CHIPS)':
 'VSS'<2>: CDS_PINID='VSS(2)';
NODE_NAME     J6U1 276
 '@BASEBOARD_FAB2_LIB.BASEBOARD_FAB2(SCH_1):PAGE46_I138@MSTR_SCONN.SCONN288_H44441003(CHIPS)':
 'VSS'<3>: CDS_PINID='VSS(3)';
NODE_NAME     J6U1 274
 '@BASEBOARD_FAB2_LIB.BASEBOARD_FAB2(SCH_1):PAGE46_I138@MSTR_SCONN.SCONN288_H44441003(CHIPS)':
 'VSS'<4>: CDS_PINID='VSS(4)';
NODE_NAME     J6U1 272
 '@BASEBOARD_FAB2_LIB.BASEBOARD_FAB2(SCH_1):PAGE46_I138@MSTR_SCONN.SCONN288_H44441003(CHIPS)':
 'VSS'<5>: CDS_PINID='VSS(5)';
NODE_NAME     J6U1 270
 '@BASEBOARD_FAB2_LIB.BASEBOARD_FAB2(SCH_1):PAGE46_I138@MSTR_SCONN.SCONN288_H44441003(CHIPS)':
 'VSS'<6>: CDS_PINID='VSS(6)';
NODE_NAME     J6U1 268
 '@BASEBOARD_FAB2_LIB.BASEBOARD_FAB2(SCH_1):PAGE46_I138@MSTR_SCONN.SCONN288_H44441003(CHIPS)':
 'VSS'<7>: CDS_PINID='VSS(7)';
NODE_NAME     J6U1 265
 '@BASEBOARD_FAB2_LIB.BASEBOARD_FAB2(SCH_1):PAGE46_I138@MSTR_SCONN.SCONN288_H44441003(CHIPS)':
 'VSS'<8>: CDS_PINID='VSS(8)';
NODE_NAME     J6U1 263
 '@BASEBOARD_FAB2_LIB.BASEBOARD_FAB2(SCH_1):PAGE46_I138@MSTR_SCONN.SCONN288_H44441003(CHIPS)':
 'VSS'<9>: CDS_PINID='VSS(9)';
NODE_NAME     J6U1 261
 '@BASEBOARD_FAB2_LIB.BASEBOARD_FAB2(SCH_1):PAGE46_I138@MSTR_SCONN.SCONN288_H44441003(CHIPS)':
 'VSS'<10>: CDS_PINID='VSS(10)';
NODE_NAME     J6U1 259
 '@BASEBOARD_FAB2_LIB.BASEBOARD_FAB2(SCH_1):PAGE46_I138@MSTR_SCONN.SCONN288_H44441003(CHIPS)':
 'VSS'<11>: CDS_PINID='VSS(11)';
NODE_NAME     J6U1 257
 '@BASEBOARD_FAB2_LIB.BASEBOARD_FAB2(SCH_1):PAGE46_I138@MSTR_SCONN.SCONN288_H44441003(CHIPS)':
 'VSS'<12>: CDS_PINID='VSS(12)';
NODE_NAME     J6U1 254
 '@BASEBOARD_FAB2_LIB.BASEBOARD_FAB2(SCH_1):PAGE46_I138@MSTR_SCONN.SCONN288_H44441003(CHIPS)':
 'VSS'<13>: CDS_PINID='VSS(13)';
NODE_NAME     J6U1 252
 '@BASEBOARD_FAB2_LIB.BASEBOARD_FAB2(SCH_1):PAGE46_I138@MSTR_SCONN.SCONN288_H44441003(CHIPS)':
 'VSS'<14>: CDS_PINID='VSS(14)';
NODE_NAME     J6U1 250
 '@BASEBOARD_FAB2_LIB.BASEBOARD_FAB2(SCH_1):PAGE46_I138@MSTR_SCONN.SCONN288_H44441003(CHIPS)':
 'VSS'<15>: CDS_PINID='VSS(15)';
NODE_NAME     J6U1 248
 '@BASEBOARD_FAB2_LIB.BASEBOARD_FAB2(SCH_1):PAGE46_I138@MSTR_SCONN.SCONN288_H44441003(CHIPS)':
 'VSS'<16>: CDS_PINID='VSS(16)';
NODE_NAME     J6U1 246
 '@BASEBOARD_FAB2_LIB.BASEBOARD_FAB2(SCH_1):PAGE46_I138@MSTR_SCONN.SCONN288_H44441003(CHIPS)':
 'VSS'<17>: CDS_PINID='VSS(17)';
NODE_NAME     J6U1 243
 '@BASEBOARD_FAB2_LIB.BASEBOARD_FAB2(SCH_1):PAGE46_I138@MSTR_SCONN.SCONN288_H44441003(CHIPS)':
 'VSS'<18>: CDS_PINID='VSS(18)';
NODE_NAME     J6U1 241
 '@BASEBOARD_FAB2_LIB.BASEBOARD_FAB2(SCH_1):PAGE46_I138@MSTR_SCONN.SCONN288_H44441003(CHIPS)':
 'VSS'<19>: CDS_PINID='VSS(19)';
NODE_NAME     J6U1 239
 '@BASEBOARD_FAB2_LIB.BASEBOARD_FAB2(SCH_1):PAGE46_I138@MSTR_SCONN.SCONN288_H44441003(CHIPS)':
 'VSS'<20>: CDS_PINID='VSS(20)';
NODE_NAME     J6U1 202
 '@BASEBOARD_FAB2_LIB.BASEBOARD_FAB2(SCH_1):PAGE46_I138@MSTR_SCONN.SCONN288_H44441003(CHIPS)':
 'VSS'<21>: CDS_PINID='VSS(21)';
NODE_NAME     J6U1 200
 '@BASEBOARD_FAB2_LIB.BASEBOARD_FAB2(SCH_1):PAGE46_I138@MSTR_SCONN.SCONN288_H44441003(CHIPS)':
 'VSS'<22>: CDS_PINID='VSS(22)';
NODE_NAME     J6U1 198
 '@BASEBOARD_FAB2_LIB.BASEBOARD_FAB2(SCH_1):PAGE46_I138@MSTR_SCONN.SCONN288_H44441003(CHIPS)':
 'VSS'<23>: CDS_PINID='VSS(23)';
NODE_NAME     J6U1 195
 '@BASEBOARD_FAB2_LIB.BASEBOARD_FAB2(SCH_1):PAGE46_I138@MSTR_SCONN.SCONN288_H44441003(CHIPS)':
 'VSS'<24>: CDS_PINID='VSS(24)';
NODE_NAME     J6U1 193
 '@BASEBOARD_FAB2_LIB.BASEBOARD_FAB2(SCH_1):PAGE46_I138@MSTR_SCONN.SCONN288_H44441003(CHIPS)':
 'VSS'<25>: CDS_PINID='VSS(25)';
NODE_NAME     J6U1 191
 '@BASEBOARD_FAB2_LIB.BASEBOARD_FAB2(SCH_1):PAGE46_I138@MSTR_SCONN.SCONN288_H44441003(CHIPS)':
 'VSS'<26>: CDS_PINID='VSS(26)';
NODE_NAME     J6U1 189
 '@BASEBOARD_FAB2_LIB.BASEBOARD_FAB2(SCH_1):PAGE46_I138@MSTR_SCONN.SCONN288_H44441003(CHIPS)':
 'VSS'<27>: CDS_PINID='VSS(27)';
NODE_NAME     J6U1 187
 '@BASEBOARD_FAB2_LIB.BASEBOARD_FAB2(SCH_1):PAGE46_I138@MSTR_SCONN.SCONN288_H44441003(CHIPS)':
 'VSS'<28>: CDS_PINID='VSS(28)';
NODE_NAME     J6U1 184
 '@BASEBOARD_FAB2_LIB.BASEBOARD_FAB2(SCH_1):PAGE46_I138@MSTR_SCONN.SCONN288_H44441003(CHIPS)':
 'VSS'<29>: CDS_PINID='VSS(29)';
NODE_NAME     J6U1 182
 '@BASEBOARD_FAB2_LIB.BASEBOARD_FAB2(SCH_1):PAGE46_I138@MSTR_SCONN.SCONN288_H44441003(CHIPS)':
 'VSS'<30>: CDS_PINID='VSS(30)';
NODE_NAME     J6U1 180
 '@BASEBOARD_FAB2_LIB.BASEBOARD_FAB2(SCH_1):PAGE46_I138@MSTR_SCONN.SCONN288_H44441003(CHIPS)':
 'VSS'<31>: CDS_PINID='VSS(31)';
NODE_NAME     J6U1 178
 '@BASEBOARD_FAB2_LIB.BASEBOARD_FAB2(SCH_1):PAGE46_I138@MSTR_SCONN.SCONN288_H44441003(CHIPS)':
 'VSS'<32>: CDS_PINID='VSS(32)';
NODE_NAME     J6U1 176
 '@BASEBOARD_FAB2_LIB.BASEBOARD_FAB2(SCH_1):PAGE46_I138@MSTR_SCONN.SCONN288_H44441003(CHIPS)':
 'VSS'<33>: CDS_PINID='VSS(33)';
NODE_NAME     J6U1 173
 '@BASEBOARD_FAB2_LIB.BASEBOARD_FAB2(SCH_1):PAGE46_I138@MSTR_SCONN.SCONN288_H44441003(CHIPS)':
 'VSS'<34>: CDS_PINID='VSS(34)';
NODE_NAME     J6U1 171
 '@BASEBOARD_FAB2_LIB.BASEBOARD_FAB2(SCH_1):PAGE46_I138@MSTR_SCONN.SCONN288_H44441003(CHIPS)':
 'VSS'<35>: CDS_PINID='VSS(35)';
NODE_NAME     J6U1 169
 '@BASEBOARD_FAB2_LIB.BASEBOARD_FAB2(SCH_1):PAGE46_I138@MSTR_SCONN.SCONN288_H44441003(CHIPS)':
 'VSS'<36>: CDS_PINID='VSS(36)';
NODE_NAME     J6U1 167
 '@BASEBOARD_FAB2_LIB.BASEBOARD_FAB2(SCH_1):PAGE46_I138@MSTR_SCONN.SCONN288_H44441003(CHIPS)':
 'VSS'<37>: CDS_PINID='VSS(37)';
NODE_NAME     J6U1 165
 '@BASEBOARD_FAB2_LIB.BASEBOARD_FAB2(SCH_1):PAGE46_I138@MSTR_SCONN.SCONN288_H44441003(CHIPS)':
 'VSS'<38>: CDS_PINID='VSS(38)';
NODE_NAME     J6U1 162
 '@BASEBOARD_FAB2_LIB.BASEBOARD_FAB2(SCH_1):PAGE46_I138@MSTR_SCONN.SCONN288_H44441003(CHIPS)':
 'VSS'<39>: CDS_PINID='VSS(39)';
NODE_NAME     J6U1 160
 '@BASEBOARD_FAB2_LIB.BASEBOARD_FAB2(SCH_1):PAGE46_I138@MSTR_SCONN.SCONN288_H44441003(CHIPS)':
 'VSS'<40>: CDS_PINID='VSS(40)';
NODE_NAME     J6U1 158
 '@BASEBOARD_FAB2_LIB.BASEBOARD_FAB2(SCH_1):PAGE46_I138@MSTR_SCONN.SCONN288_H44441003(CHIPS)':
 'VSS'<41>: CDS_PINID='VSS(41)';
NODE_NAME     J6U1 156
 '@BASEBOARD_FAB2_LIB.BASEBOARD_FAB2(SCH_1):PAGE46_I138@MSTR_SCONN.SCONN288_H44441003(CHIPS)':
 'VSS'<42>: CDS_PINID='VSS(42)';
NODE_NAME     J6U1 154
 '@BASEBOARD_FAB2_LIB.BASEBOARD_FAB2(SCH_1):PAGE46_I138@MSTR_SCONN.SCONN288_H44441003(CHIPS)':
 'VSS'<43>: CDS_PINID='VSS(43)';
NODE_NAME     J6U1 151
 '@BASEBOARD_FAB2_LIB.BASEBOARD_FAB2(SCH_1):PAGE46_I138@MSTR_SCONN.SCONN288_H44441003(CHIPS)':
 'VSS'<44>: CDS_PINID='VSS(44)';
NODE_NAME     J6U1 149
 '@BASEBOARD_FAB2_LIB.BASEBOARD_FAB2(SCH_1):PAGE46_I138@MSTR_SCONN.SCONN288_H44441003(CHIPS)':
 'VSS'<45>: CDS_PINID='VSS(45)';
NODE_NAME     J6U1 147
 '@BASEBOARD_FAB2_LIB.BASEBOARD_FAB2(SCH_1):PAGE46_I138@MSTR_SCONN.SCONN288_H44441003(CHIPS)':
 'VSS'<46>: CDS_PINID='VSS(46)';
NODE_NAME     J6U1 138
 '@BASEBOARD_FAB2_LIB.BASEBOARD_FAB2(SCH_1):PAGE46_I138@MSTR_SCONN.SCONN288_H44441003(CHIPS)':
 'VSS'<47>: CDS_PINID='VSS(47)';
NODE_NAME     J6U1 136
 '@BASEBOARD_FAB2_LIB.BASEBOARD_FAB2(SCH_1):PAGE46_I138@MSTR_SCONN.SCONN288_H44441003(CHIPS)':
 'VSS'<48>: CDS_PINID='VSS(48)';
NODE_NAME     J6U1 134
 '@BASEBOARD_FAB2_LIB.BASEBOARD_FAB2(SCH_1):PAGE46_I138@MSTR_SCONN.SCONN288_H44441003(CHIPS)':
 'VSS'<49>: CDS_PINID='VSS(49)';
NODE_NAME     J6U1 131
 '@BASEBOARD_FAB2_LIB.BASEBOARD_FAB2(SCH_1):PAGE46_I138@MSTR_SCONN.SCONN288_H44441003(CHIPS)':
 'VSS'<50>: CDS_PINID='VSS(50)';
NODE_NAME     J6U1 129
 '@BASEBOARD_FAB2_LIB.BASEBOARD_FAB2(SCH_1):PAGE46_I138@MSTR_SCONN.SCONN288_H44441003(CHIPS)':
 'VSS'<51>: CDS_PINID='VSS(51)';
NODE_NAME     J6U1 127
 '@BASEBOARD_FAB2_LIB.BASEBOARD_FAB2(SCH_1):PAGE46_I138@MSTR_SCONN.SCONN288_H44441003(CHIPS)':
 'VSS'<52>: CDS_PINID='VSS(52)';
NODE_NAME     J6U1 125
 '@BASEBOARD_FAB2_LIB.BASEBOARD_FAB2(SCH_1):PAGE46_I138@MSTR_SCONN.SCONN288_H44441003(CHIPS)':
 'VSS'<53>: CDS_PINID='VSS(53)';
NODE_NAME     J6U1 123
 '@BASEBOARD_FAB2_LIB.BASEBOARD_FAB2(SCH_1):PAGE46_I138@MSTR_SCONN.SCONN288_H44441003(CHIPS)':
 'VSS'<54>: CDS_PINID='VSS(54)';
NODE_NAME     J6U1 120
 '@BASEBOARD_FAB2_LIB.BASEBOARD_FAB2(SCH_1):PAGE46_I138@MSTR_SCONN.SCONN288_H44441003(CHIPS)':
 'VSS'<55>: CDS_PINID='VSS(55)';
NODE_NAME     J6U1 118
 '@BASEBOARD_FAB2_LIB.BASEBOARD_FAB2(SCH_1):PAGE46_I138@MSTR_SCONN.SCONN288_H44441003(CHIPS)':
 'VSS'<56>: CDS_PINID='VSS(56)';
NODE_NAME     J6U1 116
 '@BASEBOARD_FAB2_LIB.BASEBOARD_FAB2(SCH_1):PAGE46_I138@MSTR_SCONN.SCONN288_H44441003(CHIPS)':
 'VSS'<57>: CDS_PINID='VSS(57)';
NODE_NAME     J6U1 114
 '@BASEBOARD_FAB2_LIB.BASEBOARD_FAB2(SCH_1):PAGE46_I138@MSTR_SCONN.SCONN288_H44441003(CHIPS)':
 'VSS'<58>: CDS_PINID='VSS(58)';
NODE_NAME     J6U1 112
 '@BASEBOARD_FAB2_LIB.BASEBOARD_FAB2(SCH_1):PAGE46_I138@MSTR_SCONN.SCONN288_H44441003(CHIPS)':
 'VSS'<59>: CDS_PINID='VSS(59)';
NODE_NAME     J6U1 109
 '@BASEBOARD_FAB2_LIB.BASEBOARD_FAB2(SCH_1):PAGE46_I138@MSTR_SCONN.SCONN288_H44441003(CHIPS)':
 'VSS'<60>: CDS_PINID='VSS(60)';
NODE_NAME     J6U1 107
 '@BASEBOARD_FAB2_LIB.BASEBOARD_FAB2(SCH_1):PAGE46_I138@MSTR_SCONN.SCONN288_H44441003(CHIPS)':
 'VSS'<61>: CDS_PINID='VSS(61)';
NODE_NAME     J6U1 105
 '@BASEBOARD_FAB2_LIB.BASEBOARD_FAB2(SCH_1):PAGE46_I138@MSTR_SCONN.SCONN288_H44441003(CHIPS)':
 'VSS'<62>: CDS_PINID='VSS(62)';
NODE_NAME     J6U1 103
 '@BASEBOARD_FAB2_LIB.BASEBOARD_FAB2(SCH_1):PAGE46_I138@MSTR_SCONN.SCONN288_H44441003(CHIPS)':
 'VSS'<63>: CDS_PINID='VSS(63)';
NODE_NAME     J6U1 101
 '@BASEBOARD_FAB2_LIB.BASEBOARD_FAB2(SCH_1):PAGE46_I138@MSTR_SCONN.SCONN288_H44441003(CHIPS)':
 'VSS'<64>: CDS_PINID='VSS(64)';
NODE_NAME     J6U1 98
 '@BASEBOARD_FAB2_LIB.BASEBOARD_FAB2(SCH_1):PAGE46_I138@MSTR_SCONN.SCONN288_H44441003(CHIPS)':
 'VSS'<65>: CDS_PINID='VSS(65)';
NODE_NAME     J6U1 96
 '@BASEBOARD_FAB2_LIB.BASEBOARD_FAB2(SCH_1):PAGE46_I138@MSTR_SCONN.SCONN288_H44441003(CHIPS)':
 'VSS'<66>: CDS_PINID='VSS(66)';
NODE_NAME     J6U1 94
 '@BASEBOARD_FAB2_LIB.BASEBOARD_FAB2(SCH_1):PAGE46_I138@MSTR_SCONN.SCONN288_H44441003(CHIPS)':
 'VSS'<67>: CDS_PINID='VSS(67)';
NODE_NAME     J6U1 57
 '@BASEBOARD_FAB2_LIB.BASEBOARD_FAB2(SCH_1):PAGE46_I138@MSTR_SCONN.SCONN288_H44441003(CHIPS)':
 'VSS'<68>: CDS_PINID='VSS(68)';
NODE_NAME     J6U1 55
 '@BASEBOARD_FAB2_LIB.BASEBOARD_FAB2(SCH_1):PAGE46_I138@MSTR_SCONN.SCONN288_H44441003(CHIPS)':
 'VSS'<69>: CDS_PINID='VSS(69)';
NODE_NAME     J6U1 53
 '@BASEBOARD_FAB2_LIB.BASEBOARD_FAB2(SCH_1):PAGE46_I138@MSTR_SCONN.SCONN288_H44441003(CHIPS)':
 'VSS'<70>: CDS_PINID='VSS(70)';
NODE_NAME     J6U1 50
 '@BASEBOARD_FAB2_LIB.BASEBOARD_FAB2(SCH_1):PAGE46_I138@MSTR_SCONN.SCONN288_H44441003(CHIPS)':
 'VSS'<71>: CDS_PINID='VSS(71)';
NODE_NAME     J6U1 48
 '@BASEBOARD_FAB2_LIB.BASEBOARD_FAB2(SCH_1):PAGE46_I138@MSTR_SCONN.SCONN288_H44441003(CHIPS)':
 'VSS'<72>: CDS_PINID='VSS(72)';
NODE_NAME     J6U1 46
 '@BASEBOARD_FAB2_LIB.BASEBOARD_FAB2(SCH_1):PAGE46_I138@MSTR_SCONN.SCONN288_H44441003(CHIPS)':
 'VSS'<73>: CDS_PINID='VSS(73)';
NODE_NAME     J6U1 44
 '@BASEBOARD_FAB2_LIB.BASEBOARD_FAB2(SCH_1):PAGE46_I138@MSTR_SCONN.SCONN288_H44441003(CHIPS)':
 'VSS'<74>: CDS_PINID='VSS(74)';
NODE_NAME     J6U1 42
 '@BASEBOARD_FAB2_LIB.BASEBOARD_FAB2(SCH_1):PAGE46_I138@MSTR_SCONN.SCONN288_H44441003(CHIPS)':
 'VSS'<75>: CDS_PINID='VSS(75)';
NODE_NAME     J6U1 39
 '@BASEBOARD_FAB2_LIB.BASEBOARD_FAB2(SCH_1):PAGE46_I138@MSTR_SCONN.SCONN288_H44441003(CHIPS)':
 'VSS'<76>: CDS_PINID='VSS(76)';
NODE_NAME     J6U1 37
 '@BASEBOARD_FAB2_LIB.BASEBOARD_FAB2(SCH_1):PAGE46_I138@MSTR_SCONN.SCONN288_H44441003(CHIPS)':
 'VSS'<77>: CDS_PINID='VSS(77)';
NODE_NAME     J6U1 35
 '@BASEBOARD_FAB2_LIB.BASEBOARD_FAB2(SCH_1):PAGE46_I138@MSTR_SCONN.SCONN288_H44441003(CHIPS)':
 'VSS'<78>: CDS_PINID='VSS(78)';
NODE_NAME     J6U1 33
 '@BASEBOARD_FAB2_LIB.BASEBOARD_FAB2(SCH_1):PAGE46_I138@MSTR_SCONN.SCONN288_H44441003(CHIPS)':
 'VSS'<79>: CDS_PINID='VSS(79)';
NODE_NAME     J6U1 31
 '@BASEBOARD_FAB2_LIB.BASEBOARD_FAB2(SCH_1):PAGE46_I138@MSTR_SCONN.SCONN288_H44441003(CHIPS)':
 'VSS'<80>: CDS_PINID='VSS(80)';
NODE_NAME     J6U1 28
 '@BASEBOARD_FAB2_LIB.BASEBOARD_FAB2(SCH_1):PAGE46_I138@MSTR_SCONN.SCONN288_H44441003(CHIPS)':
 'VSS'<81>: CDS_PINID='VSS(81)';
NODE_NAME     J6U1 26
 '@BASEBOARD_FAB2_LIB.BASEBOARD_FAB2(SCH_1):PAGE46_I138@MSTR_SCONN.SCONN288_H44441003(CHIPS)':
 'VSS'<82>: CDS_PINID='VSS(82)';
NODE_NAME     J6U1 24
 '@BASEBOARD_FAB2_LIB.BASEBOARD_FAB2(SCH_1):PAGE46_I138@MSTR_SCONN.SCONN288_H44441003(CHIPS)':
 'VSS'<83>: CDS_PINID='VSS(83)';
NODE_NAME     J6U1 22
 '@BASEBOARD_FAB2_LIB.BASEBOARD_FAB2(SCH_1):PAGE46_I138@MSTR_SCONN.SCONN288_H44441003(CHIPS)':
 'VSS'<84>: CDS_PINID='VSS(84)';
NODE_NAME     J6U1 20
 '@BASEBOARD_FAB2_LIB.BASEBOARD_FAB2(SCH_1):PAGE46_I138@MSTR_SCONN.SCONN288_H44441003(CHIPS)':
 'VSS'<85>: CDS_PINID='VSS(85)';
NODE_NAME     J6U1 17
 '@BASEBOARD_FAB2_LIB.BASEBOARD_FAB2(SCH_1):PAGE46_I138@MSTR_SCONN.SCONN288_H44441003(CHIPS)':
 'VSS'<86>: CDS_PINID='VSS(86)';
NODE_NAME     J6U1 15
 '@BASEBOARD_FAB2_LIB.BASEBOARD_FAB2(SCH_1):PAGE46_I138@MSTR_SCONN.SCONN288_H44441003(CHIPS)':
 'VSS'<87>: CDS_PINID='VSS(87)';
NODE_NAME     J6U1 13
 '@BASEBOARD_FAB2_LIB.BASEBOARD_FAB2(SCH_1):PAGE46_I138@MSTR_SCONN.SCONN288_H44441003(CHIPS)':
 'VSS'<88>: CDS_PINID='VSS(88)';
NODE_NAME     J6U1 11
 '@BASEBOARD_FAB2_LIB.BASEBOARD_FAB2(SCH_1):PAGE46_I138@MSTR_SCONN.SCONN288_H44441003(CHIPS)':
 'VSS'<89>: CDS_PINID='VSS(89)';
NODE_NAME     J6U1 9
 '@BASEBOARD_FAB2_LIB.BASEBOARD_FAB2(SCH_1):PAGE46_I138@MSTR_SCONN.SCONN288_H44441003(CHIPS)':
 'VSS'<90>: CDS_PINID='VSS(90)';
NODE_NAME     J6U1 6
 '@BASEBOARD_FAB2_LIB.BASEBOARD_FAB2(SCH_1):PAGE46_I138@MSTR_SCONN.SCONN288_H44441003(CHIPS)':
 'VSS'<91>: CDS_PINID='VSS(91)';
NODE_NAME     J6U1 4
 '@BASEBOARD_FAB2_LIB.BASEBOARD_FAB2(SCH_1):PAGE46_I138@MSTR_SCONN.SCONN288_H44441003(CHIPS)':
 'VSS'<92>: CDS_PINID='VSS(92)';
NODE_NAME     J6U1 2
 '@BASEBOARD_FAB2_LIB.BASEBOARD_FAB2(SCH_1):PAGE46_I138@MSTR_SCONN.SCONN288_H44441003(CHIPS)':
 'VSS'<93>: CDS_PINID='VSS(93)';
NODE_NAME     J4G3 283
 '@BASEBOARD_FAB2_LIB.BASEBOARD_FAB2(SCH_1):PAGE47_I43@MSTR_SCONN.SCONN288_H44441004(CHIPS)':
 'VSS'<0>: CDS_PINID='VSS(0)';
NODE_NAME     J4G3 281
 '@BASEBOARD_FAB2_LIB.BASEBOARD_FAB2(SCH_1):PAGE47_I43@MSTR_SCONN.SCONN288_H44441004(CHIPS)':
 'VSS'<1>: CDS_PINID='VSS(1)';
NODE_NAME     J4G3 279
 '@BASEBOARD_FAB2_LIB.BASEBOARD_FAB2(SCH_1):PAGE47_I43@MSTR_SCONN.SCONN288_H44441004(CHIPS)':
 'VSS'<2>: CDS_PINID='VSS(2)';
NODE_NAME     J4G3 276
 '@BASEBOARD_FAB2_LIB.BASEBOARD_FAB2(SCH_1):PAGE47_I43@MSTR_SCONN.SCONN288_H44441004(CHIPS)':
 'VSS'<3>: CDS_PINID='VSS(3)';
NODE_NAME     J4G3 274
 '@BASEBOARD_FAB2_LIB.BASEBOARD_FAB2(SCH_1):PAGE47_I43@MSTR_SCONN.SCONN288_H44441004(CHIPS)':
 'VSS'<4>: CDS_PINID='VSS(4)';
NODE_NAME     J4G3 272
 '@BASEBOARD_FAB2_LIB.BASEBOARD_FAB2(SCH_1):PAGE47_I43@MSTR_SCONN.SCONN288_H44441004(CHIPS)':
 'VSS'<5>: CDS_PINID='VSS(5)';
NODE_NAME     J4G3 270
 '@BASEBOARD_FAB2_LIB.BASEBOARD_FAB2(SCH_1):PAGE47_I43@MSTR_SCONN.SCONN288_H44441004(CHIPS)':
 'VSS'<6>: CDS_PINID='VSS(6)';
NODE_NAME     J4G3 268
 '@BASEBOARD_FAB2_LIB.BASEBOARD_FAB2(SCH_1):PAGE47_I43@MSTR_SCONN.SCONN288_H44441004(CHIPS)':
 'VSS'<7>: CDS_PINID='VSS(7)';
NODE_NAME     J4G3 265
 '@BASEBOARD_FAB2_LIB.BASEBOARD_FAB2(SCH_1):PAGE47_I43@MSTR_SCONN.SCONN288_H44441004(CHIPS)':
 'VSS'<8>: CDS_PINID='VSS(8)';
NODE_NAME     J4G3 263
 '@BASEBOARD_FAB2_LIB.BASEBOARD_FAB2(SCH_1):PAGE47_I43@MSTR_SCONN.SCONN288_H44441004(CHIPS)':
 'VSS'<9>: CDS_PINID='VSS(9)';
NODE_NAME     J4G3 261
 '@BASEBOARD_FAB2_LIB.BASEBOARD_FAB2(SCH_1):PAGE47_I43@MSTR_SCONN.SCONN288_H44441004(CHIPS)':
 'VSS'<10>: CDS_PINID='VSS(10)';
NODE_NAME     J4G3 259
 '@BASEBOARD_FAB2_LIB.BASEBOARD_FAB2(SCH_1):PAGE47_I43@MSTR_SCONN.SCONN288_H44441004(CHIPS)':
 'VSS'<11>: CDS_PINID='VSS(11)';
NODE_NAME     J4G3 257
 '@BASEBOARD_FAB2_LIB.BASEBOARD_FAB2(SCH_1):PAGE47_I43@MSTR_SCONN.SCONN288_H44441004(CHIPS)':
 'VSS'<12>: CDS_PINID='VSS(12)';
NODE_NAME     J4G3 254
 '@BASEBOARD_FAB2_LIB.BASEBOARD_FAB2(SCH_1):PAGE47_I43@MSTR_SCONN.SCONN288_H44441004(CHIPS)':
 'VSS'<13>: CDS_PINID='VSS(13)';
NODE_NAME     J4G3 252
 '@BASEBOARD_FAB2_LIB.BASEBOARD_FAB2(SCH_1):PAGE47_I43@MSTR_SCONN.SCONN288_H44441004(CHIPS)':
 'VSS'<14>: CDS_PINID='VSS(14)';
NODE_NAME     J4G3 250
 '@BASEBOARD_FAB2_LIB.BASEBOARD_FAB2(SCH_1):PAGE47_I43@MSTR_SCONN.SCONN288_H44441004(CHIPS)':
 'VSS'<15>: CDS_PINID='VSS(15)';
NODE_NAME     J4G3 248
 '@BASEBOARD_FAB2_LIB.BASEBOARD_FAB2(SCH_1):PAGE47_I43@MSTR_SCONN.SCONN288_H44441004(CHIPS)':
 'VSS'<16>: CDS_PINID='VSS(16)';
NODE_NAME     J4G3 246
 '@BASEBOARD_FAB2_LIB.BASEBOARD_FAB2(SCH_1):PAGE47_I43@MSTR_SCONN.SCONN288_H44441004(CHIPS)':
 'VSS'<17>: CDS_PINID='VSS(17)';
NODE_NAME     J4G3 243
 '@BASEBOARD_FAB2_LIB.BASEBOARD_FAB2(SCH_1):PAGE47_I43@MSTR_SCONN.SCONN288_H44441004(CHIPS)':
 'VSS'<18>: CDS_PINID='VSS(18)';
NODE_NAME     J4G3 241
 '@BASEBOARD_FAB2_LIB.BASEBOARD_FAB2(SCH_1):PAGE47_I43@MSTR_SCONN.SCONN288_H44441004(CHIPS)':
 'VSS'<19>: CDS_PINID='VSS(19)';
NODE_NAME     J4G3 239
 '@BASEBOARD_FAB2_LIB.BASEBOARD_FAB2(SCH_1):PAGE47_I43@MSTR_SCONN.SCONN288_H44441004(CHIPS)':
 'VSS'<20>: CDS_PINID='VSS(20)';
NODE_NAME     J4G3 202
 '@BASEBOARD_FAB2_LIB.BASEBOARD_FAB2(SCH_1):PAGE47_I43@MSTR_SCONN.SCONN288_H44441004(CHIPS)':
 'VSS'<21>: CDS_PINID='VSS(21)';
NODE_NAME     J4G3 200
 '@BASEBOARD_FAB2_LIB.BASEBOARD_FAB2(SCH_1):PAGE47_I43@MSTR_SCONN.SCONN288_H44441004(CHIPS)':
 'VSS'<22>: CDS_PINID='VSS(22)';
NODE_NAME     J4G3 198
 '@BASEBOARD_FAB2_LIB.BASEBOARD_FAB2(SCH_1):PAGE47_I43@MSTR_SCONN.SCONN288_H44441004(CHIPS)':
 'VSS'<23>: CDS_PINID='VSS(23)';
NODE_NAME     J4G3 195
 '@BASEBOARD_FAB2_LIB.BASEBOARD_FAB2(SCH_1):PAGE47_I43@MSTR_SCONN.SCONN288_H44441004(CHIPS)':
 'VSS'<24>: CDS_PINID='VSS(24)';
NODE_NAME     J4G3 193
 '@BASEBOARD_FAB2_LIB.BASEBOARD_FAB2(SCH_1):PAGE47_I43@MSTR_SCONN.SCONN288_H44441004(CHIPS)':
 'VSS'<25>: CDS_PINID='VSS(25)';
NODE_NAME     J4G3 191
 '@BASEBOARD_FAB2_LIB.BASEBOARD_FAB2(SCH_1):PAGE47_I43@MSTR_SCONN.SCONN288_H44441004(CHIPS)':
 'VSS'<26>: CDS_PINID='VSS(26)';
NODE_NAME     J4G3 189
 '@BASEBOARD_FAB2_LIB.BASEBOARD_FAB2(SCH_1):PAGE47_I43@MSTR_SCONN.SCONN288_H44441004(CHIPS)':
 'VSS'<27>: CDS_PINID='VSS(27)';
NODE_NAME     J4G3 187
 '@BASEBOARD_FAB2_LIB.BASEBOARD_FAB2(SCH_1):PAGE47_I43@MSTR_SCONN.SCONN288_H44441004(CHIPS)':
 'VSS'<28>: CDS_PINID='VSS(28)';
NODE_NAME     J4G3 184
 '@BASEBOARD_FAB2_LIB.BASEBOARD_FAB2(SCH_1):PAGE47_I43@MSTR_SCONN.SCONN288_H44441004(CHIPS)':
 'VSS'<29>: CDS_PINID='VSS(29)';
NODE_NAME     J4G3 182
 '@BASEBOARD_FAB2_LIB.BASEBOARD_FAB2(SCH_1):PAGE47_I43@MSTR_SCONN.SCONN288_H44441004(CHIPS)':
 'VSS'<30>: CDS_PINID='VSS(30)';
NODE_NAME     J4G3 180
 '@BASEBOARD_FAB2_LIB.BASEBOARD_FAB2(SCH_1):PAGE47_I43@MSTR_SCONN.SCONN288_H44441004(CHIPS)':
 'VSS'<31>: CDS_PINID='VSS(31)';
NODE_NAME     J4G3 178
 '@BASEBOARD_FAB2_LIB.BASEBOARD_FAB2(SCH_1):PAGE47_I43@MSTR_SCONN.SCONN288_H44441004(CHIPS)':
 'VSS'<32>: CDS_PINID='VSS(32)';
NODE_NAME     J4G3 176
 '@BASEBOARD_FAB2_LIB.BASEBOARD_FAB2(SCH_1):PAGE47_I43@MSTR_SCONN.SCONN288_H44441004(CHIPS)':
 'VSS'<33>: CDS_PINID='VSS(33)';
NODE_NAME     J4G3 173
 '@BASEBOARD_FAB2_LIB.BASEBOARD_FAB2(SCH_1):PAGE47_I43@MSTR_SCONN.SCONN288_H44441004(CHIPS)':
 'VSS'<34>: CDS_PINID='VSS(34)';
NODE_NAME     J4G3 171
 '@BASEBOARD_FAB2_LIB.BASEBOARD_FAB2(SCH_1):PAGE47_I43@MSTR_SCONN.SCONN288_H44441004(CHIPS)':
 'VSS'<35>: CDS_PINID='VSS(35)';
NODE_NAME     J4G3 169
 '@BASEBOARD_FAB2_LIB.BASEBOARD_FAB2(SCH_1):PAGE47_I43@MSTR_SCONN.SCONN288_H44441004(CHIPS)':
 'VSS'<36>: CDS_PINID='VSS(36)';
NODE_NAME     J4G3 167
 '@BASEBOARD_FAB2_LIB.BASEBOARD_FAB2(SCH_1):PAGE47_I43@MSTR_SCONN.SCONN288_H44441004(CHIPS)':
 'VSS'<37>: CDS_PINID='VSS(37)';
NODE_NAME     J4G3 165
 '@BASEBOARD_FAB2_LIB.BASEBOARD_FAB2(SCH_1):PAGE47_I43@MSTR_SCONN.SCONN288_H44441004(CHIPS)':
 'VSS'<38>: CDS_PINID='VSS(38)';
NODE_NAME     J4G3 162
 '@BASEBOARD_FAB2_LIB.BASEBOARD_FAB2(SCH_1):PAGE47_I43@MSTR_SCONN.SCONN288_H44441004(CHIPS)':
 'VSS'<39>: CDS_PINID='VSS(39)';
NODE_NAME     J4G3 160
 '@BASEBOARD_FAB2_LIB.BASEBOARD_FAB2(SCH_1):PAGE47_I43@MSTR_SCONN.SCONN288_H44441004(CHIPS)':
 'VSS'<40>: CDS_PINID='VSS(40)';
NODE_NAME     J4G3 158
 '@BASEBOARD_FAB2_LIB.BASEBOARD_FAB2(SCH_1):PAGE47_I43@MSTR_SCONN.SCONN288_H44441004(CHIPS)':
 'VSS'<41>: CDS_PINID='VSS(41)';
NODE_NAME     J4G3 156
 '@BASEBOARD_FAB2_LIB.BASEBOARD_FAB2(SCH_1):PAGE47_I43@MSTR_SCONN.SCONN288_H44441004(CHIPS)':
 'VSS'<42>: CDS_PINID='VSS(42)';
NODE_NAME     J4G3 154
 '@BASEBOARD_FAB2_LIB.BASEBOARD_FAB2(SCH_1):PAGE47_I43@MSTR_SCONN.SCONN288_H44441004(CHIPS)':
 'VSS'<43>: CDS_PINID='VSS(43)';
NODE_NAME     J4G3 151
 '@BASEBOARD_FAB2_LIB.BASEBOARD_FAB2(SCH_1):PAGE47_I43@MSTR_SCONN.SCONN288_H44441004(CHIPS)':
 'VSS'<44>: CDS_PINID='VSS(44)';
NODE_NAME     J4G3 149
 '@BASEBOARD_FAB2_LIB.BASEBOARD_FAB2(SCH_1):PAGE47_I43@MSTR_SCONN.SCONN288_H44441004(CHIPS)':
 'VSS'<45>: CDS_PINID='VSS(45)';
NODE_NAME     J4G3 147
 '@BASEBOARD_FAB2_LIB.BASEBOARD_FAB2(SCH_1):PAGE47_I43@MSTR_SCONN.SCONN288_H44441004(CHIPS)':
 'VSS'<46>: CDS_PINID='VSS(46)';
NODE_NAME     J4G3 138
 '@BASEBOARD_FAB2_LIB.BASEBOARD_FAB2(SCH_1):PAGE47_I43@MSTR_SCONN.SCONN288_H44441004(CHIPS)':
 'VSS'<47>: CDS_PINID='VSS(47)';
NODE_NAME     J4G3 136
 '@BASEBOARD_FAB2_LIB.BASEBOARD_FAB2(SCH_1):PAGE47_I43@MSTR_SCONN.SCONN288_H44441004(CHIPS)':
 'VSS'<48>: CDS_PINID='VSS(48)';
NODE_NAME     J4G3 134
 '@BASEBOARD_FAB2_LIB.BASEBOARD_FAB2(SCH_1):PAGE47_I43@MSTR_SCONN.SCONN288_H44441004(CHIPS)':
 'VSS'<49>: CDS_PINID='VSS(49)';
NODE_NAME     J4G3 131
 '@BASEBOARD_FAB2_LIB.BASEBOARD_FAB2(SCH_1):PAGE47_I43@MSTR_SCONN.SCONN288_H44441004(CHIPS)':
 'VSS'<50>: CDS_PINID='VSS(50)';
NODE_NAME     J4G3 129
 '@BASEBOARD_FAB2_LIB.BASEBOARD_FAB2(SCH_1):PAGE47_I43@MSTR_SCONN.SCONN288_H44441004(CHIPS)':
 'VSS'<51>: CDS_PINID='VSS(51)';
NODE_NAME     J4G3 127
 '@BASEBOARD_FAB2_LIB.BASEBOARD_FAB2(SCH_1):PAGE47_I43@MSTR_SCONN.SCONN288_H44441004(CHIPS)':
 'VSS'<52>: CDS_PINID='VSS(52)';
NODE_NAME     J4G3 125
 '@BASEBOARD_FAB2_LIB.BASEBOARD_FAB2(SCH_1):PAGE47_I43@MSTR_SCONN.SCONN288_H44441004(CHIPS)':
 'VSS'<53>: CDS_PINID='VSS(53)';
NODE_NAME     J4G3 123
 '@BASEBOARD_FAB2_LIB.BASEBOARD_FAB2(SCH_1):PAGE47_I43@MSTR_SCONN.SCONN288_H44441004(CHIPS)':
 'VSS'<54>: CDS_PINID='VSS(54)';
NODE_NAME     J4G3 120
 '@BASEBOARD_FAB2_LIB.BASEBOARD_FAB2(SCH_1):PAGE47_I43@MSTR_SCONN.SCONN288_H44441004(CHIPS)':
 'VSS'<55>: CDS_PINID='VSS(55)';
NODE_NAME     J4G3 118
 '@BASEBOARD_FAB2_LIB.BASEBOARD_FAB2(SCH_1):PAGE47_I43@MSTR_SCONN.SCONN288_H44441004(CHIPS)':
 'VSS'<56>: CDS_PINID='VSS(56)';
NODE_NAME     J4G3 116
 '@BASEBOARD_FAB2_LIB.BASEBOARD_FAB2(SCH_1):PAGE47_I43@MSTR_SCONN.SCONN288_H44441004(CHIPS)':
 'VSS'<57>: CDS_PINID='VSS(57)';
NODE_NAME     J4G3 114
 '@BASEBOARD_FAB2_LIB.BASEBOARD_FAB2(SCH_1):PAGE47_I43@MSTR_SCONN.SCONN288_H44441004(CHIPS)':
 'VSS'<58>: CDS_PINID='VSS(58)';
NODE_NAME     J4G3 112
 '@BASEBOARD_FAB2_LIB.BASEBOARD_FAB2(SCH_1):PAGE47_I43@MSTR_SCONN.SCONN288_H44441004(CHIPS)':
 'VSS'<59>: CDS_PINID='VSS(59)';
NODE_NAME     J4G3 109
 '@BASEBOARD_FAB2_LIB.BASEBOARD_FAB2(SCH_1):PAGE47_I43@MSTR_SCONN.SCONN288_H44441004(CHIPS)':
 'VSS'<60>: CDS_PINID='VSS(60)';
NODE_NAME     J4G3 107
 '@BASEBOARD_FAB2_LIB.BASEBOARD_FAB2(SCH_1):PAGE47_I43@MSTR_SCONN.SCONN288_H44441004(CHIPS)':
 'VSS'<61>: CDS_PINID='VSS(61)';
NODE_NAME     J4G3 105
 '@BASEBOARD_FAB2_LIB.BASEBOARD_FAB2(SCH_1):PAGE47_I43@MSTR_SCONN.SCONN288_H44441004(CHIPS)':
 'VSS'<62>: CDS_PINID='VSS(62)';
NODE_NAME     J4G3 103
 '@BASEBOARD_FAB2_LIB.BASEBOARD_FAB2(SCH_1):PAGE47_I43@MSTR_SCONN.SCONN288_H44441004(CHIPS)':
 'VSS'<63>: CDS_PINID='VSS(63)';
NODE_NAME     J4G3 101
 '@BASEBOARD_FAB2_LIB.BASEBOARD_FAB2(SCH_1):PAGE47_I43@MSTR_SCONN.SCONN288_H44441004(CHIPS)':
 'VSS'<64>: CDS_PINID='VSS(64)';
NODE_NAME     J4G3 98
 '@BASEBOARD_FAB2_LIB.BASEBOARD_FAB2(SCH_1):PAGE47_I43@MSTR_SCONN.SCONN288_H44441004(CHIPS)':
 'VSS'<65>: CDS_PINID='VSS(65)';
NODE_NAME     J4G3 96
 '@BASEBOARD_FAB2_LIB.BASEBOARD_FAB2(SCH_1):PAGE47_I43@MSTR_SCONN.SCONN288_H44441004(CHIPS)':
 'VSS'<66>: CDS_PINID='VSS(66)';
NODE_NAME     J4G3 94
 '@BASEBOARD_FAB2_LIB.BASEBOARD_FAB2(SCH_1):PAGE47_I43@MSTR_SCONN.SCONN288_H44441004(CHIPS)':
 'VSS'<67>: CDS_PINID='VSS(67)';
NODE_NAME     J4G3 57
 '@BASEBOARD_FAB2_LIB.BASEBOARD_FAB2(SCH_1):PAGE47_I43@MSTR_SCONN.SCONN288_H44441004(CHIPS)':
 'VSS'<68>: CDS_PINID='VSS(68)';
NODE_NAME     J4G3 55
 '@BASEBOARD_FAB2_LIB.BASEBOARD_FAB2(SCH_1):PAGE47_I43@MSTR_SCONN.SCONN288_H44441004(CHIPS)':
 'VSS'<69>: CDS_PINID='VSS(69)';
NODE_NAME     J4G3 53
 '@BASEBOARD_FAB2_LIB.BASEBOARD_FAB2(SCH_1):PAGE47_I43@MSTR_SCONN.SCONN288_H44441004(CHIPS)':
 'VSS'<70>: CDS_PINID='VSS(70)';
NODE_NAME     J4G3 50
 '@BASEBOARD_FAB2_LIB.BASEBOARD_FAB2(SCH_1):PAGE47_I43@MSTR_SCONN.SCONN288_H44441004(CHIPS)':
 'VSS'<71>: CDS_PINID='VSS(71)';
NODE_NAME     J4G3 48
 '@BASEBOARD_FAB2_LIB.BASEBOARD_FAB2(SCH_1):PAGE47_I43@MSTR_SCONN.SCONN288_H44441004(CHIPS)':
 'VSS'<72>: CDS_PINID='VSS(72)';
NODE_NAME     J4G3 46
 '@BASEBOARD_FAB2_LIB.BASEBOARD_FAB2(SCH_1):PAGE47_I43@MSTR_SCONN.SCONN288_H44441004(CHIPS)':
 'VSS'<73>: CDS_PINID='VSS(73)';
NODE_NAME     J4G3 44
 '@BASEBOARD_FAB2_LIB.BASEBOARD_FAB2(SCH_1):PAGE47_I43@MSTR_SCONN.SCONN288_H44441004(CHIPS)':
 'VSS'<74>: CDS_PINID='VSS(74)';
NODE_NAME     J4G3 42
 '@BASEBOARD_FAB2_LIB.BASEBOARD_FAB2(SCH_1):PAGE47_I43@MSTR_SCONN.SCONN288_H44441004(CHIPS)':
 'VSS'<75>: CDS_PINID='VSS(75)';
NODE_NAME     J4G3 39
 '@BASEBOARD_FAB2_LIB.BASEBOARD_FAB2(SCH_1):PAGE47_I43@MSTR_SCONN.SCONN288_H44441004(CHIPS)':
 'VSS'<76>: CDS_PINID='VSS(76)';
NODE_NAME     J4G3 37
 '@BASEBOARD_FAB2_LIB.BASEBOARD_FAB2(SCH_1):PAGE47_I43@MSTR_SCONN.SCONN288_H44441004(CHIPS)':
 'VSS'<77>: CDS_PINID='VSS(77)';
NODE_NAME     J4G3 35
 '@BASEBOARD_FAB2_LIB.BASEBOARD_FAB2(SCH_1):PAGE47_I43@MSTR_SCONN.SCONN288_H44441004(CHIPS)':
 'VSS'<78>: CDS_PINID='VSS(78)';
NODE_NAME     J4G3 33
 '@BASEBOARD_FAB2_LIB.BASEBOARD_FAB2(SCH_1):PAGE47_I43@MSTR_SCONN.SCONN288_H44441004(CHIPS)':
 'VSS'<79>: CDS_PINID='VSS(79)';
NODE_NAME     J4G3 31
 '@BASEBOARD_FAB2_LIB.BASEBOARD_FAB2(SCH_1):PAGE47_I43@MSTR_SCONN.SCONN288_H44441004(CHIPS)':
 'VSS'<80>: CDS_PINID='VSS(80)';
NODE_NAME     J4G3 28
 '@BASEBOARD_FAB2_LIB.BASEBOARD_FAB2(SCH_1):PAGE47_I43@MSTR_SCONN.SCONN288_H44441004(CHIPS)':
 'VSS'<81>: CDS_PINID='VSS(81)';
NODE_NAME     J4G3 26
 '@BASEBOARD_FAB2_LIB.BASEBOARD_FAB2(SCH_1):PAGE47_I43@MSTR_SCONN.SCONN288_H44441004(CHIPS)':
 'VSS'<82>: CDS_PINID='VSS(82)';
NODE_NAME     J4G3 24
 '@BASEBOARD_FAB2_LIB.BASEBOARD_FAB2(SCH_1):PAGE47_I43@MSTR_SCONN.SCONN288_H44441004(CHIPS)':
 'VSS'<83>: CDS_PINID='VSS(83)';
NODE_NAME     J4G3 22
 '@BASEBOARD_FAB2_LIB.BASEBOARD_FAB2(SCH_1):PAGE47_I43@MSTR_SCONN.SCONN288_H44441004(CHIPS)':
 'VSS'<84>: CDS_PINID='VSS(84)';
NODE_NAME     J4G3 20
 '@BASEBOARD_FAB2_LIB.BASEBOARD_FAB2(SCH_1):PAGE47_I43@MSTR_SCONN.SCONN288_H44441004(CHIPS)':
 'VSS'<85>: CDS_PINID='VSS(85)';
NODE_NAME     J4G3 17
 '@BASEBOARD_FAB2_LIB.BASEBOARD_FAB2(SCH_1):PAGE47_I43@MSTR_SCONN.SCONN288_H44441004(CHIPS)':
 'VSS'<86>: CDS_PINID='VSS(86)';
NODE_NAME     J4G3 15
 '@BASEBOARD_FAB2_LIB.BASEBOARD_FAB2(SCH_1):PAGE47_I43@MSTR_SCONN.SCONN288_H44441004(CHIPS)':
 'VSS'<87>: CDS_PINID='VSS(87)';
NODE_NAME     J4G3 13
 '@BASEBOARD_FAB2_LIB.BASEBOARD_FAB2(SCH_1):PAGE47_I43@MSTR_SCONN.SCONN288_H44441004(CHIPS)':
 'VSS'<88>: CDS_PINID='VSS(88)';
NODE_NAME     J4G3 11
 '@BASEBOARD_FAB2_LIB.BASEBOARD_FAB2(SCH_1):PAGE47_I43@MSTR_SCONN.SCONN288_H44441004(CHIPS)':
 'VSS'<89>: CDS_PINID='VSS(89)';
NODE_NAME     J4G3 9
 '@BASEBOARD_FAB2_LIB.BASEBOARD_FAB2(SCH_1):PAGE47_I43@MSTR_SCONN.SCONN288_H44441004(CHIPS)':
 'VSS'<90>: CDS_PINID='VSS(90)';
NODE_NAME     J4G3 6
 '@BASEBOARD_FAB2_LIB.BASEBOARD_FAB2(SCH_1):PAGE47_I43@MSTR_SCONN.SCONN288_H44441004(CHIPS)':
 'VSS'<91>: CDS_PINID='VSS(91)';
NODE_NAME     J4G3 4
 '@BASEBOARD_FAB2_LIB.BASEBOARD_FAB2(SCH_1):PAGE47_I43@MSTR_SCONN.SCONN288_H44441004(CHIPS)':
 'VSS'<92>: CDS_PINID='VSS(92)';
NODE_NAME     J4G3 2
 '@BASEBOARD_FAB2_LIB.BASEBOARD_FAB2(SCH_1):PAGE47_I43@MSTR_SCONN.SCONN288_H44441004(CHIPS)':
 'VSS'<93>: CDS_PINID='VSS(93)';
NODE_NAME     J4G3 139
 '@BASEBOARD_FAB2_LIB.BASEBOARD_FAB2(SCH_1):PAGE47_I111@MSTR_SCONN.SCONN288_H44441004(CHIPS)':
 'SA'<0>: CDS_PINID='SA(0)';
NODE_NAME     J4G3 140
 '@BASEBOARD_FAB2_LIB.BASEBOARD_FAB2(SCH_1):PAGE47_I111@MSTR_SCONN.SCONN288_H44441004(CHIPS)':
 'SA'<1>: CDS_PINID='SA(1)';
NODE_NAME     C4G19 2
 '@BASEBOARD_FAB2_LIB.BASEBOARD_FAB2(SCH_1):PAGE47_I188@DEV_DISCRETE.CAP_A(CHIPS)':
 'B': CDS_PINID='B';
NODE_NAME     J6U2 283
 '@BASEBOARD_FAB2_LIB.BASEBOARD_FAB2(SCH_1):PAGE48_I43@MSTR_SCONN.SCONN288_H44441003(CHIPS)':
 'VSS'<0>: CDS_PINID='VSS(0)';
NODE_NAME     J6U2 281
 '@BASEBOARD_FAB2_LIB.BASEBOARD_FAB2(SCH_1):PAGE48_I43@MSTR_SCONN.SCONN288_H44441003(CHIPS)':
 'VSS'<1>: CDS_PINID='VSS(1)';
NODE_NAME     J6U2 279
 '@BASEBOARD_FAB2_LIB.BASEBOARD_FAB2(SCH_1):PAGE48_I43@MSTR_SCONN.SCONN288_H44441003(CHIPS)':
 'VSS'<2>: CDS_PINID='VSS(2)';
NODE_NAME     J6U2 276
 '@BASEBOARD_FAB2_LIB.BASEBOARD_FAB2(SCH_1):PAGE48_I43@MSTR_SCONN.SCONN288_H44441003(CHIPS)':
 'VSS'<3>: CDS_PINID='VSS(3)';
NODE_NAME     J6U2 274
 '@BASEBOARD_FAB2_LIB.BASEBOARD_FAB2(SCH_1):PAGE48_I43@MSTR_SCONN.SCONN288_H44441003(CHIPS)':
 'VSS'<4>: CDS_PINID='VSS(4)';
NODE_NAME     J6U2 272
 '@BASEBOARD_FAB2_LIB.BASEBOARD_FAB2(SCH_1):PAGE48_I43@MSTR_SCONN.SCONN288_H44441003(CHIPS)':
 'VSS'<5>: CDS_PINID='VSS(5)';
NODE_NAME     J6U2 270
 '@BASEBOARD_FAB2_LIB.BASEBOARD_FAB2(SCH_1):PAGE48_I43@MSTR_SCONN.SCONN288_H44441003(CHIPS)':
 'VSS'<6>: CDS_PINID='VSS(6)';
NODE_NAME     J6U2 268
 '@BASEBOARD_FAB2_LIB.BASEBOARD_FAB2(SCH_1):PAGE48_I43@MSTR_SCONN.SCONN288_H44441003(CHIPS)':
 'VSS'<7>: CDS_PINID='VSS(7)';
NODE_NAME     J6U2 265
 '@BASEBOARD_FAB2_LIB.BASEBOARD_FAB2(SCH_1):PAGE48_I43@MSTR_SCONN.SCONN288_H44441003(CHIPS)':
 'VSS'<8>: CDS_PINID='VSS(8)';
NODE_NAME     J6U2 263
 '@BASEBOARD_FAB2_LIB.BASEBOARD_FAB2(SCH_1):PAGE48_I43@MSTR_SCONN.SCONN288_H44441003(CHIPS)':
 'VSS'<9>: CDS_PINID='VSS(9)';
NODE_NAME     J6U2 261
 '@BASEBOARD_FAB2_LIB.BASEBOARD_FAB2(SCH_1):PAGE48_I43@MSTR_SCONN.SCONN288_H44441003(CHIPS)':
 'VSS'<10>: CDS_PINID='VSS(10)';
NODE_NAME     J6U2 259
 '@BASEBOARD_FAB2_LIB.BASEBOARD_FAB2(SCH_1):PAGE48_I43@MSTR_SCONN.SCONN288_H44441003(CHIPS)':
 'VSS'<11>: CDS_PINID='VSS(11)';
NODE_NAME     J6U2 257
 '@BASEBOARD_FAB2_LIB.BASEBOARD_FAB2(SCH_1):PAGE48_I43@MSTR_SCONN.SCONN288_H44441003(CHIPS)':
 'VSS'<12>: CDS_PINID='VSS(12)';
NODE_NAME     J6U2 254
 '@BASEBOARD_FAB2_LIB.BASEBOARD_FAB2(SCH_1):PAGE48_I43@MSTR_SCONN.SCONN288_H44441003(CHIPS)':
 'VSS'<13>: CDS_PINID='VSS(13)';
NODE_NAME     J6U2 252
 '@BASEBOARD_FAB2_LIB.BASEBOARD_FAB2(SCH_1):PAGE48_I43@MSTR_SCONN.SCONN288_H44441003(CHIPS)':
 'VSS'<14>: CDS_PINID='VSS(14)';
NODE_NAME     J6U2 250
 '@BASEBOARD_FAB2_LIB.BASEBOARD_FAB2(SCH_1):PAGE48_I43@MSTR_SCONN.SCONN288_H44441003(CHIPS)':
 'VSS'<15>: CDS_PINID='VSS(15)';
NODE_NAME     J6U2 248
 '@BASEBOARD_FAB2_LIB.BASEBOARD_FAB2(SCH_1):PAGE48_I43@MSTR_SCONN.SCONN288_H44441003(CHIPS)':
 'VSS'<16>: CDS_PINID='VSS(16)';
NODE_NAME     J6U2 246
 '@BASEBOARD_FAB2_LIB.BASEBOARD_FAB2(SCH_1):PAGE48_I43@MSTR_SCONN.SCONN288_H44441003(CHIPS)':
 'VSS'<17>: CDS_PINID='VSS(17)';
NODE_NAME     J6U2 243
 '@BASEBOARD_FAB2_LIB.BASEBOARD_FAB2(SCH_1):PAGE48_I43@MSTR_SCONN.SCONN288_H44441003(CHIPS)':
 'VSS'<18>: CDS_PINID='VSS(18)';
NODE_NAME     J6U2 241
 '@BASEBOARD_FAB2_LIB.BASEBOARD_FAB2(SCH_1):PAGE48_I43@MSTR_SCONN.SCONN288_H44441003(CHIPS)':
 'VSS'<19>: CDS_PINID='VSS(19)';
NODE_NAME     J6U2 239
 '@BASEBOARD_FAB2_LIB.BASEBOARD_FAB2(SCH_1):PAGE48_I43@MSTR_SCONN.SCONN288_H44441003(CHIPS)':
 'VSS'<20>: CDS_PINID='VSS(20)';
NODE_NAME     J6U2 202
 '@BASEBOARD_FAB2_LIB.BASEBOARD_FAB2(SCH_1):PAGE48_I43@MSTR_SCONN.SCONN288_H44441003(CHIPS)':
 'VSS'<21>: CDS_PINID='VSS(21)';
NODE_NAME     J6U2 200
 '@BASEBOARD_FAB2_LIB.BASEBOARD_FAB2(SCH_1):PAGE48_I43@MSTR_SCONN.SCONN288_H44441003(CHIPS)':
 'VSS'<22>: CDS_PINID='VSS(22)';
NODE_NAME     J6U2 198
 '@BASEBOARD_FAB2_LIB.BASEBOARD_FAB2(SCH_1):PAGE48_I43@MSTR_SCONN.SCONN288_H44441003(CHIPS)':
 'VSS'<23>: CDS_PINID='VSS(23)';
NODE_NAME     J6U2 195
 '@BASEBOARD_FAB2_LIB.BASEBOARD_FAB2(SCH_1):PAGE48_I43@MSTR_SCONN.SCONN288_H44441003(CHIPS)':
 'VSS'<24>: CDS_PINID='VSS(24)';
NODE_NAME     J6U2 193
 '@BASEBOARD_FAB2_LIB.BASEBOARD_FAB2(SCH_1):PAGE48_I43@MSTR_SCONN.SCONN288_H44441003(CHIPS)':
 'VSS'<25>: CDS_PINID='VSS(25)';
NODE_NAME     J6U2 191
 '@BASEBOARD_FAB2_LIB.BASEBOARD_FAB2(SCH_1):PAGE48_I43@MSTR_SCONN.SCONN288_H44441003(CHIPS)':
 'VSS'<26>: CDS_PINID='VSS(26)';
NODE_NAME     J6U2 189
 '@BASEBOARD_FAB2_LIB.BASEBOARD_FAB2(SCH_1):PAGE48_I43@MSTR_SCONN.SCONN288_H44441003(CHIPS)':
 'VSS'<27>: CDS_PINID='VSS(27)';
NODE_NAME     J6U2 187
 '@BASEBOARD_FAB2_LIB.BASEBOARD_FAB2(SCH_1):PAGE48_I43@MSTR_SCONN.SCONN288_H44441003(CHIPS)':
 'VSS'<28>: CDS_PINID='VSS(28)';
NODE_NAME     J6U2 184
 '@BASEBOARD_FAB2_LIB.BASEBOARD_FAB2(SCH_1):PAGE48_I43@MSTR_SCONN.SCONN288_H44441003(CHIPS)':
 'VSS'<29>: CDS_PINID='VSS(29)';
NODE_NAME     J6U2 182
 '@BASEBOARD_FAB2_LIB.BASEBOARD_FAB2(SCH_1):PAGE48_I43@MSTR_SCONN.SCONN288_H44441003(CHIPS)':
 'VSS'<30>: CDS_PINID='VSS(30)';
NODE_NAME     J6U2 180
 '@BASEBOARD_FAB2_LIB.BASEBOARD_FAB2(SCH_1):PAGE48_I43@MSTR_SCONN.SCONN288_H44441003(CHIPS)':
 'VSS'<31>: CDS_PINID='VSS(31)';
NODE_NAME     J6U2 178
 '@BASEBOARD_FAB2_LIB.BASEBOARD_FAB2(SCH_1):PAGE48_I43@MSTR_SCONN.SCONN288_H44441003(CHIPS)':
 'VSS'<32>: CDS_PINID='VSS(32)';
NODE_NAME     J6U2 176
 '@BASEBOARD_FAB2_LIB.BASEBOARD_FAB2(SCH_1):PAGE48_I43@MSTR_SCONN.SCONN288_H44441003(CHIPS)':
 'VSS'<33>: CDS_PINID='VSS(33)';
NODE_NAME     J6U2 173
 '@BASEBOARD_FAB2_LIB.BASEBOARD_FAB2(SCH_1):PAGE48_I43@MSTR_SCONN.SCONN288_H44441003(CHIPS)':
 'VSS'<34>: CDS_PINID='VSS(34)';
NODE_NAME     J6U2 171
 '@BASEBOARD_FAB2_LIB.BASEBOARD_FAB2(SCH_1):PAGE48_I43@MSTR_SCONN.SCONN288_H44441003(CHIPS)':
 'VSS'<35>: CDS_PINID='VSS(35)';
NODE_NAME     J6U2 169
 '@BASEBOARD_FAB2_LIB.BASEBOARD_FAB2(SCH_1):PAGE48_I43@MSTR_SCONN.SCONN288_H44441003(CHIPS)':
 'VSS'<36>: CDS_PINID='VSS(36)';
NODE_NAME     J6U2 167
 '@BASEBOARD_FAB2_LIB.BASEBOARD_FAB2(SCH_1):PAGE48_I43@MSTR_SCONN.SCONN288_H44441003(CHIPS)':
 'VSS'<37>: CDS_PINID='VSS(37)';
NODE_NAME     J6U2 165
 '@BASEBOARD_FAB2_LIB.BASEBOARD_FAB2(SCH_1):PAGE48_I43@MSTR_SCONN.SCONN288_H44441003(CHIPS)':
 'VSS'<38>: CDS_PINID='VSS(38)';
NODE_NAME     J6U2 162
 '@BASEBOARD_FAB2_LIB.BASEBOARD_FAB2(SCH_1):PAGE48_I43@MSTR_SCONN.SCONN288_H44441003(CHIPS)':
 'VSS'<39>: CDS_PINID='VSS(39)';
NODE_NAME     J6U2 160
 '@BASEBOARD_FAB2_LIB.BASEBOARD_FAB2(SCH_1):PAGE48_I43@MSTR_SCONN.SCONN288_H44441003(CHIPS)':
 'VSS'<40>: CDS_PINID='VSS(40)';
NODE_NAME     J6U2 158
 '@BASEBOARD_FAB2_LIB.BASEBOARD_FAB2(SCH_1):PAGE48_I43@MSTR_SCONN.SCONN288_H44441003(CHIPS)':
 'VSS'<41>: CDS_PINID='VSS(41)';
NODE_NAME     J6U2 156
 '@BASEBOARD_FAB2_LIB.BASEBOARD_FAB2(SCH_1):PAGE48_I43@MSTR_SCONN.SCONN288_H44441003(CHIPS)':
 'VSS'<42>: CDS_PINID='VSS(42)';
NODE_NAME     J6U2 154
 '@BASEBOARD_FAB2_LIB.BASEBOARD_FAB2(SCH_1):PAGE48_I43@MSTR_SCONN.SCONN288_H44441003(CHIPS)':
 'VSS'<43>: CDS_PINID='VSS(43)';
NODE_NAME     J6U2 151
 '@BASEBOARD_FAB2_LIB.BASEBOARD_FAB2(SCH_1):PAGE48_I43@MSTR_SCONN.SCONN288_H44441003(CHIPS)':
 'VSS'<44>: CDS_PINID='VSS(44)';
NODE_NAME     J6U2 149
 '@BASEBOARD_FAB2_LIB.BASEBOARD_FAB2(SCH_1):PAGE48_I43@MSTR_SCONN.SCONN288_H44441003(CHIPS)':
 'VSS'<45>: CDS_PINID='VSS(45)';
NODE_NAME     J6U2 147
 '@BASEBOARD_FAB2_LIB.BASEBOARD_FAB2(SCH_1):PAGE48_I43@MSTR_SCONN.SCONN288_H44441003(CHIPS)':
 'VSS'<46>: CDS_PINID='VSS(46)';
NODE_NAME     J6U2 138
 '@BASEBOARD_FAB2_LIB.BASEBOARD_FAB2(SCH_1):PAGE48_I43@MSTR_SCONN.SCONN288_H44441003(CHIPS)':
 'VSS'<47>: CDS_PINID='VSS(47)';
NODE_NAME     J6U2 136
 '@BASEBOARD_FAB2_LIB.BASEBOARD_FAB2(SCH_1):PAGE48_I43@MSTR_SCONN.SCONN288_H44441003(CHIPS)':
 'VSS'<48>: CDS_PINID='VSS(48)';
NODE_NAME     J6U2 134
 '@BASEBOARD_FAB2_LIB.BASEBOARD_FAB2(SCH_1):PAGE48_I43@MSTR_SCONN.SCONN288_H44441003(CHIPS)':
 'VSS'<49>: CDS_PINID='VSS(49)';
NODE_NAME     J6U2 131
 '@BASEBOARD_FAB2_LIB.BASEBOARD_FAB2(SCH_1):PAGE48_I43@MSTR_SCONN.SCONN288_H44441003(CHIPS)':
 'VSS'<50>: CDS_PINID='VSS(50)';
NODE_NAME     J6U2 129
 '@BASEBOARD_FAB2_LIB.BASEBOARD_FAB2(SCH_1):PAGE48_I43@MSTR_SCONN.SCONN288_H44441003(CHIPS)':
 'VSS'<51>: CDS_PINID='VSS(51)';
NODE_NAME     J6U2 127
 '@BASEBOARD_FAB2_LIB.BASEBOARD_FAB2(SCH_1):PAGE48_I43@MSTR_SCONN.SCONN288_H44441003(CHIPS)':
 'VSS'<52>: CDS_PINID='VSS(52)';
NODE_NAME     J6U2 125
 '@BASEBOARD_FAB2_LIB.BASEBOARD_FAB2(SCH_1):PAGE48_I43@MSTR_SCONN.SCONN288_H44441003(CHIPS)':
 'VSS'<53>: CDS_PINID='VSS(53)';
NODE_NAME     J6U2 123
 '@BASEBOARD_FAB2_LIB.BASEBOARD_FAB2(SCH_1):PAGE48_I43@MSTR_SCONN.SCONN288_H44441003(CHIPS)':
 'VSS'<54>: CDS_PINID='VSS(54)';
NODE_NAME     J6U2 120
 '@BASEBOARD_FAB2_LIB.BASEBOARD_FAB2(SCH_1):PAGE48_I43@MSTR_SCONN.SCONN288_H44441003(CHIPS)':
 'VSS'<55>: CDS_PINID='VSS(55)';
NODE_NAME     J6U2 118
 '@BASEBOARD_FAB2_LIB.BASEBOARD_FAB2(SCH_1):PAGE48_I43@MSTR_SCONN.SCONN288_H44441003(CHIPS)':
 'VSS'<56>: CDS_PINID='VSS(56)';
NODE_NAME     J6U2 116
 '@BASEBOARD_FAB2_LIB.BASEBOARD_FAB2(SCH_1):PAGE48_I43@MSTR_SCONN.SCONN288_H44441003(CHIPS)':
 'VSS'<57>: CDS_PINID='VSS(57)';
NODE_NAME     J6U2 114
 '@BASEBOARD_FAB2_LIB.BASEBOARD_FAB2(SCH_1):PAGE48_I43@MSTR_SCONN.SCONN288_H44441003(CHIPS)':
 'VSS'<58>: CDS_PINID='VSS(58)';
NODE_NAME     J6U2 112
 '@BASEBOARD_FAB2_LIB.BASEBOARD_FAB2(SCH_1):PAGE48_I43@MSTR_SCONN.SCONN288_H44441003(CHIPS)':
 'VSS'<59>: CDS_PINID='VSS(59)';
NODE_NAME     J6U2 109
 '@BASEBOARD_FAB2_LIB.BASEBOARD_FAB2(SCH_1):PAGE48_I43@MSTR_SCONN.SCONN288_H44441003(CHIPS)':
 'VSS'<60>: CDS_PINID='VSS(60)';
NODE_NAME     J6U2 107
 '@BASEBOARD_FAB2_LIB.BASEBOARD_FAB2(SCH_1):PAGE48_I43@MSTR_SCONN.SCONN288_H44441003(CHIPS)':
 'VSS'<61>: CDS_PINID='VSS(61)';
NODE_NAME     J6U2 105
 '@BASEBOARD_FAB2_LIB.BASEBOARD_FAB2(SCH_1):PAGE48_I43@MSTR_SCONN.SCONN288_H44441003(CHIPS)':
 'VSS'<62>: CDS_PINID='VSS(62)';
NODE_NAME     J6U2 103
 '@BASEBOARD_FAB2_LIB.BASEBOARD_FAB2(SCH_1):PAGE48_I43@MSTR_SCONN.SCONN288_H44441003(CHIPS)':
 'VSS'<63>: CDS_PINID='VSS(63)';
NODE_NAME     J6U2 101
 '@BASEBOARD_FAB2_LIB.BASEBOARD_FAB2(SCH_1):PAGE48_I43@MSTR_SCONN.SCONN288_H44441003(CHIPS)':
 'VSS'<64>: CDS_PINID='VSS(64)';
NODE_NAME     J6U2 98
 '@BASEBOARD_FAB2_LIB.BASEBOARD_FAB2(SCH_1):PAGE48_I43@MSTR_SCONN.SCONN288_H44441003(CHIPS)':
 'VSS'<65>: CDS_PINID='VSS(65)';
NODE_NAME     J6U2 96
 '@BASEBOARD_FAB2_LIB.BASEBOARD_FAB2(SCH_1):PAGE48_I43@MSTR_SCONN.SCONN288_H44441003(CHIPS)':
 'VSS'<66>: CDS_PINID='VSS(66)';
NODE_NAME     J6U2 94
 '@BASEBOARD_FAB2_LIB.BASEBOARD_FAB2(SCH_1):PAGE48_I43@MSTR_SCONN.SCONN288_H44441003(CHIPS)':
 'VSS'<67>: CDS_PINID='VSS(67)';
NODE_NAME     J6U2 57
 '@BASEBOARD_FAB2_LIB.BASEBOARD_FAB2(SCH_1):PAGE48_I43@MSTR_SCONN.SCONN288_H44441003(CHIPS)':
 'VSS'<68>: CDS_PINID='VSS(68)';
NODE_NAME     J6U2 55
 '@BASEBOARD_FAB2_LIB.BASEBOARD_FAB2(SCH_1):PAGE48_I43@MSTR_SCONN.SCONN288_H44441003(CHIPS)':
 'VSS'<69>: CDS_PINID='VSS(69)';
NODE_NAME     J6U2 53
 '@BASEBOARD_FAB2_LIB.BASEBOARD_FAB2(SCH_1):PAGE48_I43@MSTR_SCONN.SCONN288_H44441003(CHIPS)':
 'VSS'<70>: CDS_PINID='VSS(70)';
NODE_NAME     J6U2 50
 '@BASEBOARD_FAB2_LIB.BASEBOARD_FAB2(SCH_1):PAGE48_I43@MSTR_SCONN.SCONN288_H44441003(CHIPS)':
 'VSS'<71>: CDS_PINID='VSS(71)';
NODE_NAME     J6U2 48
 '@BASEBOARD_FAB2_LIB.BASEBOARD_FAB2(SCH_1):PAGE48_I43@MSTR_SCONN.SCONN288_H44441003(CHIPS)':
 'VSS'<72>: CDS_PINID='VSS(72)';
NODE_NAME     J6U2 46
 '@BASEBOARD_FAB2_LIB.BASEBOARD_FAB2(SCH_1):PAGE48_I43@MSTR_SCONN.SCONN288_H44441003(CHIPS)':
 'VSS'<73>: CDS_PINID='VSS(73)';
NODE_NAME     J6U2 44
 '@BASEBOARD_FAB2_LIB.BASEBOARD_FAB2(SCH_1):PAGE48_I43@MSTR_SCONN.SCONN288_H44441003(CHIPS)':
 'VSS'<74>: CDS_PINID='VSS(74)';
NODE_NAME     J6U2 42
 '@BASEBOARD_FAB2_LIB.BASEBOARD_FAB2(SCH_1):PAGE48_I43@MSTR_SCONN.SCONN288_H44441003(CHIPS)':
 'VSS'<75>: CDS_PINID='VSS(75)';
NODE_NAME     J6U2 39
 '@BASEBOARD_FAB2_LIB.BASEBOARD_FAB2(SCH_1):PAGE48_I43@MSTR_SCONN.SCONN288_H44441003(CHIPS)':
 'VSS'<76>: CDS_PINID='VSS(76)';
NODE_NAME     J6U2 37
 '@BASEBOARD_FAB2_LIB.BASEBOARD_FAB2(SCH_1):PAGE48_I43@MSTR_SCONN.SCONN288_H44441003(CHIPS)':
 'VSS'<77>: CDS_PINID='VSS(77)';
NODE_NAME     J6U2 35
 '@BASEBOARD_FAB2_LIB.BASEBOARD_FAB2(SCH_1):PAGE48_I43@MSTR_SCONN.SCONN288_H44441003(CHIPS)':
 'VSS'<78>: CDS_PINID='VSS(78)';
NODE_NAME     J6U2 33
 '@BASEBOARD_FAB2_LIB.BASEBOARD_FAB2(SCH_1):PAGE48_I43@MSTR_SCONN.SCONN288_H44441003(CHIPS)':
 'VSS'<79>: CDS_PINID='VSS(79)';
NODE_NAME     J6U2 31
 '@BASEBOARD_FAB2_LIB.BASEBOARD_FAB2(SCH_1):PAGE48_I43@MSTR_SCONN.SCONN288_H44441003(CHIPS)':
 'VSS'<80>: CDS_PINID='VSS(80)';
NODE_NAME     J6U2 28
 '@BASEBOARD_FAB2_LIB.BASEBOARD_FAB2(SCH_1):PAGE48_I43@MSTR_SCONN.SCONN288_H44441003(CHIPS)':
 'VSS'<81>: CDS_PINID='VSS(81)';
NODE_NAME     J6U2 26
 '@BASEBOARD_FAB2_LIB.BASEBOARD_FAB2(SCH_1):PAGE48_I43@MSTR_SCONN.SCONN288_H44441003(CHIPS)':
 'VSS'<82>: CDS_PINID='VSS(82)';
NODE_NAME     J6U2 24
 '@BASEBOARD_FAB2_LIB.BASEBOARD_FAB2(SCH_1):PAGE48_I43@MSTR_SCONN.SCONN288_H44441003(CHIPS)':
 'VSS'<83>: CDS_PINID='VSS(83)';
NODE_NAME     J6U2 22
 '@BASEBOARD_FAB2_LIB.BASEBOARD_FAB2(SCH_1):PAGE48_I43@MSTR_SCONN.SCONN288_H44441003(CHIPS)':
 'VSS'<84>: CDS_PINID='VSS(84)';
NODE_NAME     J6U2 20
 '@BASEBOARD_FAB2_LIB.BASEBOARD_FAB2(SCH_1):PAGE48_I43@MSTR_SCONN.SCONN288_H44441003(CHIPS)':
 'VSS'<85>: CDS_PINID='VSS(85)';
NODE_NAME     J6U2 17
 '@BASEBOARD_FAB2_LIB.BASEBOARD_FAB2(SCH_1):PAGE48_I43@MSTR_SCONN.SCONN288_H44441003(CHIPS)':
 'VSS'<86>: CDS_PINID='VSS(86)';
NODE_NAME     J6U2 15
 '@BASEBOARD_FAB2_LIB.BASEBOARD_FAB2(SCH_1):PAGE48_I43@MSTR_SCONN.SCONN288_H44441003(CHIPS)':
 'VSS'<87>: CDS_PINID='VSS(87)';
NODE_NAME     J6U2 13
 '@BASEBOARD_FAB2_LIB.BASEBOARD_FAB2(SCH_1):PAGE48_I43@MSTR_SCONN.SCONN288_H44441003(CHIPS)':
 'VSS'<88>: CDS_PINID='VSS(88)';
NODE_NAME     J6U2 11
 '@BASEBOARD_FAB2_LIB.BASEBOARD_FAB2(SCH_1):PAGE48_I43@MSTR_SCONN.SCONN288_H44441003(CHIPS)':
 'VSS'<89>: CDS_PINID='VSS(89)';
NODE_NAME     J6U2 9
 '@BASEBOARD_FAB2_LIB.BASEBOARD_FAB2(SCH_1):PAGE48_I43@MSTR_SCONN.SCONN288_H44441003(CHIPS)':
 'VSS'<90>: CDS_PINID='VSS(90)';
NODE_NAME     J6U2 6
 '@BASEBOARD_FAB2_LIB.BASEBOARD_FAB2(SCH_1):PAGE48_I43@MSTR_SCONN.SCONN288_H44441003(CHIPS)':
 'VSS'<91>: CDS_PINID='VSS(91)';
NODE_NAME     J6U2 4
 '@BASEBOARD_FAB2_LIB.BASEBOARD_FAB2(SCH_1):PAGE48_I43@MSTR_SCONN.SCONN288_H44441003(CHIPS)':
 'VSS'<92>: CDS_PINID='VSS(92)';
NODE_NAME     J6U2 2
 '@BASEBOARD_FAB2_LIB.BASEBOARD_FAB2(SCH_1):PAGE48_I43@MSTR_SCONN.SCONN288_H44441003(CHIPS)':
 'VSS'<93>: CDS_PINID='VSS(93)';
NODE_NAME     J6U2 140
 '@BASEBOARD_FAB2_LIB.BASEBOARD_FAB2(SCH_1):PAGE48_I111@MSTR_SCONN.SCONN288_H44441003(CHIPS)':
 'SA'<1>: CDS_PINID='SA(1)';
NODE_NAME     C6U17 2
 '@BASEBOARD_FAB2_LIB.BASEBOARD_FAB2(SCH_1):PAGE48_I176@DEV_DISCRETE.CAP_A(CHIPS)':
 'B': CDS_PINID='B';
NODE_NAME     J4B1 283
 '@BASEBOARD_FAB2_LIB.BASEBOARD_FAB2(SCH_1):PAGE49_I43@MSTR_SCONN.SCONN288_H44441004(CHIPS)':
 'VSS'<0>: CDS_PINID='VSS(0)';
NODE_NAME     J4B1 281
 '@BASEBOARD_FAB2_LIB.BASEBOARD_FAB2(SCH_1):PAGE49_I43@MSTR_SCONN.SCONN288_H44441004(CHIPS)':
 'VSS'<1>: CDS_PINID='VSS(1)';
NODE_NAME     J4B1 279
 '@BASEBOARD_FAB2_LIB.BASEBOARD_FAB2(SCH_1):PAGE49_I43@MSTR_SCONN.SCONN288_H44441004(CHIPS)':
 'VSS'<2>: CDS_PINID='VSS(2)';
NODE_NAME     J4B1 276
 '@BASEBOARD_FAB2_LIB.BASEBOARD_FAB2(SCH_1):PAGE49_I43@MSTR_SCONN.SCONN288_H44441004(CHIPS)':
 'VSS'<3>: CDS_PINID='VSS(3)';
NODE_NAME     J4B1 274
 '@BASEBOARD_FAB2_LIB.BASEBOARD_FAB2(SCH_1):PAGE49_I43@MSTR_SCONN.SCONN288_H44441004(CHIPS)':
 'VSS'<4>: CDS_PINID='VSS(4)';
NODE_NAME     J4B1 272
 '@BASEBOARD_FAB2_LIB.BASEBOARD_FAB2(SCH_1):PAGE49_I43@MSTR_SCONN.SCONN288_H44441004(CHIPS)':
 'VSS'<5>: CDS_PINID='VSS(5)';
NODE_NAME     J4B1 270
 '@BASEBOARD_FAB2_LIB.BASEBOARD_FAB2(SCH_1):PAGE49_I43@MSTR_SCONN.SCONN288_H44441004(CHIPS)':
 'VSS'<6>: CDS_PINID='VSS(6)';
NODE_NAME     J4B1 268
 '@BASEBOARD_FAB2_LIB.BASEBOARD_FAB2(SCH_1):PAGE49_I43@MSTR_SCONN.SCONN288_H44441004(CHIPS)':
 'VSS'<7>: CDS_PINID='VSS(7)';
NODE_NAME     J4B1 265
 '@BASEBOARD_FAB2_LIB.BASEBOARD_FAB2(SCH_1):PAGE49_I43@MSTR_SCONN.SCONN288_H44441004(CHIPS)':
 'VSS'<8>: CDS_PINID='VSS(8)';
NODE_NAME     J4B1 263
 '@BASEBOARD_FAB2_LIB.BASEBOARD_FAB2(SCH_1):PAGE49_I43@MSTR_SCONN.SCONN288_H44441004(CHIPS)':
 'VSS'<9>: CDS_PINID='VSS(9)';
NODE_NAME     J4B1 261
 '@BASEBOARD_FAB2_LIB.BASEBOARD_FAB2(SCH_1):PAGE49_I43@MSTR_SCONN.SCONN288_H44441004(CHIPS)':
 'VSS'<10>: CDS_PINID='VSS(10)';
NODE_NAME     J4B1 259
 '@BASEBOARD_FAB2_LIB.BASEBOARD_FAB2(SCH_1):PAGE49_I43@MSTR_SCONN.SCONN288_H44441004(CHIPS)':
 'VSS'<11>: CDS_PINID='VSS(11)';
NODE_NAME     J4B1 257
 '@BASEBOARD_FAB2_LIB.BASEBOARD_FAB2(SCH_1):PAGE49_I43@MSTR_SCONN.SCONN288_H44441004(CHIPS)':
 'VSS'<12>: CDS_PINID='VSS(12)';
NODE_NAME     J4B1 254
 '@BASEBOARD_FAB2_LIB.BASEBOARD_FAB2(SCH_1):PAGE49_I43@MSTR_SCONN.SCONN288_H44441004(CHIPS)':
 'VSS'<13>: CDS_PINID='VSS(13)';
NODE_NAME     J4B1 252
 '@BASEBOARD_FAB2_LIB.BASEBOARD_FAB2(SCH_1):PAGE49_I43@MSTR_SCONN.SCONN288_H44441004(CHIPS)':
 'VSS'<14>: CDS_PINID='VSS(14)';
NODE_NAME     J4B1 250
 '@BASEBOARD_FAB2_LIB.BASEBOARD_FAB2(SCH_1):PAGE49_I43@MSTR_SCONN.SCONN288_H44441004(CHIPS)':
 'VSS'<15>: CDS_PINID='VSS(15)';
NODE_NAME     J4B1 248
 '@BASEBOARD_FAB2_LIB.BASEBOARD_FAB2(SCH_1):PAGE49_I43@MSTR_SCONN.SCONN288_H44441004(CHIPS)':
 'VSS'<16>: CDS_PINID='VSS(16)';
NODE_NAME     J4B1 246
 '@BASEBOARD_FAB2_LIB.BASEBOARD_FAB2(SCH_1):PAGE49_I43@MSTR_SCONN.SCONN288_H44441004(CHIPS)':
 'VSS'<17>: CDS_PINID='VSS(17)';
NODE_NAME     J4B1 243
 '@BASEBOARD_FAB2_LIB.BASEBOARD_FAB2(SCH_1):PAGE49_I43@MSTR_SCONN.SCONN288_H44441004(CHIPS)':
 'VSS'<18>: CDS_PINID='VSS(18)';
NODE_NAME     J4B1 241
 '@BASEBOARD_FAB2_LIB.BASEBOARD_FAB2(SCH_1):PAGE49_I43@MSTR_SCONN.SCONN288_H44441004(CHIPS)':
 'VSS'<19>: CDS_PINID='VSS(19)';
NODE_NAME     J4B1 239
 '@BASEBOARD_FAB2_LIB.BASEBOARD_FAB2(SCH_1):PAGE49_I43@MSTR_SCONN.SCONN288_H44441004(CHIPS)':
 'VSS'<20>: CDS_PINID='VSS(20)';
NODE_NAME     J4B1 202
 '@BASEBOARD_FAB2_LIB.BASEBOARD_FAB2(SCH_1):PAGE49_I43@MSTR_SCONN.SCONN288_H44441004(CHIPS)':
 'VSS'<21>: CDS_PINID='VSS(21)';
NODE_NAME     J4B1 200
 '@BASEBOARD_FAB2_LIB.BASEBOARD_FAB2(SCH_1):PAGE49_I43@MSTR_SCONN.SCONN288_H44441004(CHIPS)':
 'VSS'<22>: CDS_PINID='VSS(22)';
NODE_NAME     J4B1 198
 '@BASEBOARD_FAB2_LIB.BASEBOARD_FAB2(SCH_1):PAGE49_I43@MSTR_SCONN.SCONN288_H44441004(CHIPS)':
 'VSS'<23>: CDS_PINID='VSS(23)';
NODE_NAME     J4B1 195
 '@BASEBOARD_FAB2_LIB.BASEBOARD_FAB2(SCH_1):PAGE49_I43@MSTR_SCONN.SCONN288_H44441004(CHIPS)':
 'VSS'<24>: CDS_PINID='VSS(24)';
NODE_NAME     J4B1 193
 '@BASEBOARD_FAB2_LIB.BASEBOARD_FAB2(SCH_1):PAGE49_I43@MSTR_SCONN.SCONN288_H44441004(CHIPS)':
 'VSS'<25>: CDS_PINID='VSS(25)';
NODE_NAME     J4B1 191
 '@BASEBOARD_FAB2_LIB.BASEBOARD_FAB2(SCH_1):PAGE49_I43@MSTR_SCONN.SCONN288_H44441004(CHIPS)':
 'VSS'<26>: CDS_PINID='VSS(26)';
NODE_NAME     J4B1 189
 '@BASEBOARD_FAB2_LIB.BASEBOARD_FAB2(SCH_1):PAGE49_I43@MSTR_SCONN.SCONN288_H44441004(CHIPS)':
 'VSS'<27>: CDS_PINID='VSS(27)';
NODE_NAME     J4B1 187
 '@BASEBOARD_FAB2_LIB.BASEBOARD_FAB2(SCH_1):PAGE49_I43@MSTR_SCONN.SCONN288_H44441004(CHIPS)':
 'VSS'<28>: CDS_PINID='VSS(28)';
NODE_NAME     J4B1 184
 '@BASEBOARD_FAB2_LIB.BASEBOARD_FAB2(SCH_1):PAGE49_I43@MSTR_SCONN.SCONN288_H44441004(CHIPS)':
 'VSS'<29>: CDS_PINID='VSS(29)';
NODE_NAME     J4B1 182
 '@BASEBOARD_FAB2_LIB.BASEBOARD_FAB2(SCH_1):PAGE49_I43@MSTR_SCONN.SCONN288_H44441004(CHIPS)':
 'VSS'<30>: CDS_PINID='VSS(30)';
NODE_NAME     J4B1 180
 '@BASEBOARD_FAB2_LIB.BASEBOARD_FAB2(SCH_1):PAGE49_I43@MSTR_SCONN.SCONN288_H44441004(CHIPS)':
 'VSS'<31>: CDS_PINID='VSS(31)';
NODE_NAME     J4B1 178
 '@BASEBOARD_FAB2_LIB.BASEBOARD_FAB2(SCH_1):PAGE49_I43@MSTR_SCONN.SCONN288_H44441004(CHIPS)':
 'VSS'<32>: CDS_PINID='VSS(32)';
NODE_NAME     J4B1 176
 '@BASEBOARD_FAB2_LIB.BASEBOARD_FAB2(SCH_1):PAGE49_I43@MSTR_SCONN.SCONN288_H44441004(CHIPS)':
 'VSS'<33>: CDS_PINID='VSS(33)';
NODE_NAME     J4B1 173
 '@BASEBOARD_FAB2_LIB.BASEBOARD_FAB2(SCH_1):PAGE49_I43@MSTR_SCONN.SCONN288_H44441004(CHIPS)':
 'VSS'<34>: CDS_PINID='VSS(34)';
NODE_NAME     J4B1 171
 '@BASEBOARD_FAB2_LIB.BASEBOARD_FAB2(SCH_1):PAGE49_I43@MSTR_SCONN.SCONN288_H44441004(CHIPS)':
 'VSS'<35>: CDS_PINID='VSS(35)';
NODE_NAME     J4B1 169
 '@BASEBOARD_FAB2_LIB.BASEBOARD_FAB2(SCH_1):PAGE49_I43@MSTR_SCONN.SCONN288_H44441004(CHIPS)':
 'VSS'<36>: CDS_PINID='VSS(36)';
NODE_NAME     J4B1 167
 '@BASEBOARD_FAB2_LIB.BASEBOARD_FAB2(SCH_1):PAGE49_I43@MSTR_SCONN.SCONN288_H44441004(CHIPS)':
 'VSS'<37>: CDS_PINID='VSS(37)';
NODE_NAME     J4B1 165
 '@BASEBOARD_FAB2_LIB.BASEBOARD_FAB2(SCH_1):PAGE49_I43@MSTR_SCONN.SCONN288_H44441004(CHIPS)':
 'VSS'<38>: CDS_PINID='VSS(38)';
NODE_NAME     J4B1 162
 '@BASEBOARD_FAB2_LIB.BASEBOARD_FAB2(SCH_1):PAGE49_I43@MSTR_SCONN.SCONN288_H44441004(CHIPS)':
 'VSS'<39>: CDS_PINID='VSS(39)';
NODE_NAME     J4B1 160
 '@BASEBOARD_FAB2_LIB.BASEBOARD_FAB2(SCH_1):PAGE49_I43@MSTR_SCONN.SCONN288_H44441004(CHIPS)':
 'VSS'<40>: CDS_PINID='VSS(40)';
NODE_NAME     J4B1 158
 '@BASEBOARD_FAB2_LIB.BASEBOARD_FAB2(SCH_1):PAGE49_I43@MSTR_SCONN.SCONN288_H44441004(CHIPS)':
 'VSS'<41>: CDS_PINID='VSS(41)';
NODE_NAME     J4B1 156
 '@BASEBOARD_FAB2_LIB.BASEBOARD_FAB2(SCH_1):PAGE49_I43@MSTR_SCONN.SCONN288_H44441004(CHIPS)':
 'VSS'<42>: CDS_PINID='VSS(42)';
NODE_NAME     J4B1 154
 '@BASEBOARD_FAB2_LIB.BASEBOARD_FAB2(SCH_1):PAGE49_I43@MSTR_SCONN.SCONN288_H44441004(CHIPS)':
 'VSS'<43>: CDS_PINID='VSS(43)';
NODE_NAME     J4B1 151
 '@BASEBOARD_FAB2_LIB.BASEBOARD_FAB2(SCH_1):PAGE49_I43@MSTR_SCONN.SCONN288_H44441004(CHIPS)':
 'VSS'<44>: CDS_PINID='VSS(44)';
NODE_NAME     J4B1 149
 '@BASEBOARD_FAB2_LIB.BASEBOARD_FAB2(SCH_1):PAGE49_I43@MSTR_SCONN.SCONN288_H44441004(CHIPS)':
 'VSS'<45>: CDS_PINID='VSS(45)';
NODE_NAME     J4B1 147
 '@BASEBOARD_FAB2_LIB.BASEBOARD_FAB2(SCH_1):PAGE49_I43@MSTR_SCONN.SCONN288_H44441004(CHIPS)':
 'VSS'<46>: CDS_PINID='VSS(46)';
NODE_NAME     J4B1 138
 '@BASEBOARD_FAB2_LIB.BASEBOARD_FAB2(SCH_1):PAGE49_I43@MSTR_SCONN.SCONN288_H44441004(CHIPS)':
 'VSS'<47>: CDS_PINID='VSS(47)';
NODE_NAME     J4B1 136
 '@BASEBOARD_FAB2_LIB.BASEBOARD_FAB2(SCH_1):PAGE49_I43@MSTR_SCONN.SCONN288_H44441004(CHIPS)':
 'VSS'<48>: CDS_PINID='VSS(48)';
NODE_NAME     J4B1 134
 '@BASEBOARD_FAB2_LIB.BASEBOARD_FAB2(SCH_1):PAGE49_I43@MSTR_SCONN.SCONN288_H44441004(CHIPS)':
 'VSS'<49>: CDS_PINID='VSS(49)';
NODE_NAME     J4B1 131
 '@BASEBOARD_FAB2_LIB.BASEBOARD_FAB2(SCH_1):PAGE49_I43@MSTR_SCONN.SCONN288_H44441004(CHIPS)':
 'VSS'<50>: CDS_PINID='VSS(50)';
NODE_NAME     J4B1 129
 '@BASEBOARD_FAB2_LIB.BASEBOARD_FAB2(SCH_1):PAGE49_I43@MSTR_SCONN.SCONN288_H44441004(CHIPS)':
 'VSS'<51>: CDS_PINID='VSS(51)';
NODE_NAME     J4B1 127
 '@BASEBOARD_FAB2_LIB.BASEBOARD_FAB2(SCH_1):PAGE49_I43@MSTR_SCONN.SCONN288_H44441004(CHIPS)':
 'VSS'<52>: CDS_PINID='VSS(52)';
NODE_NAME     J4B1 125
 '@BASEBOARD_FAB2_LIB.BASEBOARD_FAB2(SCH_1):PAGE49_I43@MSTR_SCONN.SCONN288_H44441004(CHIPS)':
 'VSS'<53>: CDS_PINID='VSS(53)';
NODE_NAME     J4B1 123
 '@BASEBOARD_FAB2_LIB.BASEBOARD_FAB2(SCH_1):PAGE49_I43@MSTR_SCONN.SCONN288_H44441004(CHIPS)':
 'VSS'<54>: CDS_PINID='VSS(54)';
NODE_NAME     J4B1 120
 '@BASEBOARD_FAB2_LIB.BASEBOARD_FAB2(SCH_1):PAGE49_I43@MSTR_SCONN.SCONN288_H44441004(CHIPS)':
 'VSS'<55>: CDS_PINID='VSS(55)';
NODE_NAME     J4B1 118
 '@BASEBOARD_FAB2_LIB.BASEBOARD_FAB2(SCH_1):PAGE49_I43@MSTR_SCONN.SCONN288_H44441004(CHIPS)':
 'VSS'<56>: CDS_PINID='VSS(56)';
NODE_NAME     J4B1 116
 '@BASEBOARD_FAB2_LIB.BASEBOARD_FAB2(SCH_1):PAGE49_I43@MSTR_SCONN.SCONN288_H44441004(CHIPS)':
 'VSS'<57>: CDS_PINID='VSS(57)';
NODE_NAME     J4B1 114
 '@BASEBOARD_FAB2_LIB.BASEBOARD_FAB2(SCH_1):PAGE49_I43@MSTR_SCONN.SCONN288_H44441004(CHIPS)':
 'VSS'<58>: CDS_PINID='VSS(58)';
NODE_NAME     J4B1 112
 '@BASEBOARD_FAB2_LIB.BASEBOARD_FAB2(SCH_1):PAGE49_I43@MSTR_SCONN.SCONN288_H44441004(CHIPS)':
 'VSS'<59>: CDS_PINID='VSS(59)';
NODE_NAME     J4B1 109
 '@BASEBOARD_FAB2_LIB.BASEBOARD_FAB2(SCH_1):PAGE49_I43@MSTR_SCONN.SCONN288_H44441004(CHIPS)':
 'VSS'<60>: CDS_PINID='VSS(60)';
NODE_NAME     J4B1 107
 '@BASEBOARD_FAB2_LIB.BASEBOARD_FAB2(SCH_1):PAGE49_I43@MSTR_SCONN.SCONN288_H44441004(CHIPS)':
 'VSS'<61>: CDS_PINID='VSS(61)';
NODE_NAME     J4B1 105
 '@BASEBOARD_FAB2_LIB.BASEBOARD_FAB2(SCH_1):PAGE49_I43@MSTR_SCONN.SCONN288_H44441004(CHIPS)':
 'VSS'<62>: CDS_PINID='VSS(62)';
NODE_NAME     J4B1 103
 '@BASEBOARD_FAB2_LIB.BASEBOARD_FAB2(SCH_1):PAGE49_I43@MSTR_SCONN.SCONN288_H44441004(CHIPS)':
 'VSS'<63>: CDS_PINID='VSS(63)';
NODE_NAME     J4B1 101
 '@BASEBOARD_FAB2_LIB.BASEBOARD_FAB2(SCH_1):PAGE49_I43@MSTR_SCONN.SCONN288_H44441004(CHIPS)':
 'VSS'<64>: CDS_PINID='VSS(64)';
NODE_NAME     J4B1 98
 '@BASEBOARD_FAB2_LIB.BASEBOARD_FAB2(SCH_1):PAGE49_I43@MSTR_SCONN.SCONN288_H44441004(CHIPS)':
 'VSS'<65>: CDS_PINID='VSS(65)';
NODE_NAME     J4B1 96
 '@BASEBOARD_FAB2_LIB.BASEBOARD_FAB2(SCH_1):PAGE49_I43@MSTR_SCONN.SCONN288_H44441004(CHIPS)':
 'VSS'<66>: CDS_PINID='VSS(66)';
NODE_NAME     J4B1 94
 '@BASEBOARD_FAB2_LIB.BASEBOARD_FAB2(SCH_1):PAGE49_I43@MSTR_SCONN.SCONN288_H44441004(CHIPS)':
 'VSS'<67>: CDS_PINID='VSS(67)';
NODE_NAME     J4B1 57
 '@BASEBOARD_FAB2_LIB.BASEBOARD_FAB2(SCH_1):PAGE49_I43@MSTR_SCONN.SCONN288_H44441004(CHIPS)':
 'VSS'<68>: CDS_PINID='VSS(68)';
NODE_NAME     J4B1 55
 '@BASEBOARD_FAB2_LIB.BASEBOARD_FAB2(SCH_1):PAGE49_I43@MSTR_SCONN.SCONN288_H44441004(CHIPS)':
 'VSS'<69>: CDS_PINID='VSS(69)';
NODE_NAME     J4B1 53
 '@BASEBOARD_FAB2_LIB.BASEBOARD_FAB2(SCH_1):PAGE49_I43@MSTR_SCONN.SCONN288_H44441004(CHIPS)':
 'VSS'<70>: CDS_PINID='VSS(70)';
NODE_NAME     J4B1 50
 '@BASEBOARD_FAB2_LIB.BASEBOARD_FAB2(SCH_1):PAGE49_I43@MSTR_SCONN.SCONN288_H44441004(CHIPS)':
 'VSS'<71>: CDS_PINID='VSS(71)';
NODE_NAME     J4B1 48
 '@BASEBOARD_FAB2_LIB.BASEBOARD_FAB2(SCH_1):PAGE49_I43@MSTR_SCONN.SCONN288_H44441004(CHIPS)':
 'VSS'<72>: CDS_PINID='VSS(72)';
NODE_NAME     J4B1 46
 '@BASEBOARD_FAB2_LIB.BASEBOARD_FAB2(SCH_1):PAGE49_I43@MSTR_SCONN.SCONN288_H44441004(CHIPS)':
 'VSS'<73>: CDS_PINID='VSS(73)';
NODE_NAME     J4B1 44
 '@BASEBOARD_FAB2_LIB.BASEBOARD_FAB2(SCH_1):PAGE49_I43@MSTR_SCONN.SCONN288_H44441004(CHIPS)':
 'VSS'<74>: CDS_PINID='VSS(74)';
NODE_NAME     J4B1 42
 '@BASEBOARD_FAB2_LIB.BASEBOARD_FAB2(SCH_1):PAGE49_I43@MSTR_SCONN.SCONN288_H44441004(CHIPS)':
 'VSS'<75>: CDS_PINID='VSS(75)';
NODE_NAME     J4B1 39
 '@BASEBOARD_FAB2_LIB.BASEBOARD_FAB2(SCH_1):PAGE49_I43@MSTR_SCONN.SCONN288_H44441004(CHIPS)':
 'VSS'<76>: CDS_PINID='VSS(76)';
NODE_NAME     J4B1 37
 '@BASEBOARD_FAB2_LIB.BASEBOARD_FAB2(SCH_1):PAGE49_I43@MSTR_SCONN.SCONN288_H44441004(CHIPS)':
 'VSS'<77>: CDS_PINID='VSS(77)';
NODE_NAME     J4B1 35
 '@BASEBOARD_FAB2_LIB.BASEBOARD_FAB2(SCH_1):PAGE49_I43@MSTR_SCONN.SCONN288_H44441004(CHIPS)':
 'VSS'<78>: CDS_PINID='VSS(78)';
NODE_NAME     J4B1 33
 '@BASEBOARD_FAB2_LIB.BASEBOARD_FAB2(SCH_1):PAGE49_I43@MSTR_SCONN.SCONN288_H44441004(CHIPS)':
 'VSS'<79>: CDS_PINID='VSS(79)';
NODE_NAME     J4B1 31
 '@BASEBOARD_FAB2_LIB.BASEBOARD_FAB2(SCH_1):PAGE49_I43@MSTR_SCONN.SCONN288_H44441004(CHIPS)':
 'VSS'<80>: CDS_PINID='VSS(80)';
NODE_NAME     J4B1 28
 '@BASEBOARD_FAB2_LIB.BASEBOARD_FAB2(SCH_1):PAGE49_I43@MSTR_SCONN.SCONN288_H44441004(CHIPS)':
 'VSS'<81>: CDS_PINID='VSS(81)';
NODE_NAME     J4B1 26
 '@BASEBOARD_FAB2_LIB.BASEBOARD_FAB2(SCH_1):PAGE49_I43@MSTR_SCONN.SCONN288_H44441004(CHIPS)':
 'VSS'<82>: CDS_PINID='VSS(82)';
NODE_NAME     J4B1 24
 '@BASEBOARD_FAB2_LIB.BASEBOARD_FAB2(SCH_1):PAGE49_I43@MSTR_SCONN.SCONN288_H44441004(CHIPS)':
 'VSS'<83>: CDS_PINID='VSS(83)';
NODE_NAME     J4B1 22
 '@BASEBOARD_FAB2_LIB.BASEBOARD_FAB2(SCH_1):PAGE49_I43@MSTR_SCONN.SCONN288_H44441004(CHIPS)':
 'VSS'<84>: CDS_PINID='VSS(84)';
NODE_NAME     J4B1 20
 '@BASEBOARD_FAB2_LIB.BASEBOARD_FAB2(SCH_1):PAGE49_I43@MSTR_SCONN.SCONN288_H44441004(CHIPS)':
 'VSS'<85>: CDS_PINID='VSS(85)';
NODE_NAME     J4B1 17
 '@BASEBOARD_FAB2_LIB.BASEBOARD_FAB2(SCH_1):PAGE49_I43@MSTR_SCONN.SCONN288_H44441004(CHIPS)':
 'VSS'<86>: CDS_PINID='VSS(86)';
NODE_NAME     J4B1 15
 '@BASEBOARD_FAB2_LIB.BASEBOARD_FAB2(SCH_1):PAGE49_I43@MSTR_SCONN.SCONN288_H44441004(CHIPS)':
 'VSS'<87>: CDS_PINID='VSS(87)';
NODE_NAME     J4B1 13
 '@BASEBOARD_FAB2_LIB.BASEBOARD_FAB2(SCH_1):PAGE49_I43@MSTR_SCONN.SCONN288_H44441004(CHIPS)':
 'VSS'<88>: CDS_PINID='VSS(88)';
NODE_NAME     J4B1 11
 '@BASEBOARD_FAB2_LIB.BASEBOARD_FAB2(SCH_1):PAGE49_I43@MSTR_SCONN.SCONN288_H44441004(CHIPS)':
 'VSS'<89>: CDS_PINID='VSS(89)';
NODE_NAME     J4B1 9
 '@BASEBOARD_FAB2_LIB.BASEBOARD_FAB2(SCH_1):PAGE49_I43@MSTR_SCONN.SCONN288_H44441004(CHIPS)':
 'VSS'<90>: CDS_PINID='VSS(90)';
NODE_NAME     J4B1 6
 '@BASEBOARD_FAB2_LIB.BASEBOARD_FAB2(SCH_1):PAGE49_I43@MSTR_SCONN.SCONN288_H44441004(CHIPS)':
 'VSS'<91>: CDS_PINID='VSS(91)';
NODE_NAME     J4B1 4
 '@BASEBOARD_FAB2_LIB.BASEBOARD_FAB2(SCH_1):PAGE49_I43@MSTR_SCONN.SCONN288_H44441004(CHIPS)':
 'VSS'<92>: CDS_PINID='VSS(92)';
NODE_NAME     J4B1 2
 '@BASEBOARD_FAB2_LIB.BASEBOARD_FAB2(SCH_1):PAGE49_I43@MSTR_SCONN.SCONN288_H44441004(CHIPS)':
 'VSS'<93>: CDS_PINID='VSS(93)';
NODE_NAME     J4B1 139
 '@BASEBOARD_FAB2_LIB.BASEBOARD_FAB2(SCH_1):PAGE49_I111@MSTR_SCONN.SCONN288_H44441004(CHIPS)':
 'SA'<0>: CDS_PINID='SA(0)';
NODE_NAME     J4B1 140
 '@BASEBOARD_FAB2_LIB.BASEBOARD_FAB2(SCH_1):PAGE49_I111@MSTR_SCONN.SCONN288_H44441004(CHIPS)':
 'SA'<1>: CDS_PINID='SA(1)';
NODE_NAME     J4B1 238
 '@BASEBOARD_FAB2_LIB.BASEBOARD_FAB2(SCH_1):PAGE49_I111@MSTR_SCONN.SCONN288_H44441004(CHIPS)':
 'SA'<2>: CDS_PINID='SA(2)';
NODE_NAME     C4B12 2
 '@BASEBOARD_FAB2_LIB.BASEBOARD_FAB2(SCH_1):PAGE49_I179@DEV_DISCRETE.CAP_A(CHIPS)':
 'B': CDS_PINID='B';
NODE_NAME     J6M1 283
 '@BASEBOARD_FAB2_LIB.BASEBOARD_FAB2(SCH_1):PAGE50_I44@MSTR_SCONN.SCONN288_H44441003(CHIPS)':
 'VSS'<0>: CDS_PINID='VSS(0)';
NODE_NAME     J6M1 281
 '@BASEBOARD_FAB2_LIB.BASEBOARD_FAB2(SCH_1):PAGE50_I44@MSTR_SCONN.SCONN288_H44441003(CHIPS)':
 'VSS'<1>: CDS_PINID='VSS(1)';
NODE_NAME     J6M1 279
 '@BASEBOARD_FAB2_LIB.BASEBOARD_FAB2(SCH_1):PAGE50_I44@MSTR_SCONN.SCONN288_H44441003(CHIPS)':
 'VSS'<2>: CDS_PINID='VSS(2)';
NODE_NAME     J6M1 276
 '@BASEBOARD_FAB2_LIB.BASEBOARD_FAB2(SCH_1):PAGE50_I44@MSTR_SCONN.SCONN288_H44441003(CHIPS)':
 'VSS'<3>: CDS_PINID='VSS(3)';
NODE_NAME     J6M1 274
 '@BASEBOARD_FAB2_LIB.BASEBOARD_FAB2(SCH_1):PAGE50_I44@MSTR_SCONN.SCONN288_H44441003(CHIPS)':
 'VSS'<4>: CDS_PINID='VSS(4)';
NODE_NAME     J6M1 272
 '@BASEBOARD_FAB2_LIB.BASEBOARD_FAB2(SCH_1):PAGE50_I44@MSTR_SCONN.SCONN288_H44441003(CHIPS)':
 'VSS'<5>: CDS_PINID='VSS(5)';
NODE_NAME     J6M1 270
 '@BASEBOARD_FAB2_LIB.BASEBOARD_FAB2(SCH_1):PAGE50_I44@MSTR_SCONN.SCONN288_H44441003(CHIPS)':
 'VSS'<6>: CDS_PINID='VSS(6)';
NODE_NAME     J6M1 268
 '@BASEBOARD_FAB2_LIB.BASEBOARD_FAB2(SCH_1):PAGE50_I44@MSTR_SCONN.SCONN288_H44441003(CHIPS)':
 'VSS'<7>: CDS_PINID='VSS(7)';
NODE_NAME     J6M1 265
 '@BASEBOARD_FAB2_LIB.BASEBOARD_FAB2(SCH_1):PAGE50_I44@MSTR_SCONN.SCONN288_H44441003(CHIPS)':
 'VSS'<8>: CDS_PINID='VSS(8)';
NODE_NAME     J6M1 263
 '@BASEBOARD_FAB2_LIB.BASEBOARD_FAB2(SCH_1):PAGE50_I44@MSTR_SCONN.SCONN288_H44441003(CHIPS)':
 'VSS'<9>: CDS_PINID='VSS(9)';
NODE_NAME     J6M1 261
 '@BASEBOARD_FAB2_LIB.BASEBOARD_FAB2(SCH_1):PAGE50_I44@MSTR_SCONN.SCONN288_H44441003(CHIPS)':
 'VSS'<10>: CDS_PINID='VSS(10)';
NODE_NAME     J6M1 259
 '@BASEBOARD_FAB2_LIB.BASEBOARD_FAB2(SCH_1):PAGE50_I44@MSTR_SCONN.SCONN288_H44441003(CHIPS)':
 'VSS'<11>: CDS_PINID='VSS(11)';
NODE_NAME     J6M1 257
 '@BASEBOARD_FAB2_LIB.BASEBOARD_FAB2(SCH_1):PAGE50_I44@MSTR_SCONN.SCONN288_H44441003(CHIPS)':
 'VSS'<12>: CDS_PINID='VSS(12)';
NODE_NAME     J6M1 254
 '@BASEBOARD_FAB2_LIB.BASEBOARD_FAB2(SCH_1):PAGE50_I44@MSTR_SCONN.SCONN288_H44441003(CHIPS)':
 'VSS'<13>: CDS_PINID='VSS(13)';
NODE_NAME     J6M1 252
 '@BASEBOARD_FAB2_LIB.BASEBOARD_FAB2(SCH_1):PAGE50_I44@MSTR_SCONN.SCONN288_H44441003(CHIPS)':
 'VSS'<14>: CDS_PINID='VSS(14)';
NODE_NAME     J6M1 250
 '@BASEBOARD_FAB2_LIB.BASEBOARD_FAB2(SCH_1):PAGE50_I44@MSTR_SCONN.SCONN288_H44441003(CHIPS)':
 'VSS'<15>: CDS_PINID='VSS(15)';
NODE_NAME     J6M1 248
 '@BASEBOARD_FAB2_LIB.BASEBOARD_FAB2(SCH_1):PAGE50_I44@MSTR_SCONN.SCONN288_H44441003(CHIPS)':
 'VSS'<16>: CDS_PINID='VSS(16)';
NODE_NAME     J6M1 246
 '@BASEBOARD_FAB2_LIB.BASEBOARD_FAB2(SCH_1):PAGE50_I44@MSTR_SCONN.SCONN288_H44441003(CHIPS)':
 'VSS'<17>: CDS_PINID='VSS(17)';
NODE_NAME     J6M1 243
 '@BASEBOARD_FAB2_LIB.BASEBOARD_FAB2(SCH_1):PAGE50_I44@MSTR_SCONN.SCONN288_H44441003(CHIPS)':
 'VSS'<18>: CDS_PINID='VSS(18)';
NODE_NAME     J6M1 241
 '@BASEBOARD_FAB2_LIB.BASEBOARD_FAB2(SCH_1):PAGE50_I44@MSTR_SCONN.SCONN288_H44441003(CHIPS)':
 'VSS'<19>: CDS_PINID='VSS(19)';
NODE_NAME     J6M1 239
 '@BASEBOARD_FAB2_LIB.BASEBOARD_FAB2(SCH_1):PAGE50_I44@MSTR_SCONN.SCONN288_H44441003(CHIPS)':
 'VSS'<20>: CDS_PINID='VSS(20)';
NODE_NAME     J6M1 202
 '@BASEBOARD_FAB2_LIB.BASEBOARD_FAB2(SCH_1):PAGE50_I44@MSTR_SCONN.SCONN288_H44441003(CHIPS)':
 'VSS'<21>: CDS_PINID='VSS(21)';
NODE_NAME     J6M1 200
 '@BASEBOARD_FAB2_LIB.BASEBOARD_FAB2(SCH_1):PAGE50_I44@MSTR_SCONN.SCONN288_H44441003(CHIPS)':
 'VSS'<22>: CDS_PINID='VSS(22)';
NODE_NAME     J6M1 198
 '@BASEBOARD_FAB2_LIB.BASEBOARD_FAB2(SCH_1):PAGE50_I44@MSTR_SCONN.SCONN288_H44441003(CHIPS)':
 'VSS'<23>: CDS_PINID='VSS(23)';
NODE_NAME     J6M1 195
 '@BASEBOARD_FAB2_LIB.BASEBOARD_FAB2(SCH_1):PAGE50_I44@MSTR_SCONN.SCONN288_H44441003(CHIPS)':
 'VSS'<24>: CDS_PINID='VSS(24)';
NODE_NAME     J6M1 193
 '@BASEBOARD_FAB2_LIB.BASEBOARD_FAB2(SCH_1):PAGE50_I44@MSTR_SCONN.SCONN288_H44441003(CHIPS)':
 'VSS'<25>: CDS_PINID='VSS(25)';
NODE_NAME     J6M1 191
 '@BASEBOARD_FAB2_LIB.BASEBOARD_FAB2(SCH_1):PAGE50_I44@MSTR_SCONN.SCONN288_H44441003(CHIPS)':
 'VSS'<26>: CDS_PINID='VSS(26)';
NODE_NAME     J6M1 189
 '@BASEBOARD_FAB2_LIB.BASEBOARD_FAB2(SCH_1):PAGE50_I44@MSTR_SCONN.SCONN288_H44441003(CHIPS)':
 'VSS'<27>: CDS_PINID='VSS(27)';
NODE_NAME     J6M1 187
 '@BASEBOARD_FAB2_LIB.BASEBOARD_FAB2(SCH_1):PAGE50_I44@MSTR_SCONN.SCONN288_H44441003(CHIPS)':
 'VSS'<28>: CDS_PINID='VSS(28)';
NODE_NAME     J6M1 184
 '@BASEBOARD_FAB2_LIB.BASEBOARD_FAB2(SCH_1):PAGE50_I44@MSTR_SCONN.SCONN288_H44441003(CHIPS)':
 'VSS'<29>: CDS_PINID='VSS(29)';
NODE_NAME     J6M1 182
 '@BASEBOARD_FAB2_LIB.BASEBOARD_FAB2(SCH_1):PAGE50_I44@MSTR_SCONN.SCONN288_H44441003(CHIPS)':
 'VSS'<30>: CDS_PINID='VSS(30)';
NODE_NAME     J6M1 180
 '@BASEBOARD_FAB2_LIB.BASEBOARD_FAB2(SCH_1):PAGE50_I44@MSTR_SCONN.SCONN288_H44441003(CHIPS)':
 'VSS'<31>: CDS_PINID='VSS(31)';
NODE_NAME     J6M1 178
 '@BASEBOARD_FAB2_LIB.BASEBOARD_FAB2(SCH_1):PAGE50_I44@MSTR_SCONN.SCONN288_H44441003(CHIPS)':
 'VSS'<32>: CDS_PINID='VSS(32)';
NODE_NAME     J6M1 176
 '@BASEBOARD_FAB2_LIB.BASEBOARD_FAB2(SCH_1):PAGE50_I44@MSTR_SCONN.SCONN288_H44441003(CHIPS)':
 'VSS'<33>: CDS_PINID='VSS(33)';
NODE_NAME     J6M1 173
 '@BASEBOARD_FAB2_LIB.BASEBOARD_FAB2(SCH_1):PAGE50_I44@MSTR_SCONN.SCONN288_H44441003(CHIPS)':
 'VSS'<34>: CDS_PINID='VSS(34)';
NODE_NAME     J6M1 171
 '@BASEBOARD_FAB2_LIB.BASEBOARD_FAB2(SCH_1):PAGE50_I44@MSTR_SCONN.SCONN288_H44441003(CHIPS)':
 'VSS'<35>: CDS_PINID='VSS(35)';
NODE_NAME     J6M1 169
 '@BASEBOARD_FAB2_LIB.BASEBOARD_FAB2(SCH_1):PAGE50_I44@MSTR_SCONN.SCONN288_H44441003(CHIPS)':
 'VSS'<36>: CDS_PINID='VSS(36)';
NODE_NAME     J6M1 167
 '@BASEBOARD_FAB2_LIB.BASEBOARD_FAB2(SCH_1):PAGE50_I44@MSTR_SCONN.SCONN288_H44441003(CHIPS)':
 'VSS'<37>: CDS_PINID='VSS(37)';
NODE_NAME     J6M1 165
 '@BASEBOARD_FAB2_LIB.BASEBOARD_FAB2(SCH_1):PAGE50_I44@MSTR_SCONN.SCONN288_H44441003(CHIPS)':
 'VSS'<38>: CDS_PINID='VSS(38)';
NODE_NAME     J6M1 162
 '@BASEBOARD_FAB2_LIB.BASEBOARD_FAB2(SCH_1):PAGE50_I44@MSTR_SCONN.SCONN288_H44441003(CHIPS)':
 'VSS'<39>: CDS_PINID='VSS(39)';
NODE_NAME     J6M1 160
 '@BASEBOARD_FAB2_LIB.BASEBOARD_FAB2(SCH_1):PAGE50_I44@MSTR_SCONN.SCONN288_H44441003(CHIPS)':
 'VSS'<40>: CDS_PINID='VSS(40)';
NODE_NAME     J6M1 158
 '@BASEBOARD_FAB2_LIB.BASEBOARD_FAB2(SCH_1):PAGE50_I44@MSTR_SCONN.SCONN288_H44441003(CHIPS)':
 'VSS'<41>: CDS_PINID='VSS(41)';
NODE_NAME     J6M1 156
 '@BASEBOARD_FAB2_LIB.BASEBOARD_FAB2(SCH_1):PAGE50_I44@MSTR_SCONN.SCONN288_H44441003(CHIPS)':
 'VSS'<42>: CDS_PINID='VSS(42)';
NODE_NAME     J6M1 154
 '@BASEBOARD_FAB2_LIB.BASEBOARD_FAB2(SCH_1):PAGE50_I44@MSTR_SCONN.SCONN288_H44441003(CHIPS)':
 'VSS'<43>: CDS_PINID='VSS(43)';
NODE_NAME     J6M1 151
 '@BASEBOARD_FAB2_LIB.BASEBOARD_FAB2(SCH_1):PAGE50_I44@MSTR_SCONN.SCONN288_H44441003(CHIPS)':
 'VSS'<44>: CDS_PINID='VSS(44)';
NODE_NAME     J6M1 149
 '@BASEBOARD_FAB2_LIB.BASEBOARD_FAB2(SCH_1):PAGE50_I44@MSTR_SCONN.SCONN288_H44441003(CHIPS)':
 'VSS'<45>: CDS_PINID='VSS(45)';
NODE_NAME     J6M1 147
 '@BASEBOARD_FAB2_LIB.BASEBOARD_FAB2(SCH_1):PAGE50_I44@MSTR_SCONN.SCONN288_H44441003(CHIPS)':
 'VSS'<46>: CDS_PINID='VSS(46)';
NODE_NAME     J6M1 138
 '@BASEBOARD_FAB2_LIB.BASEBOARD_FAB2(SCH_1):PAGE50_I44@MSTR_SCONN.SCONN288_H44441003(CHIPS)':
 'VSS'<47>: CDS_PINID='VSS(47)';
NODE_NAME     J6M1 136
 '@BASEBOARD_FAB2_LIB.BASEBOARD_FAB2(SCH_1):PAGE50_I44@MSTR_SCONN.SCONN288_H44441003(CHIPS)':
 'VSS'<48>: CDS_PINID='VSS(48)';
NODE_NAME     J6M1 134
 '@BASEBOARD_FAB2_LIB.BASEBOARD_FAB2(SCH_1):PAGE50_I44@MSTR_SCONN.SCONN288_H44441003(CHIPS)':
 'VSS'<49>: CDS_PINID='VSS(49)';
NODE_NAME     J6M1 131
 '@BASEBOARD_FAB2_LIB.BASEBOARD_FAB2(SCH_1):PAGE50_I44@MSTR_SCONN.SCONN288_H44441003(CHIPS)':
 'VSS'<50>: CDS_PINID='VSS(50)';
NODE_NAME     J6M1 129
 '@BASEBOARD_FAB2_LIB.BASEBOARD_FAB2(SCH_1):PAGE50_I44@MSTR_SCONN.SCONN288_H44441003(CHIPS)':
 'VSS'<51>: CDS_PINID='VSS(51)';
NODE_NAME     J6M1 127
 '@BASEBOARD_FAB2_LIB.BASEBOARD_FAB2(SCH_1):PAGE50_I44@MSTR_SCONN.SCONN288_H44441003(CHIPS)':
 'VSS'<52>: CDS_PINID='VSS(52)';
NODE_NAME     J6M1 125
 '@BASEBOARD_FAB2_LIB.BASEBOARD_FAB2(SCH_1):PAGE50_I44@MSTR_SCONN.SCONN288_H44441003(CHIPS)':
 'VSS'<53>: CDS_PINID='VSS(53)';
NODE_NAME     J6M1 123
 '@BASEBOARD_FAB2_LIB.BASEBOARD_FAB2(SCH_1):PAGE50_I44@MSTR_SCONN.SCONN288_H44441003(CHIPS)':
 'VSS'<54>: CDS_PINID='VSS(54)';
NODE_NAME     J6M1 120
 '@BASEBOARD_FAB2_LIB.BASEBOARD_FAB2(SCH_1):PAGE50_I44@MSTR_SCONN.SCONN288_H44441003(CHIPS)':
 'VSS'<55>: CDS_PINID='VSS(55)';
NODE_NAME     J6M1 118
 '@BASEBOARD_FAB2_LIB.BASEBOARD_FAB2(SCH_1):PAGE50_I44@MSTR_SCONN.SCONN288_H44441003(CHIPS)':
 'VSS'<56>: CDS_PINID='VSS(56)';
NODE_NAME     J6M1 116
 '@BASEBOARD_FAB2_LIB.BASEBOARD_FAB2(SCH_1):PAGE50_I44@MSTR_SCONN.SCONN288_H44441003(CHIPS)':
 'VSS'<57>: CDS_PINID='VSS(57)';
NODE_NAME     J6M1 114
 '@BASEBOARD_FAB2_LIB.BASEBOARD_FAB2(SCH_1):PAGE50_I44@MSTR_SCONN.SCONN288_H44441003(CHIPS)':
 'VSS'<58>: CDS_PINID='VSS(58)';
NODE_NAME     J6M1 112
 '@BASEBOARD_FAB2_LIB.BASEBOARD_FAB2(SCH_1):PAGE50_I44@MSTR_SCONN.SCONN288_H44441003(CHIPS)':
 'VSS'<59>: CDS_PINID='VSS(59)';
NODE_NAME     J6M1 109
 '@BASEBOARD_FAB2_LIB.BASEBOARD_FAB2(SCH_1):PAGE50_I44@MSTR_SCONN.SCONN288_H44441003(CHIPS)':
 'VSS'<60>: CDS_PINID='VSS(60)';
NODE_NAME     J6M1 107
 '@BASEBOARD_FAB2_LIB.BASEBOARD_FAB2(SCH_1):PAGE50_I44@MSTR_SCONN.SCONN288_H44441003(CHIPS)':
 'VSS'<61>: CDS_PINID='VSS(61)';
NODE_NAME     J6M1 105
 '@BASEBOARD_FAB2_LIB.BASEBOARD_FAB2(SCH_1):PAGE50_I44@MSTR_SCONN.SCONN288_H44441003(CHIPS)':
 'VSS'<62>: CDS_PINID='VSS(62)';
NODE_NAME     J6M1 103
 '@BASEBOARD_FAB2_LIB.BASEBOARD_FAB2(SCH_1):PAGE50_I44@MSTR_SCONN.SCONN288_H44441003(CHIPS)':
 'VSS'<63>: CDS_PINID='VSS(63)';
NODE_NAME     J6M1 101
 '@BASEBOARD_FAB2_LIB.BASEBOARD_FAB2(SCH_1):PAGE50_I44@MSTR_SCONN.SCONN288_H44441003(CHIPS)':
 'VSS'<64>: CDS_PINID='VSS(64)';
NODE_NAME     J6M1 98
 '@BASEBOARD_FAB2_LIB.BASEBOARD_FAB2(SCH_1):PAGE50_I44@MSTR_SCONN.SCONN288_H44441003(CHIPS)':
 'VSS'<65>: CDS_PINID='VSS(65)';
NODE_NAME     J6M1 96
 '@BASEBOARD_FAB2_LIB.BASEBOARD_FAB2(SCH_1):PAGE50_I44@MSTR_SCONN.SCONN288_H44441003(CHIPS)':
 'VSS'<66>: CDS_PINID='VSS(66)';
NODE_NAME     J6M1 94
 '@BASEBOARD_FAB2_LIB.BASEBOARD_FAB2(SCH_1):PAGE50_I44@MSTR_SCONN.SCONN288_H44441003(CHIPS)':
 'VSS'<67>: CDS_PINID='VSS(67)';
NODE_NAME     J6M1 57
 '@BASEBOARD_FAB2_LIB.BASEBOARD_FAB2(SCH_1):PAGE50_I44@MSTR_SCONN.SCONN288_H44441003(CHIPS)':
 'VSS'<68>: CDS_PINID='VSS(68)';
NODE_NAME     J6M1 55
 '@BASEBOARD_FAB2_LIB.BASEBOARD_FAB2(SCH_1):PAGE50_I44@MSTR_SCONN.SCONN288_H44441003(CHIPS)':
 'VSS'<69>: CDS_PINID='VSS(69)';
NODE_NAME     J6M1 53
 '@BASEBOARD_FAB2_LIB.BASEBOARD_FAB2(SCH_1):PAGE50_I44@MSTR_SCONN.SCONN288_H44441003(CHIPS)':
 'VSS'<70>: CDS_PINID='VSS(70)';
NODE_NAME     J6M1 50
 '@BASEBOARD_FAB2_LIB.BASEBOARD_FAB2(SCH_1):PAGE50_I44@MSTR_SCONN.SCONN288_H44441003(CHIPS)':
 'VSS'<71>: CDS_PINID='VSS(71)';
NODE_NAME     J6M1 48
 '@BASEBOARD_FAB2_LIB.BASEBOARD_FAB2(SCH_1):PAGE50_I44@MSTR_SCONN.SCONN288_H44441003(CHIPS)':
 'VSS'<72>: CDS_PINID='VSS(72)';
NODE_NAME     J6M1 46
 '@BASEBOARD_FAB2_LIB.BASEBOARD_FAB2(SCH_1):PAGE50_I44@MSTR_SCONN.SCONN288_H44441003(CHIPS)':
 'VSS'<73>: CDS_PINID='VSS(73)';
NODE_NAME     J6M1 44
 '@BASEBOARD_FAB2_LIB.BASEBOARD_FAB2(SCH_1):PAGE50_I44@MSTR_SCONN.SCONN288_H44441003(CHIPS)':
 'VSS'<74>: CDS_PINID='VSS(74)';
NODE_NAME     J6M1 42
 '@BASEBOARD_FAB2_LIB.BASEBOARD_FAB2(SCH_1):PAGE50_I44@MSTR_SCONN.SCONN288_H44441003(CHIPS)':
 'VSS'<75>: CDS_PINID='VSS(75)';
NODE_NAME     J6M1 39
 '@BASEBOARD_FAB2_LIB.BASEBOARD_FAB2(SCH_1):PAGE50_I44@MSTR_SCONN.SCONN288_H44441003(CHIPS)':
 'VSS'<76>: CDS_PINID='VSS(76)';
NODE_NAME     J6M1 37
 '@BASEBOARD_FAB2_LIB.BASEBOARD_FAB2(SCH_1):PAGE50_I44@MSTR_SCONN.SCONN288_H44441003(CHIPS)':
 'VSS'<77>: CDS_PINID='VSS(77)';
NODE_NAME     J6M1 35
 '@BASEBOARD_FAB2_LIB.BASEBOARD_FAB2(SCH_1):PAGE50_I44@MSTR_SCONN.SCONN288_H44441003(CHIPS)':
 'VSS'<78>: CDS_PINID='VSS(78)';
NODE_NAME     J6M1 33
 '@BASEBOARD_FAB2_LIB.BASEBOARD_FAB2(SCH_1):PAGE50_I44@MSTR_SCONN.SCONN288_H44441003(CHIPS)':
 'VSS'<79>: CDS_PINID='VSS(79)';
NODE_NAME     J6M1 31
 '@BASEBOARD_FAB2_LIB.BASEBOARD_FAB2(SCH_1):PAGE50_I44@MSTR_SCONN.SCONN288_H44441003(CHIPS)':
 'VSS'<80>: CDS_PINID='VSS(80)';
NODE_NAME     J6M1 28
 '@BASEBOARD_FAB2_LIB.BASEBOARD_FAB2(SCH_1):PAGE50_I44@MSTR_SCONN.SCONN288_H44441003(CHIPS)':
 'VSS'<81>: CDS_PINID='VSS(81)';
NODE_NAME     J6M1 26
 '@BASEBOARD_FAB2_LIB.BASEBOARD_FAB2(SCH_1):PAGE50_I44@MSTR_SCONN.SCONN288_H44441003(CHIPS)':
 'VSS'<82>: CDS_PINID='VSS(82)';
NODE_NAME     J6M1 24
 '@BASEBOARD_FAB2_LIB.BASEBOARD_FAB2(SCH_1):PAGE50_I44@MSTR_SCONN.SCONN288_H44441003(CHIPS)':
 'VSS'<83>: CDS_PINID='VSS(83)';
NODE_NAME     J6M1 22
 '@BASEBOARD_FAB2_LIB.BASEBOARD_FAB2(SCH_1):PAGE50_I44@MSTR_SCONN.SCONN288_H44441003(CHIPS)':
 'VSS'<84>: CDS_PINID='VSS(84)';
NODE_NAME     J6M1 20
 '@BASEBOARD_FAB2_LIB.BASEBOARD_FAB2(SCH_1):PAGE50_I44@MSTR_SCONN.SCONN288_H44441003(CHIPS)':
 'VSS'<85>: CDS_PINID='VSS(85)';
NODE_NAME     J6M1 17
 '@BASEBOARD_FAB2_LIB.BASEBOARD_FAB2(SCH_1):PAGE50_I44@MSTR_SCONN.SCONN288_H44441003(CHIPS)':
 'VSS'<86>: CDS_PINID='VSS(86)';
NODE_NAME     J6M1 15
 '@BASEBOARD_FAB2_LIB.BASEBOARD_FAB2(SCH_1):PAGE50_I44@MSTR_SCONN.SCONN288_H44441003(CHIPS)':
 'VSS'<87>: CDS_PINID='VSS(87)';
NODE_NAME     J6M1 13
 '@BASEBOARD_FAB2_LIB.BASEBOARD_FAB2(SCH_1):PAGE50_I44@MSTR_SCONN.SCONN288_H44441003(CHIPS)':
 'VSS'<88>: CDS_PINID='VSS(88)';
NODE_NAME     J6M1 11
 '@BASEBOARD_FAB2_LIB.BASEBOARD_FAB2(SCH_1):PAGE50_I44@MSTR_SCONN.SCONN288_H44441003(CHIPS)':
 'VSS'<89>: CDS_PINID='VSS(89)';
NODE_NAME     J6M1 9
 '@BASEBOARD_FAB2_LIB.BASEBOARD_FAB2(SCH_1):PAGE50_I44@MSTR_SCONN.SCONN288_H44441003(CHIPS)':
 'VSS'<90>: CDS_PINID='VSS(90)';
NODE_NAME     J6M1 6
 '@BASEBOARD_FAB2_LIB.BASEBOARD_FAB2(SCH_1):PAGE50_I44@MSTR_SCONN.SCONN288_H44441003(CHIPS)':
 'VSS'<91>: CDS_PINID='VSS(91)';
NODE_NAME     J6M1 4
 '@BASEBOARD_FAB2_LIB.BASEBOARD_FAB2(SCH_1):PAGE50_I44@MSTR_SCONN.SCONN288_H44441003(CHIPS)':
 'VSS'<92>: CDS_PINID='VSS(92)';
NODE_NAME     J6M1 2
 '@BASEBOARD_FAB2_LIB.BASEBOARD_FAB2(SCH_1):PAGE50_I44@MSTR_SCONN.SCONN288_H44441003(CHIPS)':
 'VSS'<93>: CDS_PINID='VSS(93)';
NODE_NAME     J6M1 140
 '@BASEBOARD_FAB2_LIB.BASEBOARD_FAB2(SCH_1):PAGE50_I158@MSTR_SCONN.SCONN288_H44441003(CHIPS)':
 'SA'<1>: CDS_PINID='SA(1)';
NODE_NAME     J6M1 238
 '@BASEBOARD_FAB2_LIB.BASEBOARD_FAB2(SCH_1):PAGE50_I158@MSTR_SCONN.SCONN288_H44441003(CHIPS)':
 'SA'<2>: CDS_PINID='SA(2)';
NODE_NAME     C6M1 2
 '@BASEBOARD_FAB2_LIB.BASEBOARD_FAB2(SCH_1):PAGE50_I177@DEV_DISCRETE.CAP_A(CHIPS)':
 'B': CDS_PINID='B';
NODE_NAME     J4A2 283
 '@BASEBOARD_FAB2_LIB.BASEBOARD_FAB2(SCH_1):PAGE51_I43@MSTR_SCONN.SCONN288_H44441004(CHIPS)':
 'VSS'<0>: CDS_PINID='VSS(0)';
NODE_NAME     J4A2 281
 '@BASEBOARD_FAB2_LIB.BASEBOARD_FAB2(SCH_1):PAGE51_I43@MSTR_SCONN.SCONN288_H44441004(CHIPS)':
 'VSS'<1>: CDS_PINID='VSS(1)';
NODE_NAME     J4A2 279
 '@BASEBOARD_FAB2_LIB.BASEBOARD_FAB2(SCH_1):PAGE51_I43@MSTR_SCONN.SCONN288_H44441004(CHIPS)':
 'VSS'<2>: CDS_PINID='VSS(2)';
NODE_NAME     J4A2 276
 '@BASEBOARD_FAB2_LIB.BASEBOARD_FAB2(SCH_1):PAGE51_I43@MSTR_SCONN.SCONN288_H44441004(CHIPS)':
 'VSS'<3>: CDS_PINID='VSS(3)';
NODE_NAME     J4A2 274
 '@BASEBOARD_FAB2_LIB.BASEBOARD_FAB2(SCH_1):PAGE51_I43@MSTR_SCONN.SCONN288_H44441004(CHIPS)':
 'VSS'<4>: CDS_PINID='VSS(4)';
NODE_NAME     J4A2 272
 '@BASEBOARD_FAB2_LIB.BASEBOARD_FAB2(SCH_1):PAGE51_I43@MSTR_SCONN.SCONN288_H44441004(CHIPS)':
 'VSS'<5>: CDS_PINID='VSS(5)';
NODE_NAME     J4A2 270
 '@BASEBOARD_FAB2_LIB.BASEBOARD_FAB2(SCH_1):PAGE51_I43@MSTR_SCONN.SCONN288_H44441004(CHIPS)':
 'VSS'<6>: CDS_PINID='VSS(6)';
NODE_NAME     J4A2 268
 '@BASEBOARD_FAB2_LIB.BASEBOARD_FAB2(SCH_1):PAGE51_I43@MSTR_SCONN.SCONN288_H44441004(CHIPS)':
 'VSS'<7>: CDS_PINID='VSS(7)';
NODE_NAME     J4A2 265
 '@BASEBOARD_FAB2_LIB.BASEBOARD_FAB2(SCH_1):PAGE51_I43@MSTR_SCONN.SCONN288_H44441004(CHIPS)':
 'VSS'<8>: CDS_PINID='VSS(8)';
NODE_NAME     J4A2 263
 '@BASEBOARD_FAB2_LIB.BASEBOARD_FAB2(SCH_1):PAGE51_I43@MSTR_SCONN.SCONN288_H44441004(CHIPS)':
 'VSS'<9>: CDS_PINID='VSS(9)';
NODE_NAME     J4A2 261
 '@BASEBOARD_FAB2_LIB.BASEBOARD_FAB2(SCH_1):PAGE51_I43@MSTR_SCONN.SCONN288_H44441004(CHIPS)':
 'VSS'<10>: CDS_PINID='VSS(10)';
NODE_NAME     J4A2 259
 '@BASEBOARD_FAB2_LIB.BASEBOARD_FAB2(SCH_1):PAGE51_I43@MSTR_SCONN.SCONN288_H44441004(CHIPS)':
 'VSS'<11>: CDS_PINID='VSS(11)';
NODE_NAME     J4A2 257
 '@BASEBOARD_FAB2_LIB.BASEBOARD_FAB2(SCH_1):PAGE51_I43@MSTR_SCONN.SCONN288_H44441004(CHIPS)':
 'VSS'<12>: CDS_PINID='VSS(12)';
NODE_NAME     J4A2 254
 '@BASEBOARD_FAB2_LIB.BASEBOARD_FAB2(SCH_1):PAGE51_I43@MSTR_SCONN.SCONN288_H44441004(CHIPS)':
 'VSS'<13>: CDS_PINID='VSS(13)';
NODE_NAME     J4A2 252
 '@BASEBOARD_FAB2_LIB.BASEBOARD_FAB2(SCH_1):PAGE51_I43@MSTR_SCONN.SCONN288_H44441004(CHIPS)':
 'VSS'<14>: CDS_PINID='VSS(14)';
NODE_NAME     J4A2 250
 '@BASEBOARD_FAB2_LIB.BASEBOARD_FAB2(SCH_1):PAGE51_I43@MSTR_SCONN.SCONN288_H44441004(CHIPS)':
 'VSS'<15>: CDS_PINID='VSS(15)';
NODE_NAME     J4A2 248
 '@BASEBOARD_FAB2_LIB.BASEBOARD_FAB2(SCH_1):PAGE51_I43@MSTR_SCONN.SCONN288_H44441004(CHIPS)':
 'VSS'<16>: CDS_PINID='VSS(16)';
NODE_NAME     J4A2 246
 '@BASEBOARD_FAB2_LIB.BASEBOARD_FAB2(SCH_1):PAGE51_I43@MSTR_SCONN.SCONN288_H44441004(CHIPS)':
 'VSS'<17>: CDS_PINID='VSS(17)';
NODE_NAME     J4A2 243
 '@BASEBOARD_FAB2_LIB.BASEBOARD_FAB2(SCH_1):PAGE51_I43@MSTR_SCONN.SCONN288_H44441004(CHIPS)':
 'VSS'<18>: CDS_PINID='VSS(18)';
NODE_NAME     J4A2 241
 '@BASEBOARD_FAB2_LIB.BASEBOARD_FAB2(SCH_1):PAGE51_I43@MSTR_SCONN.SCONN288_H44441004(CHIPS)':
 'VSS'<19>: CDS_PINID='VSS(19)';
NODE_NAME     J4A2 239
 '@BASEBOARD_FAB2_LIB.BASEBOARD_FAB2(SCH_1):PAGE51_I43@MSTR_SCONN.SCONN288_H44441004(CHIPS)':
 'VSS'<20>: CDS_PINID='VSS(20)';
NODE_NAME     J4A2 202
 '@BASEBOARD_FAB2_LIB.BASEBOARD_FAB2(SCH_1):PAGE51_I43@MSTR_SCONN.SCONN288_H44441004(CHIPS)':
 'VSS'<21>: CDS_PINID='VSS(21)';
NODE_NAME     J4A2 200
 '@BASEBOARD_FAB2_LIB.BASEBOARD_FAB2(SCH_1):PAGE51_I43@MSTR_SCONN.SCONN288_H44441004(CHIPS)':
 'VSS'<22>: CDS_PINID='VSS(22)';
NODE_NAME     J4A2 198
 '@BASEBOARD_FAB2_LIB.BASEBOARD_FAB2(SCH_1):PAGE51_I43@MSTR_SCONN.SCONN288_H44441004(CHIPS)':
 'VSS'<23>: CDS_PINID='VSS(23)';
NODE_NAME     J4A2 195
 '@BASEBOARD_FAB2_LIB.BASEBOARD_FAB2(SCH_1):PAGE51_I43@MSTR_SCONN.SCONN288_H44441004(CHIPS)':
 'VSS'<24>: CDS_PINID='VSS(24)';
NODE_NAME     J4A2 193
 '@BASEBOARD_FAB2_LIB.BASEBOARD_FAB2(SCH_1):PAGE51_I43@MSTR_SCONN.SCONN288_H44441004(CHIPS)':
 'VSS'<25>: CDS_PINID='VSS(25)';
NODE_NAME     J4A2 191
 '@BASEBOARD_FAB2_LIB.BASEBOARD_FAB2(SCH_1):PAGE51_I43@MSTR_SCONN.SCONN288_H44441004(CHIPS)':
 'VSS'<26>: CDS_PINID='VSS(26)';
NODE_NAME     J4A2 189
 '@BASEBOARD_FAB2_LIB.BASEBOARD_FAB2(SCH_1):PAGE51_I43@MSTR_SCONN.SCONN288_H44441004(CHIPS)':
 'VSS'<27>: CDS_PINID='VSS(27)';
NODE_NAME     J4A2 187
 '@BASEBOARD_FAB2_LIB.BASEBOARD_FAB2(SCH_1):PAGE51_I43@MSTR_SCONN.SCONN288_H44441004(CHIPS)':
 'VSS'<28>: CDS_PINID='VSS(28)';
NODE_NAME     J4A2 184
 '@BASEBOARD_FAB2_LIB.BASEBOARD_FAB2(SCH_1):PAGE51_I43@MSTR_SCONN.SCONN288_H44441004(CHIPS)':
 'VSS'<29>: CDS_PINID='VSS(29)';
NODE_NAME     J4A2 182
 '@BASEBOARD_FAB2_LIB.BASEBOARD_FAB2(SCH_1):PAGE51_I43@MSTR_SCONN.SCONN288_H44441004(CHIPS)':
 'VSS'<30>: CDS_PINID='VSS(30)';
NODE_NAME     J4A2 180
 '@BASEBOARD_FAB2_LIB.BASEBOARD_FAB2(SCH_1):PAGE51_I43@MSTR_SCONN.SCONN288_H44441004(CHIPS)':
 'VSS'<31>: CDS_PINID='VSS(31)';
NODE_NAME     J4A2 178
 '@BASEBOARD_FAB2_LIB.BASEBOARD_FAB2(SCH_1):PAGE51_I43@MSTR_SCONN.SCONN288_H44441004(CHIPS)':
 'VSS'<32>: CDS_PINID='VSS(32)';
NODE_NAME     J4A2 176
 '@BASEBOARD_FAB2_LIB.BASEBOARD_FAB2(SCH_1):PAGE51_I43@MSTR_SCONN.SCONN288_H44441004(CHIPS)':
 'VSS'<33>: CDS_PINID='VSS(33)';
NODE_NAME     J4A2 173
 '@BASEBOARD_FAB2_LIB.BASEBOARD_FAB2(SCH_1):PAGE51_I43@MSTR_SCONN.SCONN288_H44441004(CHIPS)':
 'VSS'<34>: CDS_PINID='VSS(34)';
NODE_NAME     J4A2 171
 '@BASEBOARD_FAB2_LIB.BASEBOARD_FAB2(SCH_1):PAGE51_I43@MSTR_SCONN.SCONN288_H44441004(CHIPS)':
 'VSS'<35>: CDS_PINID='VSS(35)';
NODE_NAME     J4A2 169
 '@BASEBOARD_FAB2_LIB.BASEBOARD_FAB2(SCH_1):PAGE51_I43@MSTR_SCONN.SCONN288_H44441004(CHIPS)':
 'VSS'<36>: CDS_PINID='VSS(36)';
NODE_NAME     J4A2 167
 '@BASEBOARD_FAB2_LIB.BASEBOARD_FAB2(SCH_1):PAGE51_I43@MSTR_SCONN.SCONN288_H44441004(CHIPS)':
 'VSS'<37>: CDS_PINID='VSS(37)';
NODE_NAME     J4A2 165
 '@BASEBOARD_FAB2_LIB.BASEBOARD_FAB2(SCH_1):PAGE51_I43@MSTR_SCONN.SCONN288_H44441004(CHIPS)':
 'VSS'<38>: CDS_PINID='VSS(38)';
NODE_NAME     J4A2 162
 '@BASEBOARD_FAB2_LIB.BASEBOARD_FAB2(SCH_1):PAGE51_I43@MSTR_SCONN.SCONN288_H44441004(CHIPS)':
 'VSS'<39>: CDS_PINID='VSS(39)';
NODE_NAME     J4A2 160
 '@BASEBOARD_FAB2_LIB.BASEBOARD_FAB2(SCH_1):PAGE51_I43@MSTR_SCONN.SCONN288_H44441004(CHIPS)':
 'VSS'<40>: CDS_PINID='VSS(40)';
NODE_NAME     J4A2 158
 '@BASEBOARD_FAB2_LIB.BASEBOARD_FAB2(SCH_1):PAGE51_I43@MSTR_SCONN.SCONN288_H44441004(CHIPS)':
 'VSS'<41>: CDS_PINID='VSS(41)';
NODE_NAME     J4A2 156
 '@BASEBOARD_FAB2_LIB.BASEBOARD_FAB2(SCH_1):PAGE51_I43@MSTR_SCONN.SCONN288_H44441004(CHIPS)':
 'VSS'<42>: CDS_PINID='VSS(42)';
NODE_NAME     J4A2 154
 '@BASEBOARD_FAB2_LIB.BASEBOARD_FAB2(SCH_1):PAGE51_I43@MSTR_SCONN.SCONN288_H44441004(CHIPS)':
 'VSS'<43>: CDS_PINID='VSS(43)';
NODE_NAME     J4A2 151
 '@BASEBOARD_FAB2_LIB.BASEBOARD_FAB2(SCH_1):PAGE51_I43@MSTR_SCONN.SCONN288_H44441004(CHIPS)':
 'VSS'<44>: CDS_PINID='VSS(44)';
NODE_NAME     J4A2 149
 '@BASEBOARD_FAB2_LIB.BASEBOARD_FAB2(SCH_1):PAGE51_I43@MSTR_SCONN.SCONN288_H44441004(CHIPS)':
 'VSS'<45>: CDS_PINID='VSS(45)';
NODE_NAME     J4A2 147
 '@BASEBOARD_FAB2_LIB.BASEBOARD_FAB2(SCH_1):PAGE51_I43@MSTR_SCONN.SCONN288_H44441004(CHIPS)':
 'VSS'<46>: CDS_PINID='VSS(46)';
NODE_NAME     J4A2 138
 '@BASEBOARD_FAB2_LIB.BASEBOARD_FAB2(SCH_1):PAGE51_I43@MSTR_SCONN.SCONN288_H44441004(CHIPS)':
 'VSS'<47>: CDS_PINID='VSS(47)';
NODE_NAME     J4A2 136
 '@BASEBOARD_FAB2_LIB.BASEBOARD_FAB2(SCH_1):PAGE51_I43@MSTR_SCONN.SCONN288_H44441004(CHIPS)':
 'VSS'<48>: CDS_PINID='VSS(48)';
NODE_NAME     J4A2 134
 '@BASEBOARD_FAB2_LIB.BASEBOARD_FAB2(SCH_1):PAGE51_I43@MSTR_SCONN.SCONN288_H44441004(CHIPS)':
 'VSS'<49>: CDS_PINID='VSS(49)';
NODE_NAME     J4A2 131
 '@BASEBOARD_FAB2_LIB.BASEBOARD_FAB2(SCH_1):PAGE51_I43@MSTR_SCONN.SCONN288_H44441004(CHIPS)':
 'VSS'<50>: CDS_PINID='VSS(50)';
NODE_NAME     J4A2 129
 '@BASEBOARD_FAB2_LIB.BASEBOARD_FAB2(SCH_1):PAGE51_I43@MSTR_SCONN.SCONN288_H44441004(CHIPS)':
 'VSS'<51>: CDS_PINID='VSS(51)';
NODE_NAME     J4A2 127
 '@BASEBOARD_FAB2_LIB.BASEBOARD_FAB2(SCH_1):PAGE51_I43@MSTR_SCONN.SCONN288_H44441004(CHIPS)':
 'VSS'<52>: CDS_PINID='VSS(52)';
NODE_NAME     J4A2 125
 '@BASEBOARD_FAB2_LIB.BASEBOARD_FAB2(SCH_1):PAGE51_I43@MSTR_SCONN.SCONN288_H44441004(CHIPS)':
 'VSS'<53>: CDS_PINID='VSS(53)';
NODE_NAME     J4A2 123
 '@BASEBOARD_FAB2_LIB.BASEBOARD_FAB2(SCH_1):PAGE51_I43@MSTR_SCONN.SCONN288_H44441004(CHIPS)':
 'VSS'<54>: CDS_PINID='VSS(54)';
NODE_NAME     J4A2 120
 '@BASEBOARD_FAB2_LIB.BASEBOARD_FAB2(SCH_1):PAGE51_I43@MSTR_SCONN.SCONN288_H44441004(CHIPS)':
 'VSS'<55>: CDS_PINID='VSS(55)';
NODE_NAME     J4A2 118
 '@BASEBOARD_FAB2_LIB.BASEBOARD_FAB2(SCH_1):PAGE51_I43@MSTR_SCONN.SCONN288_H44441004(CHIPS)':
 'VSS'<56>: CDS_PINID='VSS(56)';
NODE_NAME     J4A2 116
 '@BASEBOARD_FAB2_LIB.BASEBOARD_FAB2(SCH_1):PAGE51_I43@MSTR_SCONN.SCONN288_H44441004(CHIPS)':
 'VSS'<57>: CDS_PINID='VSS(57)';
NODE_NAME     J4A2 114
 '@BASEBOARD_FAB2_LIB.BASEBOARD_FAB2(SCH_1):PAGE51_I43@MSTR_SCONN.SCONN288_H44441004(CHIPS)':
 'VSS'<58>: CDS_PINID='VSS(58)';
NODE_NAME     J4A2 112
 '@BASEBOARD_FAB2_LIB.BASEBOARD_FAB2(SCH_1):PAGE51_I43@MSTR_SCONN.SCONN288_H44441004(CHIPS)':
 'VSS'<59>: CDS_PINID='VSS(59)';
NODE_NAME     J4A2 109
 '@BASEBOARD_FAB2_LIB.BASEBOARD_FAB2(SCH_1):PAGE51_I43@MSTR_SCONN.SCONN288_H44441004(CHIPS)':
 'VSS'<60>: CDS_PINID='VSS(60)';
NODE_NAME     J4A2 107
 '@BASEBOARD_FAB2_LIB.BASEBOARD_FAB2(SCH_1):PAGE51_I43@MSTR_SCONN.SCONN288_H44441004(CHIPS)':
 'VSS'<61>: CDS_PINID='VSS(61)';
NODE_NAME     J4A2 105
 '@BASEBOARD_FAB2_LIB.BASEBOARD_FAB2(SCH_1):PAGE51_I43@MSTR_SCONN.SCONN288_H44441004(CHIPS)':
 'VSS'<62>: CDS_PINID='VSS(62)';
NODE_NAME     J4A2 103
 '@BASEBOARD_FAB2_LIB.BASEBOARD_FAB2(SCH_1):PAGE51_I43@MSTR_SCONN.SCONN288_H44441004(CHIPS)':
 'VSS'<63>: CDS_PINID='VSS(63)';
NODE_NAME     J4A2 101
 '@BASEBOARD_FAB2_LIB.BASEBOARD_FAB2(SCH_1):PAGE51_I43@MSTR_SCONN.SCONN288_H44441004(CHIPS)':
 'VSS'<64>: CDS_PINID='VSS(64)';
NODE_NAME     J4A2 98
 '@BASEBOARD_FAB2_LIB.BASEBOARD_FAB2(SCH_1):PAGE51_I43@MSTR_SCONN.SCONN288_H44441004(CHIPS)':
 'VSS'<65>: CDS_PINID='VSS(65)';
NODE_NAME     J4A2 96
 '@BASEBOARD_FAB2_LIB.BASEBOARD_FAB2(SCH_1):PAGE51_I43@MSTR_SCONN.SCONN288_H44441004(CHIPS)':
 'VSS'<66>: CDS_PINID='VSS(66)';
NODE_NAME     J4A2 94
 '@BASEBOARD_FAB2_LIB.BASEBOARD_FAB2(SCH_1):PAGE51_I43@MSTR_SCONN.SCONN288_H44441004(CHIPS)':
 'VSS'<67>: CDS_PINID='VSS(67)';
NODE_NAME     J4A2 57
 '@BASEBOARD_FAB2_LIB.BASEBOARD_FAB2(SCH_1):PAGE51_I43@MSTR_SCONN.SCONN288_H44441004(CHIPS)':
 'VSS'<68>: CDS_PINID='VSS(68)';
NODE_NAME     J4A2 55
 '@BASEBOARD_FAB2_LIB.BASEBOARD_FAB2(SCH_1):PAGE51_I43@MSTR_SCONN.SCONN288_H44441004(CHIPS)':
 'VSS'<69>: CDS_PINID='VSS(69)';
NODE_NAME     J4A2 53
 '@BASEBOARD_FAB2_LIB.BASEBOARD_FAB2(SCH_1):PAGE51_I43@MSTR_SCONN.SCONN288_H44441004(CHIPS)':
 'VSS'<70>: CDS_PINID='VSS(70)';
NODE_NAME     J4A2 50
 '@BASEBOARD_FAB2_LIB.BASEBOARD_FAB2(SCH_1):PAGE51_I43@MSTR_SCONN.SCONN288_H44441004(CHIPS)':
 'VSS'<71>: CDS_PINID='VSS(71)';
NODE_NAME     J4A2 48
 '@BASEBOARD_FAB2_LIB.BASEBOARD_FAB2(SCH_1):PAGE51_I43@MSTR_SCONN.SCONN288_H44441004(CHIPS)':
 'VSS'<72>: CDS_PINID='VSS(72)';
NODE_NAME     J4A2 46
 '@BASEBOARD_FAB2_LIB.BASEBOARD_FAB2(SCH_1):PAGE51_I43@MSTR_SCONN.SCONN288_H44441004(CHIPS)':
 'VSS'<73>: CDS_PINID='VSS(73)';
NODE_NAME     J4A2 44
 '@BASEBOARD_FAB2_LIB.BASEBOARD_FAB2(SCH_1):PAGE51_I43@MSTR_SCONN.SCONN288_H44441004(CHIPS)':
 'VSS'<74>: CDS_PINID='VSS(74)';
NODE_NAME     J4A2 42
 '@BASEBOARD_FAB2_LIB.BASEBOARD_FAB2(SCH_1):PAGE51_I43@MSTR_SCONN.SCONN288_H44441004(CHIPS)':
 'VSS'<75>: CDS_PINID='VSS(75)';
NODE_NAME     J4A2 39
 '@BASEBOARD_FAB2_LIB.BASEBOARD_FAB2(SCH_1):PAGE51_I43@MSTR_SCONN.SCONN288_H44441004(CHIPS)':
 'VSS'<76>: CDS_PINID='VSS(76)';
NODE_NAME     J4A2 37
 '@BASEBOARD_FAB2_LIB.BASEBOARD_FAB2(SCH_1):PAGE51_I43@MSTR_SCONN.SCONN288_H44441004(CHIPS)':
 'VSS'<77>: CDS_PINID='VSS(77)';
NODE_NAME     J4A2 35
 '@BASEBOARD_FAB2_LIB.BASEBOARD_FAB2(SCH_1):PAGE51_I43@MSTR_SCONN.SCONN288_H44441004(CHIPS)':
 'VSS'<78>: CDS_PINID='VSS(78)';
NODE_NAME     J4A2 33
 '@BASEBOARD_FAB2_LIB.BASEBOARD_FAB2(SCH_1):PAGE51_I43@MSTR_SCONN.SCONN288_H44441004(CHIPS)':
 'VSS'<79>: CDS_PINID='VSS(79)';
NODE_NAME     J4A2 31
 '@BASEBOARD_FAB2_LIB.BASEBOARD_FAB2(SCH_1):PAGE51_I43@MSTR_SCONN.SCONN288_H44441004(CHIPS)':
 'VSS'<80>: CDS_PINID='VSS(80)';
NODE_NAME     J4A2 28
 '@BASEBOARD_FAB2_LIB.BASEBOARD_FAB2(SCH_1):PAGE51_I43@MSTR_SCONN.SCONN288_H44441004(CHIPS)':
 'VSS'<81>: CDS_PINID='VSS(81)';
NODE_NAME     J4A2 26
 '@BASEBOARD_FAB2_LIB.BASEBOARD_FAB2(SCH_1):PAGE51_I43@MSTR_SCONN.SCONN288_H44441004(CHIPS)':
 'VSS'<82>: CDS_PINID='VSS(82)';
NODE_NAME     J4A2 24
 '@BASEBOARD_FAB2_LIB.BASEBOARD_FAB2(SCH_1):PAGE51_I43@MSTR_SCONN.SCONN288_H44441004(CHIPS)':
 'VSS'<83>: CDS_PINID='VSS(83)';
NODE_NAME     J4A2 22
 '@BASEBOARD_FAB2_LIB.BASEBOARD_FAB2(SCH_1):PAGE51_I43@MSTR_SCONN.SCONN288_H44441004(CHIPS)':
 'VSS'<84>: CDS_PINID='VSS(84)';
NODE_NAME     J4A2 20
 '@BASEBOARD_FAB2_LIB.BASEBOARD_FAB2(SCH_1):PAGE51_I43@MSTR_SCONN.SCONN288_H44441004(CHIPS)':
 'VSS'<85>: CDS_PINID='VSS(85)';
NODE_NAME     J4A2 17
 '@BASEBOARD_FAB2_LIB.BASEBOARD_FAB2(SCH_1):PAGE51_I43@MSTR_SCONN.SCONN288_H44441004(CHIPS)':
 'VSS'<86>: CDS_PINID='VSS(86)';
NODE_NAME     J4A2 15
 '@BASEBOARD_FAB2_LIB.BASEBOARD_FAB2(SCH_1):PAGE51_I43@MSTR_SCONN.SCONN288_H44441004(CHIPS)':
 'VSS'<87>: CDS_PINID='VSS(87)';
NODE_NAME     J4A2 13
 '@BASEBOARD_FAB2_LIB.BASEBOARD_FAB2(SCH_1):PAGE51_I43@MSTR_SCONN.SCONN288_H44441004(CHIPS)':
 'VSS'<88>: CDS_PINID='VSS(88)';
NODE_NAME     J4A2 11
 '@BASEBOARD_FAB2_LIB.BASEBOARD_FAB2(SCH_1):PAGE51_I43@MSTR_SCONN.SCONN288_H44441004(CHIPS)':
 'VSS'<89>: CDS_PINID='VSS(89)';
NODE_NAME     J4A2 9
 '@BASEBOARD_FAB2_LIB.BASEBOARD_FAB2(SCH_1):PAGE51_I43@MSTR_SCONN.SCONN288_H44441004(CHIPS)':
 'VSS'<90>: CDS_PINID='VSS(90)';
NODE_NAME     J4A2 6
 '@BASEBOARD_FAB2_LIB.BASEBOARD_FAB2(SCH_1):PAGE51_I43@MSTR_SCONN.SCONN288_H44441004(CHIPS)':
 'VSS'<91>: CDS_PINID='VSS(91)';
NODE_NAME     J4A2 4
 '@BASEBOARD_FAB2_LIB.BASEBOARD_FAB2(SCH_1):PAGE51_I43@MSTR_SCONN.SCONN288_H44441004(CHIPS)':
 'VSS'<92>: CDS_PINID='VSS(92)';
NODE_NAME     J4A2 2
 '@BASEBOARD_FAB2_LIB.BASEBOARD_FAB2(SCH_1):PAGE51_I43@MSTR_SCONN.SCONN288_H44441004(CHIPS)':
 'VSS'<93>: CDS_PINID='VSS(93)';
NODE_NAME     J4A2 139
 '@BASEBOARD_FAB2_LIB.BASEBOARD_FAB2(SCH_1):PAGE51_I111@MSTR_SCONN.SCONN288_H44441004(CHIPS)':
 'SA'<0>: CDS_PINID='SA(0)';
NODE_NAME     J4A2 238
 '@BASEBOARD_FAB2_LIB.BASEBOARD_FAB2(SCH_1):PAGE51_I111@MSTR_SCONN.SCONN288_H44441004(CHIPS)':
 'SA'<2>: CDS_PINID='SA(2)';
NODE_NAME     C6L6 2
 '@BASEBOARD_FAB2_LIB.BASEBOARD_FAB2(SCH_1):PAGE51_I175@DEV_DISCRETE.CAP_A(CHIPS)':
 'B': CDS_PINID='B';
NODE_NAME     C4A18 2
 '@BASEBOARD_FAB2_LIB.BASEBOARD_FAB2(SCH_1):PAGE52_I3@DEV_DISCRETE.CAP_A(CHIPS)':
 'B': CDS_PINID='B';
NODE_NAME     J6L2 238
 '@BASEBOARD_FAB2_LIB.BASEBOARD_FAB2(SCH_1):PAGE52_I12@MSTR_SCONN.SCONN288_H44441003(CHIPS)':
 'SA'<2>: CDS_PINID='SA(2)';
NODE_NAME     J6L2 283
 '@BASEBOARD_FAB2_LIB.BASEBOARD_FAB2(SCH_1):PAGE52_I138@MSTR_SCONN.SCONN288_H44441003(CHIPS)':
 'VSS'<0>: CDS_PINID='VSS(0)';
NODE_NAME     J6L2 281
 '@BASEBOARD_FAB2_LIB.BASEBOARD_FAB2(SCH_1):PAGE52_I138@MSTR_SCONN.SCONN288_H44441003(CHIPS)':
 'VSS'<1>: CDS_PINID='VSS(1)';
NODE_NAME     J6L2 279
 '@BASEBOARD_FAB2_LIB.BASEBOARD_FAB2(SCH_1):PAGE52_I138@MSTR_SCONN.SCONN288_H44441003(CHIPS)':
 'VSS'<2>: CDS_PINID='VSS(2)';
NODE_NAME     J6L2 276
 '@BASEBOARD_FAB2_LIB.BASEBOARD_FAB2(SCH_1):PAGE52_I138@MSTR_SCONN.SCONN288_H44441003(CHIPS)':
 'VSS'<3>: CDS_PINID='VSS(3)';
NODE_NAME     J6L2 274
 '@BASEBOARD_FAB2_LIB.BASEBOARD_FAB2(SCH_1):PAGE52_I138@MSTR_SCONN.SCONN288_H44441003(CHIPS)':
 'VSS'<4>: CDS_PINID='VSS(4)';
NODE_NAME     J6L2 272
 '@BASEBOARD_FAB2_LIB.BASEBOARD_FAB2(SCH_1):PAGE52_I138@MSTR_SCONN.SCONN288_H44441003(CHIPS)':
 'VSS'<5>: CDS_PINID='VSS(5)';
NODE_NAME     J6L2 270
 '@BASEBOARD_FAB2_LIB.BASEBOARD_FAB2(SCH_1):PAGE52_I138@MSTR_SCONN.SCONN288_H44441003(CHIPS)':
 'VSS'<6>: CDS_PINID='VSS(6)';
NODE_NAME     J6L2 268
 '@BASEBOARD_FAB2_LIB.BASEBOARD_FAB2(SCH_1):PAGE52_I138@MSTR_SCONN.SCONN288_H44441003(CHIPS)':
 'VSS'<7>: CDS_PINID='VSS(7)';
NODE_NAME     J6L2 265
 '@BASEBOARD_FAB2_LIB.BASEBOARD_FAB2(SCH_1):PAGE52_I138@MSTR_SCONN.SCONN288_H44441003(CHIPS)':
 'VSS'<8>: CDS_PINID='VSS(8)';
NODE_NAME     J6L2 263
 '@BASEBOARD_FAB2_LIB.BASEBOARD_FAB2(SCH_1):PAGE52_I138@MSTR_SCONN.SCONN288_H44441003(CHIPS)':
 'VSS'<9>: CDS_PINID='VSS(9)';
NODE_NAME     J6L2 261
 '@BASEBOARD_FAB2_LIB.BASEBOARD_FAB2(SCH_1):PAGE52_I138@MSTR_SCONN.SCONN288_H44441003(CHIPS)':
 'VSS'<10>: CDS_PINID='VSS(10)';
NODE_NAME     J6L2 259
 '@BASEBOARD_FAB2_LIB.BASEBOARD_FAB2(SCH_1):PAGE52_I138@MSTR_SCONN.SCONN288_H44441003(CHIPS)':
 'VSS'<11>: CDS_PINID='VSS(11)';
NODE_NAME     J6L2 257
 '@BASEBOARD_FAB2_LIB.BASEBOARD_FAB2(SCH_1):PAGE52_I138@MSTR_SCONN.SCONN288_H44441003(CHIPS)':
 'VSS'<12>: CDS_PINID='VSS(12)';
NODE_NAME     J6L2 254
 '@BASEBOARD_FAB2_LIB.BASEBOARD_FAB2(SCH_1):PAGE52_I138@MSTR_SCONN.SCONN288_H44441003(CHIPS)':
 'VSS'<13>: CDS_PINID='VSS(13)';
NODE_NAME     J6L2 252
 '@BASEBOARD_FAB2_LIB.BASEBOARD_FAB2(SCH_1):PAGE52_I138@MSTR_SCONN.SCONN288_H44441003(CHIPS)':
 'VSS'<14>: CDS_PINID='VSS(14)';
NODE_NAME     J6L2 250
 '@BASEBOARD_FAB2_LIB.BASEBOARD_FAB2(SCH_1):PAGE52_I138@MSTR_SCONN.SCONN288_H44441003(CHIPS)':
 'VSS'<15>: CDS_PINID='VSS(15)';
NODE_NAME     J6L2 248
 '@BASEBOARD_FAB2_LIB.BASEBOARD_FAB2(SCH_1):PAGE52_I138@MSTR_SCONN.SCONN288_H44441003(CHIPS)':
 'VSS'<16>: CDS_PINID='VSS(16)';
NODE_NAME     J6L2 246
 '@BASEBOARD_FAB2_LIB.BASEBOARD_FAB2(SCH_1):PAGE52_I138@MSTR_SCONN.SCONN288_H44441003(CHIPS)':
 'VSS'<17>: CDS_PINID='VSS(17)';
NODE_NAME     J6L2 243
 '@BASEBOARD_FAB2_LIB.BASEBOARD_FAB2(SCH_1):PAGE52_I138@MSTR_SCONN.SCONN288_H44441003(CHIPS)':
 'VSS'<18>: CDS_PINID='VSS(18)';
NODE_NAME     J6L2 241
 '@BASEBOARD_FAB2_LIB.BASEBOARD_FAB2(SCH_1):PAGE52_I138@MSTR_SCONN.SCONN288_H44441003(CHIPS)':
 'VSS'<19>: CDS_PINID='VSS(19)';
NODE_NAME     J6L2 239
 '@BASEBOARD_FAB2_LIB.BASEBOARD_FAB2(SCH_1):PAGE52_I138@MSTR_SCONN.SCONN288_H44441003(CHIPS)':
 'VSS'<20>: CDS_PINID='VSS(20)';
NODE_NAME     J6L2 202
 '@BASEBOARD_FAB2_LIB.BASEBOARD_FAB2(SCH_1):PAGE52_I138@MSTR_SCONN.SCONN288_H44441003(CHIPS)':
 'VSS'<21>: CDS_PINID='VSS(21)';
NODE_NAME     J6L2 200
 '@BASEBOARD_FAB2_LIB.BASEBOARD_FAB2(SCH_1):PAGE52_I138@MSTR_SCONN.SCONN288_H44441003(CHIPS)':
 'VSS'<22>: CDS_PINID='VSS(22)';
NODE_NAME     J6L2 198
 '@BASEBOARD_FAB2_LIB.BASEBOARD_FAB2(SCH_1):PAGE52_I138@MSTR_SCONN.SCONN288_H44441003(CHIPS)':
 'VSS'<23>: CDS_PINID='VSS(23)';
NODE_NAME     J6L2 195
 '@BASEBOARD_FAB2_LIB.BASEBOARD_FAB2(SCH_1):PAGE52_I138@MSTR_SCONN.SCONN288_H44441003(CHIPS)':
 'VSS'<24>: CDS_PINID='VSS(24)';
NODE_NAME     J6L2 193
 '@BASEBOARD_FAB2_LIB.BASEBOARD_FAB2(SCH_1):PAGE52_I138@MSTR_SCONN.SCONN288_H44441003(CHIPS)':
 'VSS'<25>: CDS_PINID='VSS(25)';
NODE_NAME     J6L2 191
 '@BASEBOARD_FAB2_LIB.BASEBOARD_FAB2(SCH_1):PAGE52_I138@MSTR_SCONN.SCONN288_H44441003(CHIPS)':
 'VSS'<26>: CDS_PINID='VSS(26)';
NODE_NAME     J6L2 189
 '@BASEBOARD_FAB2_LIB.BASEBOARD_FAB2(SCH_1):PAGE52_I138@MSTR_SCONN.SCONN288_H44441003(CHIPS)':
 'VSS'<27>: CDS_PINID='VSS(27)';
NODE_NAME     J6L2 187
 '@BASEBOARD_FAB2_LIB.BASEBOARD_FAB2(SCH_1):PAGE52_I138@MSTR_SCONN.SCONN288_H44441003(CHIPS)':
 'VSS'<28>: CDS_PINID='VSS(28)';
NODE_NAME     J6L2 184
 '@BASEBOARD_FAB2_LIB.BASEBOARD_FAB2(SCH_1):PAGE52_I138@MSTR_SCONN.SCONN288_H44441003(CHIPS)':
 'VSS'<29>: CDS_PINID='VSS(29)';
NODE_NAME     J6L2 182
 '@BASEBOARD_FAB2_LIB.BASEBOARD_FAB2(SCH_1):PAGE52_I138@MSTR_SCONN.SCONN288_H44441003(CHIPS)':
 'VSS'<30>: CDS_PINID='VSS(30)';
NODE_NAME     J6L2 180
 '@BASEBOARD_FAB2_LIB.BASEBOARD_FAB2(SCH_1):PAGE52_I138@MSTR_SCONN.SCONN288_H44441003(CHIPS)':
 'VSS'<31>: CDS_PINID='VSS(31)';
NODE_NAME     J6L2 178
 '@BASEBOARD_FAB2_LIB.BASEBOARD_FAB2(SCH_1):PAGE52_I138@MSTR_SCONN.SCONN288_H44441003(CHIPS)':
 'VSS'<32>: CDS_PINID='VSS(32)';
NODE_NAME     J6L2 176
 '@BASEBOARD_FAB2_LIB.BASEBOARD_FAB2(SCH_1):PAGE52_I138@MSTR_SCONN.SCONN288_H44441003(CHIPS)':
 'VSS'<33>: CDS_PINID='VSS(33)';
NODE_NAME     J6L2 173
 '@BASEBOARD_FAB2_LIB.BASEBOARD_FAB2(SCH_1):PAGE52_I138@MSTR_SCONN.SCONN288_H44441003(CHIPS)':
 'VSS'<34>: CDS_PINID='VSS(34)';
NODE_NAME     J6L2 171
 '@BASEBOARD_FAB2_LIB.BASEBOARD_FAB2(SCH_1):PAGE52_I138@MSTR_SCONN.SCONN288_H44441003(CHIPS)':
 'VSS'<35>: CDS_PINID='VSS(35)';
NODE_NAME     J6L2 169
 '@BASEBOARD_FAB2_LIB.BASEBOARD_FAB2(SCH_1):PAGE52_I138@MSTR_SCONN.SCONN288_H44441003(CHIPS)':
 'VSS'<36>: CDS_PINID='VSS(36)';
NODE_NAME     J6L2 167
 '@BASEBOARD_FAB2_LIB.BASEBOARD_FAB2(SCH_1):PAGE52_I138@MSTR_SCONN.SCONN288_H44441003(CHIPS)':
 'VSS'<37>: CDS_PINID='VSS(37)';
NODE_NAME     J6L2 165
 '@BASEBOARD_FAB2_LIB.BASEBOARD_FAB2(SCH_1):PAGE52_I138@MSTR_SCONN.SCONN288_H44441003(CHIPS)':
 'VSS'<38>: CDS_PINID='VSS(38)';
NODE_NAME     J6L2 162
 '@BASEBOARD_FAB2_LIB.BASEBOARD_FAB2(SCH_1):PAGE52_I138@MSTR_SCONN.SCONN288_H44441003(CHIPS)':
 'VSS'<39>: CDS_PINID='VSS(39)';
NODE_NAME     J6L2 160
 '@BASEBOARD_FAB2_LIB.BASEBOARD_FAB2(SCH_1):PAGE52_I138@MSTR_SCONN.SCONN288_H44441003(CHIPS)':
 'VSS'<40>: CDS_PINID='VSS(40)';
NODE_NAME     J6L2 158
 '@BASEBOARD_FAB2_LIB.BASEBOARD_FAB2(SCH_1):PAGE52_I138@MSTR_SCONN.SCONN288_H44441003(CHIPS)':
 'VSS'<41>: CDS_PINID='VSS(41)';
NODE_NAME     J6L2 156
 '@BASEBOARD_FAB2_LIB.BASEBOARD_FAB2(SCH_1):PAGE52_I138@MSTR_SCONN.SCONN288_H44441003(CHIPS)':
 'VSS'<42>: CDS_PINID='VSS(42)';
NODE_NAME     J6L2 154
 '@BASEBOARD_FAB2_LIB.BASEBOARD_FAB2(SCH_1):PAGE52_I138@MSTR_SCONN.SCONN288_H44441003(CHIPS)':
 'VSS'<43>: CDS_PINID='VSS(43)';
NODE_NAME     J6L2 151
 '@BASEBOARD_FAB2_LIB.BASEBOARD_FAB2(SCH_1):PAGE52_I138@MSTR_SCONN.SCONN288_H44441003(CHIPS)':
 'VSS'<44>: CDS_PINID='VSS(44)';
NODE_NAME     J6L2 149
 '@BASEBOARD_FAB2_LIB.BASEBOARD_FAB2(SCH_1):PAGE52_I138@MSTR_SCONN.SCONN288_H44441003(CHIPS)':
 'VSS'<45>: CDS_PINID='VSS(45)';
NODE_NAME     J6L2 147
 '@BASEBOARD_FAB2_LIB.BASEBOARD_FAB2(SCH_1):PAGE52_I138@MSTR_SCONN.SCONN288_H44441003(CHIPS)':
 'VSS'<46>: CDS_PINID='VSS(46)';
NODE_NAME     J6L2 138
 '@BASEBOARD_FAB2_LIB.BASEBOARD_FAB2(SCH_1):PAGE52_I138@MSTR_SCONN.SCONN288_H44441003(CHIPS)':
 'VSS'<47>: CDS_PINID='VSS(47)';
NODE_NAME     J6L2 136
 '@BASEBOARD_FAB2_LIB.BASEBOARD_FAB2(SCH_1):PAGE52_I138@MSTR_SCONN.SCONN288_H44441003(CHIPS)':
 'VSS'<48>: CDS_PINID='VSS(48)';
NODE_NAME     J6L2 134
 '@BASEBOARD_FAB2_LIB.BASEBOARD_FAB2(SCH_1):PAGE52_I138@MSTR_SCONN.SCONN288_H44441003(CHIPS)':
 'VSS'<49>: CDS_PINID='VSS(49)';
NODE_NAME     J6L2 131
 '@BASEBOARD_FAB2_LIB.BASEBOARD_FAB2(SCH_1):PAGE52_I138@MSTR_SCONN.SCONN288_H44441003(CHIPS)':
 'VSS'<50>: CDS_PINID='VSS(50)';
NODE_NAME     J6L2 129
 '@BASEBOARD_FAB2_LIB.BASEBOARD_FAB2(SCH_1):PAGE52_I138@MSTR_SCONN.SCONN288_H44441003(CHIPS)':
 'VSS'<51>: CDS_PINID='VSS(51)';
NODE_NAME     J6L2 127
 '@BASEBOARD_FAB2_LIB.BASEBOARD_FAB2(SCH_1):PAGE52_I138@MSTR_SCONN.SCONN288_H44441003(CHIPS)':
 'VSS'<52>: CDS_PINID='VSS(52)';
NODE_NAME     J6L2 125
 '@BASEBOARD_FAB2_LIB.BASEBOARD_FAB2(SCH_1):PAGE52_I138@MSTR_SCONN.SCONN288_H44441003(CHIPS)':
 'VSS'<53>: CDS_PINID='VSS(53)';
NODE_NAME     J6L2 123
 '@BASEBOARD_FAB2_LIB.BASEBOARD_FAB2(SCH_1):PAGE52_I138@MSTR_SCONN.SCONN288_H44441003(CHIPS)':
 'VSS'<54>: CDS_PINID='VSS(54)';
NODE_NAME     J6L2 120
 '@BASEBOARD_FAB2_LIB.BASEBOARD_FAB2(SCH_1):PAGE52_I138@MSTR_SCONN.SCONN288_H44441003(CHIPS)':
 'VSS'<55>: CDS_PINID='VSS(55)';
NODE_NAME     J6L2 118
 '@BASEBOARD_FAB2_LIB.BASEBOARD_FAB2(SCH_1):PAGE52_I138@MSTR_SCONN.SCONN288_H44441003(CHIPS)':
 'VSS'<56>: CDS_PINID='VSS(56)';
NODE_NAME     J6L2 116
 '@BASEBOARD_FAB2_LIB.BASEBOARD_FAB2(SCH_1):PAGE52_I138@MSTR_SCONN.SCONN288_H44441003(CHIPS)':
 'VSS'<57>: CDS_PINID='VSS(57)';
NODE_NAME     J6L2 114
 '@BASEBOARD_FAB2_LIB.BASEBOARD_FAB2(SCH_1):PAGE52_I138@MSTR_SCONN.SCONN288_H44441003(CHIPS)':
 'VSS'<58>: CDS_PINID='VSS(58)';
NODE_NAME     J6L2 112
 '@BASEBOARD_FAB2_LIB.BASEBOARD_FAB2(SCH_1):PAGE52_I138@MSTR_SCONN.SCONN288_H44441003(CHIPS)':
 'VSS'<59>: CDS_PINID='VSS(59)';
NODE_NAME     J6L2 109
 '@BASEBOARD_FAB2_LIB.BASEBOARD_FAB2(SCH_1):PAGE52_I138@MSTR_SCONN.SCONN288_H44441003(CHIPS)':
 'VSS'<60>: CDS_PINID='VSS(60)';
NODE_NAME     J6L2 107
 '@BASEBOARD_FAB2_LIB.BASEBOARD_FAB2(SCH_1):PAGE52_I138@MSTR_SCONN.SCONN288_H44441003(CHIPS)':
 'VSS'<61>: CDS_PINID='VSS(61)';
NODE_NAME     J6L2 105
 '@BASEBOARD_FAB2_LIB.BASEBOARD_FAB2(SCH_1):PAGE52_I138@MSTR_SCONN.SCONN288_H44441003(CHIPS)':
 'VSS'<62>: CDS_PINID='VSS(62)';
NODE_NAME     J6L2 103
 '@BASEBOARD_FAB2_LIB.BASEBOARD_FAB2(SCH_1):PAGE52_I138@MSTR_SCONN.SCONN288_H44441003(CHIPS)':
 'VSS'<63>: CDS_PINID='VSS(63)';
NODE_NAME     J6L2 101
 '@BASEBOARD_FAB2_LIB.BASEBOARD_FAB2(SCH_1):PAGE52_I138@MSTR_SCONN.SCONN288_H44441003(CHIPS)':
 'VSS'<64>: CDS_PINID='VSS(64)';
NODE_NAME     J6L2 98
 '@BASEBOARD_FAB2_LIB.BASEBOARD_FAB2(SCH_1):PAGE52_I138@MSTR_SCONN.SCONN288_H44441003(CHIPS)':
 'VSS'<65>: CDS_PINID='VSS(65)';
NODE_NAME     J6L2 96
 '@BASEBOARD_FAB2_LIB.BASEBOARD_FAB2(SCH_1):PAGE52_I138@MSTR_SCONN.SCONN288_H44441003(CHIPS)':
 'VSS'<66>: CDS_PINID='VSS(66)';
NODE_NAME     J6L2 94
 '@BASEBOARD_FAB2_LIB.BASEBOARD_FAB2(SCH_1):PAGE52_I138@MSTR_SCONN.SCONN288_H44441003(CHIPS)':
 'VSS'<67>: CDS_PINID='VSS(67)';
NODE_NAME     J6L2 57
 '@BASEBOARD_FAB2_LIB.BASEBOARD_FAB2(SCH_1):PAGE52_I138@MSTR_SCONN.SCONN288_H44441003(CHIPS)':
 'VSS'<68>: CDS_PINID='VSS(68)';
NODE_NAME     J6L2 55
 '@BASEBOARD_FAB2_LIB.BASEBOARD_FAB2(SCH_1):PAGE52_I138@MSTR_SCONN.SCONN288_H44441003(CHIPS)':
 'VSS'<69>: CDS_PINID='VSS(69)';
NODE_NAME     J6L2 53
 '@BASEBOARD_FAB2_LIB.BASEBOARD_FAB2(SCH_1):PAGE52_I138@MSTR_SCONN.SCONN288_H44441003(CHIPS)':
 'VSS'<70>: CDS_PINID='VSS(70)';
NODE_NAME     J6L2 50
 '@BASEBOARD_FAB2_LIB.BASEBOARD_FAB2(SCH_1):PAGE52_I138@MSTR_SCONN.SCONN288_H44441003(CHIPS)':
 'VSS'<71>: CDS_PINID='VSS(71)';
NODE_NAME     J6L2 48
 '@BASEBOARD_FAB2_LIB.BASEBOARD_FAB2(SCH_1):PAGE52_I138@MSTR_SCONN.SCONN288_H44441003(CHIPS)':
 'VSS'<72>: CDS_PINID='VSS(72)';
NODE_NAME     J6L2 46
 '@BASEBOARD_FAB2_LIB.BASEBOARD_FAB2(SCH_1):PAGE52_I138@MSTR_SCONN.SCONN288_H44441003(CHIPS)':
 'VSS'<73>: CDS_PINID='VSS(73)';
NODE_NAME     J6L2 44
 '@BASEBOARD_FAB2_LIB.BASEBOARD_FAB2(SCH_1):PAGE52_I138@MSTR_SCONN.SCONN288_H44441003(CHIPS)':
 'VSS'<74>: CDS_PINID='VSS(74)';
NODE_NAME     J6L2 42
 '@BASEBOARD_FAB2_LIB.BASEBOARD_FAB2(SCH_1):PAGE52_I138@MSTR_SCONN.SCONN288_H44441003(CHIPS)':
 'VSS'<75>: CDS_PINID='VSS(75)';
NODE_NAME     J6L2 39
 '@BASEBOARD_FAB2_LIB.BASEBOARD_FAB2(SCH_1):PAGE52_I138@MSTR_SCONN.SCONN288_H44441003(CHIPS)':
 'VSS'<76>: CDS_PINID='VSS(76)';
NODE_NAME     J6L2 37
 '@BASEBOARD_FAB2_LIB.BASEBOARD_FAB2(SCH_1):PAGE52_I138@MSTR_SCONN.SCONN288_H44441003(CHIPS)':
 'VSS'<77>: CDS_PINID='VSS(77)';
NODE_NAME     J6L2 35
 '@BASEBOARD_FAB2_LIB.BASEBOARD_FAB2(SCH_1):PAGE52_I138@MSTR_SCONN.SCONN288_H44441003(CHIPS)':
 'VSS'<78>: CDS_PINID='VSS(78)';
NODE_NAME     J6L2 33
 '@BASEBOARD_FAB2_LIB.BASEBOARD_FAB2(SCH_1):PAGE52_I138@MSTR_SCONN.SCONN288_H44441003(CHIPS)':
 'VSS'<79>: CDS_PINID='VSS(79)';
NODE_NAME     J6L2 31
 '@BASEBOARD_FAB2_LIB.BASEBOARD_FAB2(SCH_1):PAGE52_I138@MSTR_SCONN.SCONN288_H44441003(CHIPS)':
 'VSS'<80>: CDS_PINID='VSS(80)';
NODE_NAME     J6L2 28
 '@BASEBOARD_FAB2_LIB.BASEBOARD_FAB2(SCH_1):PAGE52_I138@MSTR_SCONN.SCONN288_H44441003(CHIPS)':
 'VSS'<81>: CDS_PINID='VSS(81)';
NODE_NAME     J6L2 26
 '@BASEBOARD_FAB2_LIB.BASEBOARD_FAB2(SCH_1):PAGE52_I138@MSTR_SCONN.SCONN288_H44441003(CHIPS)':
 'VSS'<82>: CDS_PINID='VSS(82)';
NODE_NAME     J6L2 24
 '@BASEBOARD_FAB2_LIB.BASEBOARD_FAB2(SCH_1):PAGE52_I138@MSTR_SCONN.SCONN288_H44441003(CHIPS)':
 'VSS'<83>: CDS_PINID='VSS(83)';
NODE_NAME     J6L2 22
 '@BASEBOARD_FAB2_LIB.BASEBOARD_FAB2(SCH_1):PAGE52_I138@MSTR_SCONN.SCONN288_H44441003(CHIPS)':
 'VSS'<84>: CDS_PINID='VSS(84)';
NODE_NAME     J6L2 20
 '@BASEBOARD_FAB2_LIB.BASEBOARD_FAB2(SCH_1):PAGE52_I138@MSTR_SCONN.SCONN288_H44441003(CHIPS)':
 'VSS'<85>: CDS_PINID='VSS(85)';
NODE_NAME     J6L2 17
 '@BASEBOARD_FAB2_LIB.BASEBOARD_FAB2(SCH_1):PAGE52_I138@MSTR_SCONN.SCONN288_H44441003(CHIPS)':
 'VSS'<86>: CDS_PINID='VSS(86)';
NODE_NAME     J6L2 15
 '@BASEBOARD_FAB2_LIB.BASEBOARD_FAB2(SCH_1):PAGE52_I138@MSTR_SCONN.SCONN288_H44441003(CHIPS)':
 'VSS'<87>: CDS_PINID='VSS(87)';
NODE_NAME     J6L2 13
 '@BASEBOARD_FAB2_LIB.BASEBOARD_FAB2(SCH_1):PAGE52_I138@MSTR_SCONN.SCONN288_H44441003(CHIPS)':
 'VSS'<88>: CDS_PINID='VSS(88)';
NODE_NAME     J6L2 11
 '@BASEBOARD_FAB2_LIB.BASEBOARD_FAB2(SCH_1):PAGE52_I138@MSTR_SCONN.SCONN288_H44441003(CHIPS)':
 'VSS'<89>: CDS_PINID='VSS(89)';
NODE_NAME     J6L2 9
 '@BASEBOARD_FAB2_LIB.BASEBOARD_FAB2(SCH_1):PAGE52_I138@MSTR_SCONN.SCONN288_H44441003(CHIPS)':
 'VSS'<90>: CDS_PINID='VSS(90)';
NODE_NAME     J6L2 6
 '@BASEBOARD_FAB2_LIB.BASEBOARD_FAB2(SCH_1):PAGE52_I138@MSTR_SCONN.SCONN288_H44441003(CHIPS)':
 'VSS'<91>: CDS_PINID='VSS(91)';
NODE_NAME     J6L2 4
 '@BASEBOARD_FAB2_LIB.BASEBOARD_FAB2(SCH_1):PAGE52_I138@MSTR_SCONN.SCONN288_H44441003(CHIPS)':
 'VSS'<92>: CDS_PINID='VSS(92)';
NODE_NAME     J6L2 2
 '@BASEBOARD_FAB2_LIB.BASEBOARD_FAB2(SCH_1):PAGE52_I138@MSTR_SCONN.SCONN288_H44441003(CHIPS)':
 'VSS'<93>: CDS_PINID='VSS(93)';
NODE_NAME     J4A1 283
 '@BASEBOARD_FAB2_LIB.BASEBOARD_FAB2(SCH_1):PAGE53_I43@MSTR_SCONN.SCONN288_H44441004(CHIPS)':
 'VSS'<0>: CDS_PINID='VSS(0)';
NODE_NAME     J4A1 281
 '@BASEBOARD_FAB2_LIB.BASEBOARD_FAB2(SCH_1):PAGE53_I43@MSTR_SCONN.SCONN288_H44441004(CHIPS)':
 'VSS'<1>: CDS_PINID='VSS(1)';
NODE_NAME     J4A1 279
 '@BASEBOARD_FAB2_LIB.BASEBOARD_FAB2(SCH_1):PAGE53_I43@MSTR_SCONN.SCONN288_H44441004(CHIPS)':
 'VSS'<2>: CDS_PINID='VSS(2)';
NODE_NAME     J4A1 276
 '@BASEBOARD_FAB2_LIB.BASEBOARD_FAB2(SCH_1):PAGE53_I43@MSTR_SCONN.SCONN288_H44441004(CHIPS)':
 'VSS'<3>: CDS_PINID='VSS(3)';
NODE_NAME     J4A1 274
 '@BASEBOARD_FAB2_LIB.BASEBOARD_FAB2(SCH_1):PAGE53_I43@MSTR_SCONN.SCONN288_H44441004(CHIPS)':
 'VSS'<4>: CDS_PINID='VSS(4)';
NODE_NAME     J4A1 272
 '@BASEBOARD_FAB2_LIB.BASEBOARD_FAB2(SCH_1):PAGE53_I43@MSTR_SCONN.SCONN288_H44441004(CHIPS)':
 'VSS'<5>: CDS_PINID='VSS(5)';
NODE_NAME     J4A1 270
 '@BASEBOARD_FAB2_LIB.BASEBOARD_FAB2(SCH_1):PAGE53_I43@MSTR_SCONN.SCONN288_H44441004(CHIPS)':
 'VSS'<6>: CDS_PINID='VSS(6)';
NODE_NAME     J4A1 268
 '@BASEBOARD_FAB2_LIB.BASEBOARD_FAB2(SCH_1):PAGE53_I43@MSTR_SCONN.SCONN288_H44441004(CHIPS)':
 'VSS'<7>: CDS_PINID='VSS(7)';
NODE_NAME     J4A1 265
 '@BASEBOARD_FAB2_LIB.BASEBOARD_FAB2(SCH_1):PAGE53_I43@MSTR_SCONN.SCONN288_H44441004(CHIPS)':
 'VSS'<8>: CDS_PINID='VSS(8)';
NODE_NAME     J4A1 263
 '@BASEBOARD_FAB2_LIB.BASEBOARD_FAB2(SCH_1):PAGE53_I43@MSTR_SCONN.SCONN288_H44441004(CHIPS)':
 'VSS'<9>: CDS_PINID='VSS(9)';
NODE_NAME     J4A1 261
 '@BASEBOARD_FAB2_LIB.BASEBOARD_FAB2(SCH_1):PAGE53_I43@MSTR_SCONN.SCONN288_H44441004(CHIPS)':
 'VSS'<10>: CDS_PINID='VSS(10)';
NODE_NAME     J4A1 259
 '@BASEBOARD_FAB2_LIB.BASEBOARD_FAB2(SCH_1):PAGE53_I43@MSTR_SCONN.SCONN288_H44441004(CHIPS)':
 'VSS'<11>: CDS_PINID='VSS(11)';
NODE_NAME     J4A1 257
 '@BASEBOARD_FAB2_LIB.BASEBOARD_FAB2(SCH_1):PAGE53_I43@MSTR_SCONN.SCONN288_H44441004(CHIPS)':
 'VSS'<12>: CDS_PINID='VSS(12)';
NODE_NAME     J4A1 254
 '@BASEBOARD_FAB2_LIB.BASEBOARD_FAB2(SCH_1):PAGE53_I43@MSTR_SCONN.SCONN288_H44441004(CHIPS)':
 'VSS'<13>: CDS_PINID='VSS(13)';
NODE_NAME     J4A1 252
 '@BASEBOARD_FAB2_LIB.BASEBOARD_FAB2(SCH_1):PAGE53_I43@MSTR_SCONN.SCONN288_H44441004(CHIPS)':
 'VSS'<14>: CDS_PINID='VSS(14)';
NODE_NAME     J4A1 250
 '@BASEBOARD_FAB2_LIB.BASEBOARD_FAB2(SCH_1):PAGE53_I43@MSTR_SCONN.SCONN288_H44441004(CHIPS)':
 'VSS'<15>: CDS_PINID='VSS(15)';
NODE_NAME     J4A1 248
 '@BASEBOARD_FAB2_LIB.BASEBOARD_FAB2(SCH_1):PAGE53_I43@MSTR_SCONN.SCONN288_H44441004(CHIPS)':
 'VSS'<16>: CDS_PINID='VSS(16)';
NODE_NAME     J4A1 246
 '@BASEBOARD_FAB2_LIB.BASEBOARD_FAB2(SCH_1):PAGE53_I43@MSTR_SCONN.SCONN288_H44441004(CHIPS)':
 'VSS'<17>: CDS_PINID='VSS(17)';
NODE_NAME     J4A1 243
 '@BASEBOARD_FAB2_LIB.BASEBOARD_FAB2(SCH_1):PAGE53_I43@MSTR_SCONN.SCONN288_H44441004(CHIPS)':
 'VSS'<18>: CDS_PINID='VSS(18)';
NODE_NAME     J4A1 241
 '@BASEBOARD_FAB2_LIB.BASEBOARD_FAB2(SCH_1):PAGE53_I43@MSTR_SCONN.SCONN288_H44441004(CHIPS)':
 'VSS'<19>: CDS_PINID='VSS(19)';
NODE_NAME     J4A1 239
 '@BASEBOARD_FAB2_LIB.BASEBOARD_FAB2(SCH_1):PAGE53_I43@MSTR_SCONN.SCONN288_H44441004(CHIPS)':
 'VSS'<20>: CDS_PINID='VSS(20)';
NODE_NAME     J4A1 202
 '@BASEBOARD_FAB2_LIB.BASEBOARD_FAB2(SCH_1):PAGE53_I43@MSTR_SCONN.SCONN288_H44441004(CHIPS)':
 'VSS'<21>: CDS_PINID='VSS(21)';
NODE_NAME     J4A1 200
 '@BASEBOARD_FAB2_LIB.BASEBOARD_FAB2(SCH_1):PAGE53_I43@MSTR_SCONN.SCONN288_H44441004(CHIPS)':
 'VSS'<22>: CDS_PINID='VSS(22)';
NODE_NAME     J4A1 198
 '@BASEBOARD_FAB2_LIB.BASEBOARD_FAB2(SCH_1):PAGE53_I43@MSTR_SCONN.SCONN288_H44441004(CHIPS)':
 'VSS'<23>: CDS_PINID='VSS(23)';
NODE_NAME     J4A1 195
 '@BASEBOARD_FAB2_LIB.BASEBOARD_FAB2(SCH_1):PAGE53_I43@MSTR_SCONN.SCONN288_H44441004(CHIPS)':
 'VSS'<24>: CDS_PINID='VSS(24)';
NODE_NAME     J4A1 193
 '@BASEBOARD_FAB2_LIB.BASEBOARD_FAB2(SCH_1):PAGE53_I43@MSTR_SCONN.SCONN288_H44441004(CHIPS)':
 'VSS'<25>: CDS_PINID='VSS(25)';
NODE_NAME     J4A1 191
 '@BASEBOARD_FAB2_LIB.BASEBOARD_FAB2(SCH_1):PAGE53_I43@MSTR_SCONN.SCONN288_H44441004(CHIPS)':
 'VSS'<26>: CDS_PINID='VSS(26)';
NODE_NAME     J4A1 189
 '@BASEBOARD_FAB2_LIB.BASEBOARD_FAB2(SCH_1):PAGE53_I43@MSTR_SCONN.SCONN288_H44441004(CHIPS)':
 'VSS'<27>: CDS_PINID='VSS(27)';
NODE_NAME     J4A1 187
 '@BASEBOARD_FAB2_LIB.BASEBOARD_FAB2(SCH_1):PAGE53_I43@MSTR_SCONN.SCONN288_H44441004(CHIPS)':
 'VSS'<28>: CDS_PINID='VSS(28)';
NODE_NAME     J4A1 184
 '@BASEBOARD_FAB2_LIB.BASEBOARD_FAB2(SCH_1):PAGE53_I43@MSTR_SCONN.SCONN288_H44441004(CHIPS)':
 'VSS'<29>: CDS_PINID='VSS(29)';
NODE_NAME     J4A1 182
 '@BASEBOARD_FAB2_LIB.BASEBOARD_FAB2(SCH_1):PAGE53_I43@MSTR_SCONN.SCONN288_H44441004(CHIPS)':
 'VSS'<30>: CDS_PINID='VSS(30)';
NODE_NAME     J4A1 180
 '@BASEBOARD_FAB2_LIB.BASEBOARD_FAB2(SCH_1):PAGE53_I43@MSTR_SCONN.SCONN288_H44441004(CHIPS)':
 'VSS'<31>: CDS_PINID='VSS(31)';
NODE_NAME     J4A1 178
 '@BASEBOARD_FAB2_LIB.BASEBOARD_FAB2(SCH_1):PAGE53_I43@MSTR_SCONN.SCONN288_H44441004(CHIPS)':
 'VSS'<32>: CDS_PINID='VSS(32)';
NODE_NAME     J4A1 176
 '@BASEBOARD_FAB2_LIB.BASEBOARD_FAB2(SCH_1):PAGE53_I43@MSTR_SCONN.SCONN288_H44441004(CHIPS)':
 'VSS'<33>: CDS_PINID='VSS(33)';
NODE_NAME     J4A1 173
 '@BASEBOARD_FAB2_LIB.BASEBOARD_FAB2(SCH_1):PAGE53_I43@MSTR_SCONN.SCONN288_H44441004(CHIPS)':
 'VSS'<34>: CDS_PINID='VSS(34)';
NODE_NAME     J4A1 171
 '@BASEBOARD_FAB2_LIB.BASEBOARD_FAB2(SCH_1):PAGE53_I43@MSTR_SCONN.SCONN288_H44441004(CHIPS)':
 'VSS'<35>: CDS_PINID='VSS(35)';
NODE_NAME     J4A1 169
 '@BASEBOARD_FAB2_LIB.BASEBOARD_FAB2(SCH_1):PAGE53_I43@MSTR_SCONN.SCONN288_H44441004(CHIPS)':
 'VSS'<36>: CDS_PINID='VSS(36)';
NODE_NAME     J4A1 167
 '@BASEBOARD_FAB2_LIB.BASEBOARD_FAB2(SCH_1):PAGE53_I43@MSTR_SCONN.SCONN288_H44441004(CHIPS)':
 'VSS'<37>: CDS_PINID='VSS(37)';
NODE_NAME     J4A1 165
 '@BASEBOARD_FAB2_LIB.BASEBOARD_FAB2(SCH_1):PAGE53_I43@MSTR_SCONN.SCONN288_H44441004(CHIPS)':
 'VSS'<38>: CDS_PINID='VSS(38)';
NODE_NAME     J4A1 162
 '@BASEBOARD_FAB2_LIB.BASEBOARD_FAB2(SCH_1):PAGE53_I43@MSTR_SCONN.SCONN288_H44441004(CHIPS)':
 'VSS'<39>: CDS_PINID='VSS(39)';
NODE_NAME     J4A1 160
 '@BASEBOARD_FAB2_LIB.BASEBOARD_FAB2(SCH_1):PAGE53_I43@MSTR_SCONN.SCONN288_H44441004(CHIPS)':
 'VSS'<40>: CDS_PINID='VSS(40)';
NODE_NAME     J4A1 158
 '@BASEBOARD_FAB2_LIB.BASEBOARD_FAB2(SCH_1):PAGE53_I43@MSTR_SCONN.SCONN288_H44441004(CHIPS)':
 'VSS'<41>: CDS_PINID='VSS(41)';
NODE_NAME     J4A1 156
 '@BASEBOARD_FAB2_LIB.BASEBOARD_FAB2(SCH_1):PAGE53_I43@MSTR_SCONN.SCONN288_H44441004(CHIPS)':
 'VSS'<42>: CDS_PINID='VSS(42)';
NODE_NAME     J4A1 154
 '@BASEBOARD_FAB2_LIB.BASEBOARD_FAB2(SCH_1):PAGE53_I43@MSTR_SCONN.SCONN288_H44441004(CHIPS)':
 'VSS'<43>: CDS_PINID='VSS(43)';
NODE_NAME     J4A1 151
 '@BASEBOARD_FAB2_LIB.BASEBOARD_FAB2(SCH_1):PAGE53_I43@MSTR_SCONN.SCONN288_H44441004(CHIPS)':
 'VSS'<44>: CDS_PINID='VSS(44)';
NODE_NAME     J4A1 149
 '@BASEBOARD_FAB2_LIB.BASEBOARD_FAB2(SCH_1):PAGE53_I43@MSTR_SCONN.SCONN288_H44441004(CHIPS)':
 'VSS'<45>: CDS_PINID='VSS(45)';
NODE_NAME     J4A1 147
 '@BASEBOARD_FAB2_LIB.BASEBOARD_FAB2(SCH_1):PAGE53_I43@MSTR_SCONN.SCONN288_H44441004(CHIPS)':
 'VSS'<46>: CDS_PINID='VSS(46)';
NODE_NAME     J4A1 138
 '@BASEBOARD_FAB2_LIB.BASEBOARD_FAB2(SCH_1):PAGE53_I43@MSTR_SCONN.SCONN288_H44441004(CHIPS)':
 'VSS'<47>: CDS_PINID='VSS(47)';
NODE_NAME     J4A1 136
 '@BASEBOARD_FAB2_LIB.BASEBOARD_FAB2(SCH_1):PAGE53_I43@MSTR_SCONN.SCONN288_H44441004(CHIPS)':
 'VSS'<48>: CDS_PINID='VSS(48)';
NODE_NAME     J4A1 134
 '@BASEBOARD_FAB2_LIB.BASEBOARD_FAB2(SCH_1):PAGE53_I43@MSTR_SCONN.SCONN288_H44441004(CHIPS)':
 'VSS'<49>: CDS_PINID='VSS(49)';
NODE_NAME     J4A1 131
 '@BASEBOARD_FAB2_LIB.BASEBOARD_FAB2(SCH_1):PAGE53_I43@MSTR_SCONN.SCONN288_H44441004(CHIPS)':
 'VSS'<50>: CDS_PINID='VSS(50)';
NODE_NAME     J4A1 129
 '@BASEBOARD_FAB2_LIB.BASEBOARD_FAB2(SCH_1):PAGE53_I43@MSTR_SCONN.SCONN288_H44441004(CHIPS)':
 'VSS'<51>: CDS_PINID='VSS(51)';
NODE_NAME     J4A1 127
 '@BASEBOARD_FAB2_LIB.BASEBOARD_FAB2(SCH_1):PAGE53_I43@MSTR_SCONN.SCONN288_H44441004(CHIPS)':
 'VSS'<52>: CDS_PINID='VSS(52)';
NODE_NAME     J4A1 125
 '@BASEBOARD_FAB2_LIB.BASEBOARD_FAB2(SCH_1):PAGE53_I43@MSTR_SCONN.SCONN288_H44441004(CHIPS)':
 'VSS'<53>: CDS_PINID='VSS(53)';
NODE_NAME     J4A1 123
 '@BASEBOARD_FAB2_LIB.BASEBOARD_FAB2(SCH_1):PAGE53_I43@MSTR_SCONN.SCONN288_H44441004(CHIPS)':
 'VSS'<54>: CDS_PINID='VSS(54)';
NODE_NAME     J4A1 120
 '@BASEBOARD_FAB2_LIB.BASEBOARD_FAB2(SCH_1):PAGE53_I43@MSTR_SCONN.SCONN288_H44441004(CHIPS)':
 'VSS'<55>: CDS_PINID='VSS(55)';
NODE_NAME     J4A1 118
 '@BASEBOARD_FAB2_LIB.BASEBOARD_FAB2(SCH_1):PAGE53_I43@MSTR_SCONN.SCONN288_H44441004(CHIPS)':
 'VSS'<56>: CDS_PINID='VSS(56)';
NODE_NAME     J4A1 116
 '@BASEBOARD_FAB2_LIB.BASEBOARD_FAB2(SCH_1):PAGE53_I43@MSTR_SCONN.SCONN288_H44441004(CHIPS)':
 'VSS'<57>: CDS_PINID='VSS(57)';
NODE_NAME     J4A1 114
 '@BASEBOARD_FAB2_LIB.BASEBOARD_FAB2(SCH_1):PAGE53_I43@MSTR_SCONN.SCONN288_H44441004(CHIPS)':
 'VSS'<58>: CDS_PINID='VSS(58)';
NODE_NAME     J4A1 112
 '@BASEBOARD_FAB2_LIB.BASEBOARD_FAB2(SCH_1):PAGE53_I43@MSTR_SCONN.SCONN288_H44441004(CHIPS)':
 'VSS'<59>: CDS_PINID='VSS(59)';
NODE_NAME     J4A1 109
 '@BASEBOARD_FAB2_LIB.BASEBOARD_FAB2(SCH_1):PAGE53_I43@MSTR_SCONN.SCONN288_H44441004(CHIPS)':
 'VSS'<60>: CDS_PINID='VSS(60)';
NODE_NAME     J4A1 107
 '@BASEBOARD_FAB2_LIB.BASEBOARD_FAB2(SCH_1):PAGE53_I43@MSTR_SCONN.SCONN288_H44441004(CHIPS)':
 'VSS'<61>: CDS_PINID='VSS(61)';
NODE_NAME     J4A1 105
 '@BASEBOARD_FAB2_LIB.BASEBOARD_FAB2(SCH_1):PAGE53_I43@MSTR_SCONN.SCONN288_H44441004(CHIPS)':
 'VSS'<62>: CDS_PINID='VSS(62)';
NODE_NAME     J4A1 103
 '@BASEBOARD_FAB2_LIB.BASEBOARD_FAB2(SCH_1):PAGE53_I43@MSTR_SCONN.SCONN288_H44441004(CHIPS)':
 'VSS'<63>: CDS_PINID='VSS(63)';
NODE_NAME     J4A1 101
 '@BASEBOARD_FAB2_LIB.BASEBOARD_FAB2(SCH_1):PAGE53_I43@MSTR_SCONN.SCONN288_H44441004(CHIPS)':
 'VSS'<64>: CDS_PINID='VSS(64)';
NODE_NAME     J4A1 98
 '@BASEBOARD_FAB2_LIB.BASEBOARD_FAB2(SCH_1):PAGE53_I43@MSTR_SCONN.SCONN288_H44441004(CHIPS)':
 'VSS'<65>: CDS_PINID='VSS(65)';
NODE_NAME     J4A1 96
 '@BASEBOARD_FAB2_LIB.BASEBOARD_FAB2(SCH_1):PAGE53_I43@MSTR_SCONN.SCONN288_H44441004(CHIPS)':
 'VSS'<66>: CDS_PINID='VSS(66)';
NODE_NAME     J4A1 94
 '@BASEBOARD_FAB2_LIB.BASEBOARD_FAB2(SCH_1):PAGE53_I43@MSTR_SCONN.SCONN288_H44441004(CHIPS)':
 'VSS'<67>: CDS_PINID='VSS(67)';
NODE_NAME     J4A1 57
 '@BASEBOARD_FAB2_LIB.BASEBOARD_FAB2(SCH_1):PAGE53_I43@MSTR_SCONN.SCONN288_H44441004(CHIPS)':
 'VSS'<68>: CDS_PINID='VSS(68)';
NODE_NAME     J4A1 55
 '@BASEBOARD_FAB2_LIB.BASEBOARD_FAB2(SCH_1):PAGE53_I43@MSTR_SCONN.SCONN288_H44441004(CHIPS)':
 'VSS'<69>: CDS_PINID='VSS(69)';
NODE_NAME     J4A1 53
 '@BASEBOARD_FAB2_LIB.BASEBOARD_FAB2(SCH_1):PAGE53_I43@MSTR_SCONN.SCONN288_H44441004(CHIPS)':
 'VSS'<70>: CDS_PINID='VSS(70)';
NODE_NAME     J4A1 50
 '@BASEBOARD_FAB2_LIB.BASEBOARD_FAB2(SCH_1):PAGE53_I43@MSTR_SCONN.SCONN288_H44441004(CHIPS)':
 'VSS'<71>: CDS_PINID='VSS(71)';
NODE_NAME     J4A1 48
 '@BASEBOARD_FAB2_LIB.BASEBOARD_FAB2(SCH_1):PAGE53_I43@MSTR_SCONN.SCONN288_H44441004(CHIPS)':
 'VSS'<72>: CDS_PINID='VSS(72)';
NODE_NAME     J4A1 46
 '@BASEBOARD_FAB2_LIB.BASEBOARD_FAB2(SCH_1):PAGE53_I43@MSTR_SCONN.SCONN288_H44441004(CHIPS)':
 'VSS'<73>: CDS_PINID='VSS(73)';
NODE_NAME     J4A1 44
 '@BASEBOARD_FAB2_LIB.BASEBOARD_FAB2(SCH_1):PAGE53_I43@MSTR_SCONN.SCONN288_H44441004(CHIPS)':
 'VSS'<74>: CDS_PINID='VSS(74)';
NODE_NAME     J4A1 42
 '@BASEBOARD_FAB2_LIB.BASEBOARD_FAB2(SCH_1):PAGE53_I43@MSTR_SCONN.SCONN288_H44441004(CHIPS)':
 'VSS'<75>: CDS_PINID='VSS(75)';
NODE_NAME     J4A1 39
 '@BASEBOARD_FAB2_LIB.BASEBOARD_FAB2(SCH_1):PAGE53_I43@MSTR_SCONN.SCONN288_H44441004(CHIPS)':
 'VSS'<76>: CDS_PINID='VSS(76)';
NODE_NAME     J4A1 37
 '@BASEBOARD_FAB2_LIB.BASEBOARD_FAB2(SCH_1):PAGE53_I43@MSTR_SCONN.SCONN288_H44441004(CHIPS)':
 'VSS'<77>: CDS_PINID='VSS(77)';
NODE_NAME     J4A1 35
 '@BASEBOARD_FAB2_LIB.BASEBOARD_FAB2(SCH_1):PAGE53_I43@MSTR_SCONN.SCONN288_H44441004(CHIPS)':
 'VSS'<78>: CDS_PINID='VSS(78)';
NODE_NAME     J4A1 33
 '@BASEBOARD_FAB2_LIB.BASEBOARD_FAB2(SCH_1):PAGE53_I43@MSTR_SCONN.SCONN288_H44441004(CHIPS)':
 'VSS'<79>: CDS_PINID='VSS(79)';
NODE_NAME     J4A1 31
 '@BASEBOARD_FAB2_LIB.BASEBOARD_FAB2(SCH_1):PAGE53_I43@MSTR_SCONN.SCONN288_H44441004(CHIPS)':
 'VSS'<80>: CDS_PINID='VSS(80)';
NODE_NAME     J4A1 28
 '@BASEBOARD_FAB2_LIB.BASEBOARD_FAB2(SCH_1):PAGE53_I43@MSTR_SCONN.SCONN288_H44441004(CHIPS)':
 'VSS'<81>: CDS_PINID='VSS(81)';
NODE_NAME     J4A1 26
 '@BASEBOARD_FAB2_LIB.BASEBOARD_FAB2(SCH_1):PAGE53_I43@MSTR_SCONN.SCONN288_H44441004(CHIPS)':
 'VSS'<82>: CDS_PINID='VSS(82)';
NODE_NAME     J4A1 24
 '@BASEBOARD_FAB2_LIB.BASEBOARD_FAB2(SCH_1):PAGE53_I43@MSTR_SCONN.SCONN288_H44441004(CHIPS)':
 'VSS'<83>: CDS_PINID='VSS(83)';
NODE_NAME     J4A1 22
 '@BASEBOARD_FAB2_LIB.BASEBOARD_FAB2(SCH_1):PAGE53_I43@MSTR_SCONN.SCONN288_H44441004(CHIPS)':
 'VSS'<84>: CDS_PINID='VSS(84)';
NODE_NAME     J4A1 20
 '@BASEBOARD_FAB2_LIB.BASEBOARD_FAB2(SCH_1):PAGE53_I43@MSTR_SCONN.SCONN288_H44441004(CHIPS)':
 'VSS'<85>: CDS_PINID='VSS(85)';
NODE_NAME     J4A1 17
 '@BASEBOARD_FAB2_LIB.BASEBOARD_FAB2(SCH_1):PAGE53_I43@MSTR_SCONN.SCONN288_H44441004(CHIPS)':
 'VSS'<86>: CDS_PINID='VSS(86)';
NODE_NAME     J4A1 15
 '@BASEBOARD_FAB2_LIB.BASEBOARD_FAB2(SCH_1):PAGE53_I43@MSTR_SCONN.SCONN288_H44441004(CHIPS)':
 'VSS'<87>: CDS_PINID='VSS(87)';
NODE_NAME     J4A1 13
 '@BASEBOARD_FAB2_LIB.BASEBOARD_FAB2(SCH_1):PAGE53_I43@MSTR_SCONN.SCONN288_H44441004(CHIPS)':
 'VSS'<88>: CDS_PINID='VSS(88)';
NODE_NAME     J4A1 11
 '@BASEBOARD_FAB2_LIB.BASEBOARD_FAB2(SCH_1):PAGE53_I43@MSTR_SCONN.SCONN288_H44441004(CHIPS)':
 'VSS'<89>: CDS_PINID='VSS(89)';
NODE_NAME     J4A1 9
 '@BASEBOARD_FAB2_LIB.BASEBOARD_FAB2(SCH_1):PAGE53_I43@MSTR_SCONN.SCONN288_H44441004(CHIPS)':
 'VSS'<90>: CDS_PINID='VSS(90)';
NODE_NAME     J4A1 6
 '@BASEBOARD_FAB2_LIB.BASEBOARD_FAB2(SCH_1):PAGE53_I43@MSTR_SCONN.SCONN288_H44441004(CHIPS)':
 'VSS'<91>: CDS_PINID='VSS(91)';
NODE_NAME     J4A1 4
 '@BASEBOARD_FAB2_LIB.BASEBOARD_FAB2(SCH_1):PAGE53_I43@MSTR_SCONN.SCONN288_H44441004(CHIPS)':
 'VSS'<92>: CDS_PINID='VSS(92)';
NODE_NAME     J4A1 2
 '@BASEBOARD_FAB2_LIB.BASEBOARD_FAB2(SCH_1):PAGE53_I43@MSTR_SCONN.SCONN288_H44441004(CHIPS)':
 'VSS'<93>: CDS_PINID='VSS(93)';
NODE_NAME     J4A1 139
 '@BASEBOARD_FAB2_LIB.BASEBOARD_FAB2(SCH_1):PAGE53_I111@MSTR_SCONN.SCONN288_H44441004(CHIPS)':
 'SA'<0>: CDS_PINID='SA(0)';
NODE_NAME     J4A1 140
 '@BASEBOARD_FAB2_LIB.BASEBOARD_FAB2(SCH_1):PAGE53_I111@MSTR_SCONN.SCONN288_H44441004(CHIPS)':
 'SA'<1>: CDS_PINID='SA(1)';
NODE_NAME     C6L1 2
 '@BASEBOARD_FAB2_LIB.BASEBOARD_FAB2(SCH_1):PAGE53_I178@DEV_DISCRETE.CAP_A(CHIPS)':
 'B': CDS_PINID='B';
NODE_NAME     J6L1 283
 '@BASEBOARD_FAB2_LIB.BASEBOARD_FAB2(SCH_1):PAGE54_I43@MSTR_SCONN.SCONN288_H44441003(CHIPS)':
 'VSS'<0>: CDS_PINID='VSS(0)';
NODE_NAME     J6L1 281
 '@BASEBOARD_FAB2_LIB.BASEBOARD_FAB2(SCH_1):PAGE54_I43@MSTR_SCONN.SCONN288_H44441003(CHIPS)':
 'VSS'<1>: CDS_PINID='VSS(1)';
NODE_NAME     J6L1 279
 '@BASEBOARD_FAB2_LIB.BASEBOARD_FAB2(SCH_1):PAGE54_I43@MSTR_SCONN.SCONN288_H44441003(CHIPS)':
 'VSS'<2>: CDS_PINID='VSS(2)';
NODE_NAME     J6L1 276
 '@BASEBOARD_FAB2_LIB.BASEBOARD_FAB2(SCH_1):PAGE54_I43@MSTR_SCONN.SCONN288_H44441003(CHIPS)':
 'VSS'<3>: CDS_PINID='VSS(3)';
NODE_NAME     J6L1 274
 '@BASEBOARD_FAB2_LIB.BASEBOARD_FAB2(SCH_1):PAGE54_I43@MSTR_SCONN.SCONN288_H44441003(CHIPS)':
 'VSS'<4>: CDS_PINID='VSS(4)';
NODE_NAME     J6L1 272
 '@BASEBOARD_FAB2_LIB.BASEBOARD_FAB2(SCH_1):PAGE54_I43@MSTR_SCONN.SCONN288_H44441003(CHIPS)':
 'VSS'<5>: CDS_PINID='VSS(5)';
NODE_NAME     J6L1 270
 '@BASEBOARD_FAB2_LIB.BASEBOARD_FAB2(SCH_1):PAGE54_I43@MSTR_SCONN.SCONN288_H44441003(CHIPS)':
 'VSS'<6>: CDS_PINID='VSS(6)';
NODE_NAME     J6L1 268
 '@BASEBOARD_FAB2_LIB.BASEBOARD_FAB2(SCH_1):PAGE54_I43@MSTR_SCONN.SCONN288_H44441003(CHIPS)':
 'VSS'<7>: CDS_PINID='VSS(7)';
NODE_NAME     J6L1 265
 '@BASEBOARD_FAB2_LIB.BASEBOARD_FAB2(SCH_1):PAGE54_I43@MSTR_SCONN.SCONN288_H44441003(CHIPS)':
 'VSS'<8>: CDS_PINID='VSS(8)';
NODE_NAME     J6L1 263
 '@BASEBOARD_FAB2_LIB.BASEBOARD_FAB2(SCH_1):PAGE54_I43@MSTR_SCONN.SCONN288_H44441003(CHIPS)':
 'VSS'<9>: CDS_PINID='VSS(9)';
NODE_NAME     J6L1 261
 '@BASEBOARD_FAB2_LIB.BASEBOARD_FAB2(SCH_1):PAGE54_I43@MSTR_SCONN.SCONN288_H44441003(CHIPS)':
 'VSS'<10>: CDS_PINID='VSS(10)';
NODE_NAME     J6L1 259
 '@BASEBOARD_FAB2_LIB.BASEBOARD_FAB2(SCH_1):PAGE54_I43@MSTR_SCONN.SCONN288_H44441003(CHIPS)':
 'VSS'<11>: CDS_PINID='VSS(11)';
NODE_NAME     J6L1 257
 '@BASEBOARD_FAB2_LIB.BASEBOARD_FAB2(SCH_1):PAGE54_I43@MSTR_SCONN.SCONN288_H44441003(CHIPS)':
 'VSS'<12>: CDS_PINID='VSS(12)';
NODE_NAME     J6L1 254
 '@BASEBOARD_FAB2_LIB.BASEBOARD_FAB2(SCH_1):PAGE54_I43@MSTR_SCONN.SCONN288_H44441003(CHIPS)':
 'VSS'<13>: CDS_PINID='VSS(13)';
NODE_NAME     J6L1 252
 '@BASEBOARD_FAB2_LIB.BASEBOARD_FAB2(SCH_1):PAGE54_I43@MSTR_SCONN.SCONN288_H44441003(CHIPS)':
 'VSS'<14>: CDS_PINID='VSS(14)';
NODE_NAME     J6L1 250
 '@BASEBOARD_FAB2_LIB.BASEBOARD_FAB2(SCH_1):PAGE54_I43@MSTR_SCONN.SCONN288_H44441003(CHIPS)':
 'VSS'<15>: CDS_PINID='VSS(15)';
NODE_NAME     J6L1 248
 '@BASEBOARD_FAB2_LIB.BASEBOARD_FAB2(SCH_1):PAGE54_I43@MSTR_SCONN.SCONN288_H44441003(CHIPS)':
 'VSS'<16>: CDS_PINID='VSS(16)';
NODE_NAME     J6L1 246
 '@BASEBOARD_FAB2_LIB.BASEBOARD_FAB2(SCH_1):PAGE54_I43@MSTR_SCONN.SCONN288_H44441003(CHIPS)':
 'VSS'<17>: CDS_PINID='VSS(17)';
NODE_NAME     J6L1 243
 '@BASEBOARD_FAB2_LIB.BASEBOARD_FAB2(SCH_1):PAGE54_I43@MSTR_SCONN.SCONN288_H44441003(CHIPS)':
 'VSS'<18>: CDS_PINID='VSS(18)';
NODE_NAME     J6L1 241
 '@BASEBOARD_FAB2_LIB.BASEBOARD_FAB2(SCH_1):PAGE54_I43@MSTR_SCONN.SCONN288_H44441003(CHIPS)':
 'VSS'<19>: CDS_PINID='VSS(19)';
NODE_NAME     J6L1 239
 '@BASEBOARD_FAB2_LIB.BASEBOARD_FAB2(SCH_1):PAGE54_I43@MSTR_SCONN.SCONN288_H44441003(CHIPS)':
 'VSS'<20>: CDS_PINID='VSS(20)';
NODE_NAME     J6L1 202
 '@BASEBOARD_FAB2_LIB.BASEBOARD_FAB2(SCH_1):PAGE54_I43@MSTR_SCONN.SCONN288_H44441003(CHIPS)':
 'VSS'<21>: CDS_PINID='VSS(21)';
NODE_NAME     J6L1 200
 '@BASEBOARD_FAB2_LIB.BASEBOARD_FAB2(SCH_1):PAGE54_I43@MSTR_SCONN.SCONN288_H44441003(CHIPS)':
 'VSS'<22>: CDS_PINID='VSS(22)';
NODE_NAME     J6L1 198
 '@BASEBOARD_FAB2_LIB.BASEBOARD_FAB2(SCH_1):PAGE54_I43@MSTR_SCONN.SCONN288_H44441003(CHIPS)':
 'VSS'<23>: CDS_PINID='VSS(23)';
NODE_NAME     J6L1 195
 '@BASEBOARD_FAB2_LIB.BASEBOARD_FAB2(SCH_1):PAGE54_I43@MSTR_SCONN.SCONN288_H44441003(CHIPS)':
 'VSS'<24>: CDS_PINID='VSS(24)';
NODE_NAME     J6L1 193
 '@BASEBOARD_FAB2_LIB.BASEBOARD_FAB2(SCH_1):PAGE54_I43@MSTR_SCONN.SCONN288_H44441003(CHIPS)':
 'VSS'<25>: CDS_PINID='VSS(25)';
NODE_NAME     J6L1 191
 '@BASEBOARD_FAB2_LIB.BASEBOARD_FAB2(SCH_1):PAGE54_I43@MSTR_SCONN.SCONN288_H44441003(CHIPS)':
 'VSS'<26>: CDS_PINID='VSS(26)';
NODE_NAME     J6L1 189
 '@BASEBOARD_FAB2_LIB.BASEBOARD_FAB2(SCH_1):PAGE54_I43@MSTR_SCONN.SCONN288_H44441003(CHIPS)':
 'VSS'<27>: CDS_PINID='VSS(27)';
NODE_NAME     J6L1 187
 '@BASEBOARD_FAB2_LIB.BASEBOARD_FAB2(SCH_1):PAGE54_I43@MSTR_SCONN.SCONN288_H44441003(CHIPS)':
 'VSS'<28>: CDS_PINID='VSS(28)';
NODE_NAME     J6L1 184
 '@BASEBOARD_FAB2_LIB.BASEBOARD_FAB2(SCH_1):PAGE54_I43@MSTR_SCONN.SCONN288_H44441003(CHIPS)':
 'VSS'<29>: CDS_PINID='VSS(29)';
NODE_NAME     J6L1 182
 '@BASEBOARD_FAB2_LIB.BASEBOARD_FAB2(SCH_1):PAGE54_I43@MSTR_SCONN.SCONN288_H44441003(CHIPS)':
 'VSS'<30>: CDS_PINID='VSS(30)';
NODE_NAME     J6L1 180
 '@BASEBOARD_FAB2_LIB.BASEBOARD_FAB2(SCH_1):PAGE54_I43@MSTR_SCONN.SCONN288_H44441003(CHIPS)':
 'VSS'<31>: CDS_PINID='VSS(31)';
NODE_NAME     J6L1 178
 '@BASEBOARD_FAB2_LIB.BASEBOARD_FAB2(SCH_1):PAGE54_I43@MSTR_SCONN.SCONN288_H44441003(CHIPS)':
 'VSS'<32>: CDS_PINID='VSS(32)';
NODE_NAME     J6L1 176
 '@BASEBOARD_FAB2_LIB.BASEBOARD_FAB2(SCH_1):PAGE54_I43@MSTR_SCONN.SCONN288_H44441003(CHIPS)':
 'VSS'<33>: CDS_PINID='VSS(33)';
NODE_NAME     J6L1 173
 '@BASEBOARD_FAB2_LIB.BASEBOARD_FAB2(SCH_1):PAGE54_I43@MSTR_SCONN.SCONN288_H44441003(CHIPS)':
 'VSS'<34>: CDS_PINID='VSS(34)';
NODE_NAME     J6L1 171
 '@BASEBOARD_FAB2_LIB.BASEBOARD_FAB2(SCH_1):PAGE54_I43@MSTR_SCONN.SCONN288_H44441003(CHIPS)':
 'VSS'<35>: CDS_PINID='VSS(35)';
NODE_NAME     J6L1 169
 '@BASEBOARD_FAB2_LIB.BASEBOARD_FAB2(SCH_1):PAGE54_I43@MSTR_SCONN.SCONN288_H44441003(CHIPS)':
 'VSS'<36>: CDS_PINID='VSS(36)';
NODE_NAME     J6L1 167
 '@BASEBOARD_FAB2_LIB.BASEBOARD_FAB2(SCH_1):PAGE54_I43@MSTR_SCONN.SCONN288_H44441003(CHIPS)':
 'VSS'<37>: CDS_PINID='VSS(37)';
NODE_NAME     J6L1 165
 '@BASEBOARD_FAB2_LIB.BASEBOARD_FAB2(SCH_1):PAGE54_I43@MSTR_SCONN.SCONN288_H44441003(CHIPS)':
 'VSS'<38>: CDS_PINID='VSS(38)';
NODE_NAME     J6L1 162
 '@BASEBOARD_FAB2_LIB.BASEBOARD_FAB2(SCH_1):PAGE54_I43@MSTR_SCONN.SCONN288_H44441003(CHIPS)':
 'VSS'<39>: CDS_PINID='VSS(39)';
NODE_NAME     J6L1 160
 '@BASEBOARD_FAB2_LIB.BASEBOARD_FAB2(SCH_1):PAGE54_I43@MSTR_SCONN.SCONN288_H44441003(CHIPS)':
 'VSS'<40>: CDS_PINID='VSS(40)';
NODE_NAME     J6L1 158
 '@BASEBOARD_FAB2_LIB.BASEBOARD_FAB2(SCH_1):PAGE54_I43@MSTR_SCONN.SCONN288_H44441003(CHIPS)':
 'VSS'<41>: CDS_PINID='VSS(41)';
NODE_NAME     J6L1 156
 '@BASEBOARD_FAB2_LIB.BASEBOARD_FAB2(SCH_1):PAGE54_I43@MSTR_SCONN.SCONN288_H44441003(CHIPS)':
 'VSS'<42>: CDS_PINID='VSS(42)';
NODE_NAME     J6L1 154
 '@BASEBOARD_FAB2_LIB.BASEBOARD_FAB2(SCH_1):PAGE54_I43@MSTR_SCONN.SCONN288_H44441003(CHIPS)':
 'VSS'<43>: CDS_PINID='VSS(43)';
NODE_NAME     J6L1 151
 '@BASEBOARD_FAB2_LIB.BASEBOARD_FAB2(SCH_1):PAGE54_I43@MSTR_SCONN.SCONN288_H44441003(CHIPS)':
 'VSS'<44>: CDS_PINID='VSS(44)';
NODE_NAME     J6L1 149
 '@BASEBOARD_FAB2_LIB.BASEBOARD_FAB2(SCH_1):PAGE54_I43@MSTR_SCONN.SCONN288_H44441003(CHIPS)':
 'VSS'<45>: CDS_PINID='VSS(45)';
NODE_NAME     J6L1 147
 '@BASEBOARD_FAB2_LIB.BASEBOARD_FAB2(SCH_1):PAGE54_I43@MSTR_SCONN.SCONN288_H44441003(CHIPS)':
 'VSS'<46>: CDS_PINID='VSS(46)';
NODE_NAME     J6L1 138
 '@BASEBOARD_FAB2_LIB.BASEBOARD_FAB2(SCH_1):PAGE54_I43@MSTR_SCONN.SCONN288_H44441003(CHIPS)':
 'VSS'<47>: CDS_PINID='VSS(47)';
NODE_NAME     J6L1 136
 '@BASEBOARD_FAB2_LIB.BASEBOARD_FAB2(SCH_1):PAGE54_I43@MSTR_SCONN.SCONN288_H44441003(CHIPS)':
 'VSS'<48>: CDS_PINID='VSS(48)';
NODE_NAME     J6L1 134
 '@BASEBOARD_FAB2_LIB.BASEBOARD_FAB2(SCH_1):PAGE54_I43@MSTR_SCONN.SCONN288_H44441003(CHIPS)':
 'VSS'<49>: CDS_PINID='VSS(49)';
NODE_NAME     J6L1 131
 '@BASEBOARD_FAB2_LIB.BASEBOARD_FAB2(SCH_1):PAGE54_I43@MSTR_SCONN.SCONN288_H44441003(CHIPS)':
 'VSS'<50>: CDS_PINID='VSS(50)';
NODE_NAME     J6L1 129
 '@BASEBOARD_FAB2_LIB.BASEBOARD_FAB2(SCH_1):PAGE54_I43@MSTR_SCONN.SCONN288_H44441003(CHIPS)':
 'VSS'<51>: CDS_PINID='VSS(51)';
NODE_NAME     J6L1 127
 '@BASEBOARD_FAB2_LIB.BASEBOARD_FAB2(SCH_1):PAGE54_I43@MSTR_SCONN.SCONN288_H44441003(CHIPS)':
 'VSS'<52>: CDS_PINID='VSS(52)';
NODE_NAME     J6L1 125
 '@BASEBOARD_FAB2_LIB.BASEBOARD_FAB2(SCH_1):PAGE54_I43@MSTR_SCONN.SCONN288_H44441003(CHIPS)':
 'VSS'<53>: CDS_PINID='VSS(53)';
NODE_NAME     J6L1 123
 '@BASEBOARD_FAB2_LIB.BASEBOARD_FAB2(SCH_1):PAGE54_I43@MSTR_SCONN.SCONN288_H44441003(CHIPS)':
 'VSS'<54>: CDS_PINID='VSS(54)';
NODE_NAME     J6L1 120
 '@BASEBOARD_FAB2_LIB.BASEBOARD_FAB2(SCH_1):PAGE54_I43@MSTR_SCONN.SCONN288_H44441003(CHIPS)':
 'VSS'<55>: CDS_PINID='VSS(55)';
NODE_NAME     J6L1 118
 '@BASEBOARD_FAB2_LIB.BASEBOARD_FAB2(SCH_1):PAGE54_I43@MSTR_SCONN.SCONN288_H44441003(CHIPS)':
 'VSS'<56>: CDS_PINID='VSS(56)';
NODE_NAME     J6L1 116
 '@BASEBOARD_FAB2_LIB.BASEBOARD_FAB2(SCH_1):PAGE54_I43@MSTR_SCONN.SCONN288_H44441003(CHIPS)':
 'VSS'<57>: CDS_PINID='VSS(57)';
NODE_NAME     J6L1 114
 '@BASEBOARD_FAB2_LIB.BASEBOARD_FAB2(SCH_1):PAGE54_I43@MSTR_SCONN.SCONN288_H44441003(CHIPS)':
 'VSS'<58>: CDS_PINID='VSS(58)';
NODE_NAME     J6L1 112
 '@BASEBOARD_FAB2_LIB.BASEBOARD_FAB2(SCH_1):PAGE54_I43@MSTR_SCONN.SCONN288_H44441003(CHIPS)':
 'VSS'<59>: CDS_PINID='VSS(59)';
NODE_NAME     J6L1 109
 '@BASEBOARD_FAB2_LIB.BASEBOARD_FAB2(SCH_1):PAGE54_I43@MSTR_SCONN.SCONN288_H44441003(CHIPS)':
 'VSS'<60>: CDS_PINID='VSS(60)';
NODE_NAME     J6L1 107
 '@BASEBOARD_FAB2_LIB.BASEBOARD_FAB2(SCH_1):PAGE54_I43@MSTR_SCONN.SCONN288_H44441003(CHIPS)':
 'VSS'<61>: CDS_PINID='VSS(61)';
NODE_NAME     J6L1 105
 '@BASEBOARD_FAB2_LIB.BASEBOARD_FAB2(SCH_1):PAGE54_I43@MSTR_SCONN.SCONN288_H44441003(CHIPS)':
 'VSS'<62>: CDS_PINID='VSS(62)';
NODE_NAME     J6L1 103
 '@BASEBOARD_FAB2_LIB.BASEBOARD_FAB2(SCH_1):PAGE54_I43@MSTR_SCONN.SCONN288_H44441003(CHIPS)':
 'VSS'<63>: CDS_PINID='VSS(63)';
NODE_NAME     J6L1 101
 '@BASEBOARD_FAB2_LIB.BASEBOARD_FAB2(SCH_1):PAGE54_I43@MSTR_SCONN.SCONN288_H44441003(CHIPS)':
 'VSS'<64>: CDS_PINID='VSS(64)';
NODE_NAME     J6L1 98
 '@BASEBOARD_FAB2_LIB.BASEBOARD_FAB2(SCH_1):PAGE54_I43@MSTR_SCONN.SCONN288_H44441003(CHIPS)':
 'VSS'<65>: CDS_PINID='VSS(65)';
NODE_NAME     J6L1 96
 '@BASEBOARD_FAB2_LIB.BASEBOARD_FAB2(SCH_1):PAGE54_I43@MSTR_SCONN.SCONN288_H44441003(CHIPS)':
 'VSS'<66>: CDS_PINID='VSS(66)';
NODE_NAME     J6L1 94
 '@BASEBOARD_FAB2_LIB.BASEBOARD_FAB2(SCH_1):PAGE54_I43@MSTR_SCONN.SCONN288_H44441003(CHIPS)':
 'VSS'<67>: CDS_PINID='VSS(67)';
NODE_NAME     J6L1 57
 '@BASEBOARD_FAB2_LIB.BASEBOARD_FAB2(SCH_1):PAGE54_I43@MSTR_SCONN.SCONN288_H44441003(CHIPS)':
 'VSS'<68>: CDS_PINID='VSS(68)';
NODE_NAME     J6L1 55
 '@BASEBOARD_FAB2_LIB.BASEBOARD_FAB2(SCH_1):PAGE54_I43@MSTR_SCONN.SCONN288_H44441003(CHIPS)':
 'VSS'<69>: CDS_PINID='VSS(69)';
NODE_NAME     J6L1 53
 '@BASEBOARD_FAB2_LIB.BASEBOARD_FAB2(SCH_1):PAGE54_I43@MSTR_SCONN.SCONN288_H44441003(CHIPS)':
 'VSS'<70>: CDS_PINID='VSS(70)';
NODE_NAME     J6L1 50
 '@BASEBOARD_FAB2_LIB.BASEBOARD_FAB2(SCH_1):PAGE54_I43@MSTR_SCONN.SCONN288_H44441003(CHIPS)':
 'VSS'<71>: CDS_PINID='VSS(71)';
NODE_NAME     J6L1 48
 '@BASEBOARD_FAB2_LIB.BASEBOARD_FAB2(SCH_1):PAGE54_I43@MSTR_SCONN.SCONN288_H44441003(CHIPS)':
 'VSS'<72>: CDS_PINID='VSS(72)';
NODE_NAME     J6L1 46
 '@BASEBOARD_FAB2_LIB.BASEBOARD_FAB2(SCH_1):PAGE54_I43@MSTR_SCONN.SCONN288_H44441003(CHIPS)':
 'VSS'<73>: CDS_PINID='VSS(73)';
NODE_NAME     J6L1 44
 '@BASEBOARD_FAB2_LIB.BASEBOARD_FAB2(SCH_1):PAGE54_I43@MSTR_SCONN.SCONN288_H44441003(CHIPS)':
 'VSS'<74>: CDS_PINID='VSS(74)';
NODE_NAME     J6L1 42
 '@BASEBOARD_FAB2_LIB.BASEBOARD_FAB2(SCH_1):PAGE54_I43@MSTR_SCONN.SCONN288_H44441003(CHIPS)':
 'VSS'<75>: CDS_PINID='VSS(75)';
NODE_NAME     J6L1 39
 '@BASEBOARD_FAB2_LIB.BASEBOARD_FAB2(SCH_1):PAGE54_I43@MSTR_SCONN.SCONN288_H44441003(CHIPS)':
 'VSS'<76>: CDS_PINID='VSS(76)';
NODE_NAME     J6L1 37
 '@BASEBOARD_FAB2_LIB.BASEBOARD_FAB2(SCH_1):PAGE54_I43@MSTR_SCONN.SCONN288_H44441003(CHIPS)':
 'VSS'<77>: CDS_PINID='VSS(77)';
NODE_NAME     J6L1 35
 '@BASEBOARD_FAB2_LIB.BASEBOARD_FAB2(SCH_1):PAGE54_I43@MSTR_SCONN.SCONN288_H44441003(CHIPS)':
 'VSS'<78>: CDS_PINID='VSS(78)';
NODE_NAME     J6L1 33
 '@BASEBOARD_FAB2_LIB.BASEBOARD_FAB2(SCH_1):PAGE54_I43@MSTR_SCONN.SCONN288_H44441003(CHIPS)':
 'VSS'<79>: CDS_PINID='VSS(79)';
NODE_NAME     J6L1 31
 '@BASEBOARD_FAB2_LIB.BASEBOARD_FAB2(SCH_1):PAGE54_I43@MSTR_SCONN.SCONN288_H44441003(CHIPS)':
 'VSS'<80>: CDS_PINID='VSS(80)';
NODE_NAME     J6L1 28
 '@BASEBOARD_FAB2_LIB.BASEBOARD_FAB2(SCH_1):PAGE54_I43@MSTR_SCONN.SCONN288_H44441003(CHIPS)':
 'VSS'<81>: CDS_PINID='VSS(81)';
NODE_NAME     J6L1 26
 '@BASEBOARD_FAB2_LIB.BASEBOARD_FAB2(SCH_1):PAGE54_I43@MSTR_SCONN.SCONN288_H44441003(CHIPS)':
 'VSS'<82>: CDS_PINID='VSS(82)';
NODE_NAME     J6L1 24
 '@BASEBOARD_FAB2_LIB.BASEBOARD_FAB2(SCH_1):PAGE54_I43@MSTR_SCONN.SCONN288_H44441003(CHIPS)':
 'VSS'<83>: CDS_PINID='VSS(83)';
NODE_NAME     J6L1 22
 '@BASEBOARD_FAB2_LIB.BASEBOARD_FAB2(SCH_1):PAGE54_I43@MSTR_SCONN.SCONN288_H44441003(CHIPS)':
 'VSS'<84>: CDS_PINID='VSS(84)';
NODE_NAME     J6L1 20
 '@BASEBOARD_FAB2_LIB.BASEBOARD_FAB2(SCH_1):PAGE54_I43@MSTR_SCONN.SCONN288_H44441003(CHIPS)':
 'VSS'<85>: CDS_PINID='VSS(85)';
NODE_NAME     J6L1 17
 '@BASEBOARD_FAB2_LIB.BASEBOARD_FAB2(SCH_1):PAGE54_I43@MSTR_SCONN.SCONN288_H44441003(CHIPS)':
 'VSS'<86>: CDS_PINID='VSS(86)';
NODE_NAME     J6L1 15
 '@BASEBOARD_FAB2_LIB.BASEBOARD_FAB2(SCH_1):PAGE54_I43@MSTR_SCONN.SCONN288_H44441003(CHIPS)':
 'VSS'<87>: CDS_PINID='VSS(87)';
NODE_NAME     J6L1 13
 '@BASEBOARD_FAB2_LIB.BASEBOARD_FAB2(SCH_1):PAGE54_I43@MSTR_SCONN.SCONN288_H44441003(CHIPS)':
 'VSS'<88>: CDS_PINID='VSS(88)';
NODE_NAME     J6L1 11
 '@BASEBOARD_FAB2_LIB.BASEBOARD_FAB2(SCH_1):PAGE54_I43@MSTR_SCONN.SCONN288_H44441003(CHIPS)':
 'VSS'<89>: CDS_PINID='VSS(89)';
NODE_NAME     J6L1 9
 '@BASEBOARD_FAB2_LIB.BASEBOARD_FAB2(SCH_1):PAGE54_I43@MSTR_SCONN.SCONN288_H44441003(CHIPS)':
 'VSS'<90>: CDS_PINID='VSS(90)';
NODE_NAME     J6L1 6
 '@BASEBOARD_FAB2_LIB.BASEBOARD_FAB2(SCH_1):PAGE54_I43@MSTR_SCONN.SCONN288_H44441003(CHIPS)':
 'VSS'<91>: CDS_PINID='VSS(91)';
NODE_NAME     J6L1 4
 '@BASEBOARD_FAB2_LIB.BASEBOARD_FAB2(SCH_1):PAGE54_I43@MSTR_SCONN.SCONN288_H44441003(CHIPS)':
 'VSS'<92>: CDS_PINID='VSS(92)';
NODE_NAME     J6L1 2
 '@BASEBOARD_FAB2_LIB.BASEBOARD_FAB2(SCH_1):PAGE54_I43@MSTR_SCONN.SCONN288_H44441003(CHIPS)':
 'VSS'<93>: CDS_PINID='VSS(93)';
NODE_NAME     J6L1 140
 '@BASEBOARD_FAB2_LIB.BASEBOARD_FAB2(SCH_1):PAGE54_I111@MSTR_SCONN.SCONN288_H44441003(CHIPS)':
 'SA'<1>: CDS_PINID='SA(1)';
NODE_NAME     C4A5 2
 '@BASEBOARD_FAB2_LIB.BASEBOARD_FAB2(SCH_1):PAGE54_I179@DEV_DISCRETE.CAP_A(CHIPS)':
 'B': CDS_PINID='B';
NODE_NAME     R7P19 2
 '@BASEBOARD_FAB2_LIB.BASEBOARD_FAB2(SCH_1):PAGE55_I115@MSTR_DISCRETE.RES(CHIPS)':
 'B': CDS_PINID='B';
NODE_NAME     R3D1 2
 '@BASEBOARD_FAB2_LIB.BASEBOARD_FAB2(SCH_1):PAGE55_I116@MSTR_DISCRETE.RES(CHIPS)':
 'B': CDS_PINID='B';
NODE_NAME     R3D2 2
 '@BASEBOARD_FAB2_LIB.BASEBOARD_FAB2(SCH_1):PAGE55_I117@MSTR_DISCRETE.RES(CHIPS)':
 'B': CDS_PINID='B';
NODE_NAME     R3D3 2
 '@BASEBOARD_FAB2_LIB.BASEBOARD_FAB2(SCH_1):PAGE55_I118@MSTR_DISCRETE.RES(CHIPS)':
 'B': CDS_PINID='B';
NODE_NAME     R7P16 2
 '@BASEBOARD_FAB2_LIB.BASEBOARD_FAB2(SCH_1):PAGE55_I119@MSTR_DISCRETE.RES(CHIPS)':
 'B': CDS_PINID='B';
NODE_NAME     R7P8 2
 '@BASEBOARD_FAB2_LIB.BASEBOARD_FAB2(SCH_1):PAGE55_I123@MSTR_DISCRETE.RES(CHIPS)':
 'B': CDS_PINID='B';
NODE_NAME     R7P10 2
 '@BASEBOARD_FAB2_LIB.BASEBOARD_FAB2(SCH_1):PAGE55_I124@MSTR_DISCRETE.RES(CHIPS)':
 'B': CDS_PINID='B';
NODE_NAME     R3D19 2
 '@BASEBOARD_FAB2_LIB.BASEBOARD_FAB2(SCH_1):PAGE55_I125@MSTR_DISCRETE.RES(CHIPS)':
 'B': CDS_PINID='B';
NODE_NAME     R7P11 2
 '@BASEBOARD_FAB2_LIB.BASEBOARD_FAB2(SCH_1):PAGE55_I126@MSTR_DISCRETE.RES(CHIPS)':
 'B': CDS_PINID='B';
NODE_NAME     R7P17 2
 '@BASEBOARD_FAB2_LIB.BASEBOARD_FAB2(SCH_1):PAGE55_I140@MSTR_DISCRETE.RES(CHIPS)':
 'B': CDS_PINID='B';
NODE_NAME     R3D4 2
 '@BASEBOARD_FAB2_LIB.BASEBOARD_FAB2(SCH_1):PAGE55_I155@MSTR_DISCRETE.RES(CHIPS)':
 'B': CDS_PINID='B';
NODE_NAME     R8P3 2
 '@BASEBOARD_FAB2_LIB.BASEBOARD_FAB2(SCH_1):PAGE56_I173@MSTR_DISCRETE.RES(CHIPS)':
 'B': CDS_PINID='B';
NODE_NAME     R8R1 2
 '@BASEBOARD_FAB2_LIB.BASEBOARD_FAB2(SCH_1):PAGE56_I174@MSTR_DISCRETE.RES(CHIPS)':
 'B': CDS_PINID='B';
NODE_NAME     U2D1 DF23
 '@BASEBOARD_FAB2_LIB.BASEBOARD_FAB2(SCH_1):PAGE69_I1@CHPSET_LIB.SKX_EXT_B(CHIPS)':
 'UPI2_RX_DN'<0>: CDS_PINID='UPI2_RX_DN(0)';
NODE_NAME     U2D1 DE22
 '@BASEBOARD_FAB2_LIB.BASEBOARD_FAB2(SCH_1):PAGE69_I1@CHPSET_LIB.SKX_EXT_B(CHIPS)':
 'UPI2_RX_DN'<1>: CDS_PINID='UPI2_RX_DN(1)';
NODE_NAME     U2D1 DC22
 '@BASEBOARD_FAB2_LIB.BASEBOARD_FAB2(SCH_1):PAGE69_I1@CHPSET_LIB.SKX_EXT_B(CHIPS)':
 'UPI2_RX_DN'<2>: CDS_PINID='UPI2_RX_DN(2)';
NODE_NAME     U2D1 DB21
 '@BASEBOARD_FAB2_LIB.BASEBOARD_FAB2(SCH_1):PAGE69_I1@CHPSET_LIB.SKX_EXT_B(CHIPS)':
 'UPI2_RX_DN'<3>: CDS_PINID='UPI2_RX_DN(3)';
NODE_NAME     U2D1 DD19
 '@BASEBOARD_FAB2_LIB.BASEBOARD_FAB2(SCH_1):PAGE69_I1@CHPSET_LIB.SKX_EXT_B(CHIPS)':
 'UPI2_RX_DN'<4>: CDS_PINID='UPI2_RX_DN(4)';
NODE_NAME     U2D1 DA20
 '@BASEBOARD_FAB2_LIB.BASEBOARD_FAB2(SCH_1):PAGE69_I1@CHPSET_LIB.SKX_EXT_B(CHIPS)':
 'UPI2_RX_DN'<5>: CDS_PINID='UPI2_RX_DN(5)';
NODE_NAME     U2D1 CW20
 '@BASEBOARD_FAB2_LIB.BASEBOARD_FAB2(SCH_1):PAGE69_I1@CHPSET_LIB.SKX_EXT_B(CHIPS)':
 'UPI2_RX_DN'<6>: CDS_PINID='UPI2_RX_DN(6)';
NODE_NAME     U2D1 CV19
 '@BASEBOARD_FAB2_LIB.BASEBOARD_FAB2(SCH_1):PAGE69_I1@CHPSET_LIB.SKX_EXT_B(CHIPS)':
 'UPI2_RX_DN'<7>: CDS_PINID='UPI2_RX_DN(7)';
NODE_NAME     U2D1 CT21
 '@BASEBOARD_FAB2_LIB.BASEBOARD_FAB2(SCH_1):PAGE69_I1@CHPSET_LIB.SKX_EXT_B(CHIPS)':
 'UPI2_RX_DN'<8>: CDS_PINID='UPI2_RX_DN(8)';
NODE_NAME     U2D1 CR18
 '@BASEBOARD_FAB2_LIB.BASEBOARD_FAB2(SCH_1):PAGE69_I1@CHPSET_LIB.SKX_EXT_B(CHIPS)':
 'UPI2_RX_DN'<9>: CDS_PINID='UPI2_RX_DN(9)';
NODE_NAME     U2D1 CN20
 '@BASEBOARD_FAB2_LIB.BASEBOARD_FAB2(SCH_1):PAGE69_I1@CHPSET_LIB.SKX_EXT_B(CHIPS)':
 'UPI2_RX_DN'<10>: CDS_PINID='UPI2_RX_DN(10)';
NODE_NAME     U2D1 CP21
 '@BASEBOARD_FAB2_LIB.BASEBOARD_FAB2(SCH_1):PAGE69_I1@CHPSET_LIB.SKX_EXT_B(CHIPS)':
 'UPI2_RX_DN'<11>: CDS_PINID='UPI2_RX_DN(11)';
NODE_NAME     U2D1 CL16
 '@BASEBOARD_FAB2_LIB.BASEBOARD_FAB2(SCH_1):PAGE69_I1@CHPSET_LIB.SKX_EXT_B(CHIPS)':
 'UPI2_RX_DN'<12>: CDS_PINID='UPI2_RX_DN(12)';
NODE_NAME     U2D1 CJ18
 '@BASEBOARD_FAB2_LIB.BASEBOARD_FAB2(SCH_1):PAGE69_I1@CHPSET_LIB.SKX_EXT_B(CHIPS)':
 'UPI2_RX_DN'<13>: CDS_PINID='UPI2_RX_DN(13)';
NODE_NAME     U2D1 CH17
 '@BASEBOARD_FAB2_LIB.BASEBOARD_FAB2(SCH_1):PAGE69_I1@CHPSET_LIB.SKX_EXT_B(CHIPS)':
 'UPI2_RX_DN'<14>: CDS_PINID='UPI2_RX_DN(14)';
NODE_NAME     U2D1 CE16
 '@BASEBOARD_FAB2_LIB.BASEBOARD_FAB2(SCH_1):PAGE69_I1@CHPSET_LIB.SKX_EXT_B(CHIPS)':
 'UPI2_RX_DN'<15>: CDS_PINID='UPI2_RX_DN(15)';
NODE_NAME     U2D1 CD15
 '@BASEBOARD_FAB2_LIB.BASEBOARD_FAB2(SCH_1):PAGE69_I1@CHPSET_LIB.SKX_EXT_B(CHIPS)':
 'UPI2_RX_DN'<16>: CDS_PINID='UPI2_RX_DN(16)';
NODE_NAME     U2D1 CF17
 '@BASEBOARD_FAB2_LIB.BASEBOARD_FAB2(SCH_1):PAGE69_I1@CHPSET_LIB.SKX_EXT_B(CHIPS)':
 'UPI2_RX_DN'<17>: CDS_PINID='UPI2_RX_DN(17)';
NODE_NAME     U2D1 CB15
 '@BASEBOARD_FAB2_LIB.BASEBOARD_FAB2(SCH_1):PAGE69_I1@CHPSET_LIB.SKX_EXT_B(CHIPS)':
 'UPI2_RX_DN'<18>: CDS_PINID='UPI2_RX_DN(18)';
NODE_NAME     U2D1 BY17
 '@BASEBOARD_FAB2_LIB.BASEBOARD_FAB2(SCH_1):PAGE69_I1@CHPSET_LIB.SKX_EXT_B(CHIPS)':
 'UPI2_RX_DN'<19>: CDS_PINID='UPI2_RX_DN(19)';
NODE_NAME     U2D1 DG22
 '@BASEBOARD_FAB2_LIB.BASEBOARD_FAB2(SCH_1):PAGE69_I1@CHPSET_LIB.SKX_EXT_B(CHIPS)':
 'UPI2_RX_DP'<0>: CDS_PINID='UPI2_RX_DP(0)';
NODE_NAME     U2D1 DD21
 '@BASEBOARD_FAB2_LIB.BASEBOARD_FAB2(SCH_1):PAGE69_I1@CHPSET_LIB.SKX_EXT_B(CHIPS)':
 'UPI2_RX_DP'<1>: CDS_PINID='UPI2_RX_DP(1)';
NODE_NAME     U2D1 DA22
 '@BASEBOARD_FAB2_LIB.BASEBOARD_FAB2(SCH_1):PAGE69_I1@CHPSET_LIB.SKX_EXT_B(CHIPS)':
 'UPI2_RX_DP'<2>: CDS_PINID='UPI2_RX_DP(2)';
NODE_NAME     U2D1 DC20
 '@BASEBOARD_FAB2_LIB.BASEBOARD_FAB2(SCH_1):PAGE69_I1@CHPSET_LIB.SKX_EXT_B(CHIPS)':
 'UPI2_RX_DP'<3>: CDS_PINID='UPI2_RX_DP(3)';
NODE_NAME     U2D1 DB19
 '@BASEBOARD_FAB2_LIB.BASEBOARD_FAB2(SCH_1):PAGE69_I1@CHPSET_LIB.SKX_EXT_B(CHIPS)':
 'UPI2_RX_DP'<4>: CDS_PINID='UPI2_RX_DP(4)';
NODE_NAME     U2D1 CY19
 '@BASEBOARD_FAB2_LIB.BASEBOARD_FAB2(SCH_1):PAGE69_I1@CHPSET_LIB.SKX_EXT_B(CHIPS)':
 'UPI2_RX_DP'<5>: CDS_PINID='UPI2_RX_DP(5)';
NODE_NAME     U2D1 CU20
 '@BASEBOARD_FAB2_LIB.BASEBOARD_FAB2(SCH_1):PAGE69_I1@CHPSET_LIB.SKX_EXT_B(CHIPS)':
 'UPI2_RX_DP'<6>: CDS_PINID='UPI2_RX_DP(6)';
NODE_NAME     U2D1 CW18
 '@BASEBOARD_FAB2_LIB.BASEBOARD_FAB2(SCH_1):PAGE69_I1@CHPSET_LIB.SKX_EXT_B(CHIPS)':
 'UPI2_RX_DP'<7>: CDS_PINID='UPI2_RX_DP(7)';
NODE_NAME     U2D1 CR20
 '@BASEBOARD_FAB2_LIB.BASEBOARD_FAB2(SCH_1):PAGE69_I1@CHPSET_LIB.SKX_EXT_B(CHIPS)':
 'UPI2_RX_DP'<8>: CDS_PINID='UPI2_RX_DP(8)';
NODE_NAME     U2D1 CN18
 '@BASEBOARD_FAB2_LIB.BASEBOARD_FAB2(SCH_1):PAGE69_I1@CHPSET_LIB.SKX_EXT_B(CHIPS)':
 'UPI2_RX_DP'<9>: CDS_PINID='UPI2_RX_DP(9)';
NODE_NAME     U2D1 CP19
 '@BASEBOARD_FAB2_LIB.BASEBOARD_FAB2(SCH_1):PAGE69_I1@CHPSET_LIB.SKX_EXT_B(CHIPS)':
 'UPI2_RX_DP'<10>: CDS_PINID='UPI2_RX_DP(10)';
NODE_NAME     U2D1 CM21
 '@BASEBOARD_FAB2_LIB.BASEBOARD_FAB2(SCH_1):PAGE69_I1@CHPSET_LIB.SKX_EXT_B(CHIPS)':
 'UPI2_RX_DP'<11>: CDS_PINID='UPI2_RX_DP(11)';
NODE_NAME     U2D1 CJ16
 '@BASEBOARD_FAB2_LIB.BASEBOARD_FAB2(SCH_1):PAGE69_I1@CHPSET_LIB.SKX_EXT_B(CHIPS)':
 'UPI2_RX_DP'<12>: CDS_PINID='UPI2_RX_DP(12)';
NODE_NAME     U2D1 CK17
 '@BASEBOARD_FAB2_LIB.BASEBOARD_FAB2(SCH_1):PAGE69_I1@CHPSET_LIB.SKX_EXT_B(CHIPS)':
 'UPI2_RX_DP'<13>: CDS_PINID='UPI2_RX_DP(13)';
NODE_NAME     U2D1 CG16
 '@BASEBOARD_FAB2_LIB.BASEBOARD_FAB2(SCH_1):PAGE69_I1@CHPSET_LIB.SKX_EXT_B(CHIPS)':
 'UPI2_RX_DP'<14>: CDS_PINID='UPI2_RX_DP(14)';
NODE_NAME     U2D1 CF15
 '@BASEBOARD_FAB2_LIB.BASEBOARD_FAB2(SCH_1):PAGE69_I1@CHPSET_LIB.SKX_EXT_B(CHIPS)':
 'UPI2_RX_DP'<15>: CDS_PINID='UPI2_RX_DP(15)';
NODE_NAME     U2D1 CC14
 '@BASEBOARD_FAB2_LIB.BASEBOARD_FAB2(SCH_1):PAGE69_I1@CHPSET_LIB.SKX_EXT_B(CHIPS)':
 'UPI2_RX_DP'<16>: CDS_PINID='UPI2_RX_DP(16)';
NODE_NAME     U2D1 CD17
 '@BASEBOARD_FAB2_LIB.BASEBOARD_FAB2(SCH_1):PAGE69_I1@CHPSET_LIB.SKX_EXT_B(CHIPS)':
 'UPI2_RX_DP'<17>: CDS_PINID='UPI2_RX_DP(17)';
NODE_NAME     U2D1 BY15
 '@BASEBOARD_FAB2_LIB.BASEBOARD_FAB2(SCH_1):PAGE69_I1@CHPSET_LIB.SKX_EXT_B(CHIPS)':
 'UPI2_RX_DP'<18>: CDS_PINID='UPI2_RX_DP(18)';
NODE_NAME     U2D1 CA16
 '@BASEBOARD_FAB2_LIB.BASEBOARD_FAB2(SCH_1):PAGE69_I1@CHPSET_LIB.SKX_EXT_B(CHIPS)':
 'UPI2_RX_DP'<19>: CDS_PINID='UPI2_RX_DP(19)';
NODE_NAME     R3D27 2
 '@BASEBOARD_FAB2_LIB.BASEBOARD_FAB2(SCH_1):PAGE71_I43@MSTR_DISCRETE.RES(CHIPS)':
 'B': CDS_PINID='B';
NODE_NAME     C3D3 2
 '@BASEBOARD_FAB2_LIB.BASEBOARD_FAB2(SCH_1):PAGE72_I25@MSTR_DISCRETE.CAP(CHIPS)':
 'B': CDS_PINID='B';
NODE_NAME     U2D1 J74
 '@BASEBOARD_FAB2_LIB.BASEBOARD_FAB2(SCH_1):PAGE74_I20@CHPSET_LIB.SKX_EXT_B(CHIPS)':
 'VSS'<1094>: CDS_PINID='VSS(1094)';
NODE_NAME     U2D1 J72
 '@BASEBOARD_FAB2_LIB.BASEBOARD_FAB2(SCH_1):PAGE74_I20@CHPSET_LIB.SKX_EXT_B(CHIPS)':
 'VSS'<1095>: CDS_PINID='VSS(1095)';
NODE_NAME     U2D1 J40
 '@BASEBOARD_FAB2_LIB.BASEBOARD_FAB2(SCH_1):PAGE74_I20@CHPSET_LIB.SKX_EXT_B(CHIPS)':
 'VSS'<1096>: CDS_PINID='VSS(1096)';
NODE_NAME     U2D1 J38
 '@BASEBOARD_FAB2_LIB.BASEBOARD_FAB2(SCH_1):PAGE74_I20@CHPSET_LIB.SKX_EXT_B(CHIPS)':
 'VSS'<1097>: CDS_PINID='VSS(1097)';
NODE_NAME     U2D1 J34
 '@BASEBOARD_FAB2_LIB.BASEBOARD_FAB2(SCH_1):PAGE74_I20@CHPSET_LIB.SKX_EXT_B(CHIPS)':
 'VSS'<1098>: CDS_PINID='VSS(1098)';
NODE_NAME     U2D1 J32
 '@BASEBOARD_FAB2_LIB.BASEBOARD_FAB2(SCH_1):PAGE74_I20@CHPSET_LIB.SKX_EXT_B(CHIPS)':
 'VSS'<1099>: CDS_PINID='VSS(1099)';
NODE_NAME     U2D1 J28
 '@BASEBOARD_FAB2_LIB.BASEBOARD_FAB2(SCH_1):PAGE74_I20@CHPSET_LIB.SKX_EXT_B(CHIPS)':
 'VSS'<1100>: CDS_PINID='VSS(1100)';
NODE_NAME     U2D1 J26
 '@BASEBOARD_FAB2_LIB.BASEBOARD_FAB2(SCH_1):PAGE74_I20@CHPSET_LIB.SKX_EXT_B(CHIPS)':
 'VSS'<1101>: CDS_PINID='VSS(1101)';
NODE_NAME     U2D1 J22
 '@BASEBOARD_FAB2_LIB.BASEBOARD_FAB2(SCH_1):PAGE74_I20@CHPSET_LIB.SKX_EXT_B(CHIPS)':
 'VSS'<1102>: CDS_PINID='VSS(1102)';
NODE_NAME     U2D1 J14
 '@BASEBOARD_FAB2_LIB.BASEBOARD_FAB2(SCH_1):PAGE74_I20@CHPSET_LIB.SKX_EXT_B(CHIPS)':
 'VSS'<1103>: CDS_PINID='VSS(1103)';
NODE_NAME     U2D1 J12
 '@BASEBOARD_FAB2_LIB.BASEBOARD_FAB2(SCH_1):PAGE74_I20@CHPSET_LIB.SKX_EXT_B(CHIPS)':
 'VSS'<1104>: CDS_PINID='VSS(1104)';
NODE_NAME     U2D1 J4
 '@BASEBOARD_FAB2_LIB.BASEBOARD_FAB2(SCH_1):PAGE74_I20@CHPSET_LIB.SKX_EXT_B(CHIPS)':
 'VSS'<1105>: CDS_PINID='VSS(1105)';
NODE_NAME     U2D1 DN44
 '@BASEBOARD_FAB2_LIB.BASEBOARD_FAB2(SCH_1):PAGE74_I20@CHPSET_LIB.SKX_EXT_B(CHIPS)':
 'VSS'<1106>: CDS_PINID='VSS(1106)';
NODE_NAME     U2D1 H75
 '@BASEBOARD_FAB2_LIB.BASEBOARD_FAB2(SCH_1):PAGE74_I20@CHPSET_LIB.SKX_EXT_B(CHIPS)':
 'VSS'<1107>: CDS_PINID='VSS(1107)';
NODE_NAME     U2D1 H71
 '@BASEBOARD_FAB2_LIB.BASEBOARD_FAB2(SCH_1):PAGE74_I20@CHPSET_LIB.SKX_EXT_B(CHIPS)':
 'VSS'<1108>: CDS_PINID='VSS(1108)';
NODE_NAME     U2D1 H65
 '@BASEBOARD_FAB2_LIB.BASEBOARD_FAB2(SCH_1):PAGE74_I20@CHPSET_LIB.SKX_EXT_B(CHIPS)':
 'VSS'<1109>: CDS_PINID='VSS(1109)';
NODE_NAME     U2D1 H41
 '@BASEBOARD_FAB2_LIB.BASEBOARD_FAB2(SCH_1):PAGE74_I20@CHPSET_LIB.SKX_EXT_B(CHIPS)':
 'VSS'<1110>: CDS_PINID='VSS(1110)';
NODE_NAME     U2D1 H39
 '@BASEBOARD_FAB2_LIB.BASEBOARD_FAB2(SCH_1):PAGE74_I20@CHPSET_LIB.SKX_EXT_B(CHIPS)':
 'VSS'<1111>: CDS_PINID='VSS(1111)';
NODE_NAME     U2D1 H37
 '@BASEBOARD_FAB2_LIB.BASEBOARD_FAB2(SCH_1):PAGE74_I20@CHPSET_LIB.SKX_EXT_B(CHIPS)':
 'VSS'<1112>: CDS_PINID='VSS(1112)';
NODE_NAME     U2D1 H35
 '@BASEBOARD_FAB2_LIB.BASEBOARD_FAB2(SCH_1):PAGE74_I20@CHPSET_LIB.SKX_EXT_B(CHIPS)':
 'VSS'<1113>: CDS_PINID='VSS(1113)';
NODE_NAME     U2D1 H33
 '@BASEBOARD_FAB2_LIB.BASEBOARD_FAB2(SCH_1):PAGE74_I20@CHPSET_LIB.SKX_EXT_B(CHIPS)':
 'VSS'<1114>: CDS_PINID='VSS(1114)';
NODE_NAME     U2D1 H31
 '@BASEBOARD_FAB2_LIB.BASEBOARD_FAB2(SCH_1):PAGE74_I20@CHPSET_LIB.SKX_EXT_B(CHIPS)':
 'VSS'<1115>: CDS_PINID='VSS(1115)';
NODE_NAME     U2D1 H29
 '@BASEBOARD_FAB2_LIB.BASEBOARD_FAB2(SCH_1):PAGE74_I20@CHPSET_LIB.SKX_EXT_B(CHIPS)':
 'VSS'<1116>: CDS_PINID='VSS(1116)';
NODE_NAME     U2D1 H27
 '@BASEBOARD_FAB2_LIB.BASEBOARD_FAB2(SCH_1):PAGE74_I20@CHPSET_LIB.SKX_EXT_B(CHIPS)':
 'VSS'<1117>: CDS_PINID='VSS(1117)';
NODE_NAME     U2D1 H25
 '@BASEBOARD_FAB2_LIB.BASEBOARD_FAB2(SCH_1):PAGE74_I20@CHPSET_LIB.SKX_EXT_B(CHIPS)':
 'VSS'<1118>: CDS_PINID='VSS(1118)';
NODE_NAME     U2D1 H11
 '@BASEBOARD_FAB2_LIB.BASEBOARD_FAB2(SCH_1):PAGE74_I20@CHPSET_LIB.SKX_EXT_B(CHIPS)':
 'VSS'<1119>: CDS_PINID='VSS(1119)';
NODE_NAME     U2D1 H3
 '@BASEBOARD_FAB2_LIB.BASEBOARD_FAB2(SCH_1):PAGE74_I20@CHPSET_LIB.SKX_EXT_B(CHIPS)':
 'VSS'<1120>: CDS_PINID='VSS(1120)';
NODE_NAME     U2D1 G82
 '@BASEBOARD_FAB2_LIB.BASEBOARD_FAB2(SCH_1):PAGE74_I20@CHPSET_LIB.SKX_EXT_B(CHIPS)':
 'VSS'<1121>: CDS_PINID='VSS(1121)';
NODE_NAME     U2D1 G80
 '@BASEBOARD_FAB2_LIB.BASEBOARD_FAB2(SCH_1):PAGE74_I20@CHPSET_LIB.SKX_EXT_B(CHIPS)':
 'VSS'<1122>: CDS_PINID='VSS(1122)';
NODE_NAME     U2D1 G78
 '@BASEBOARD_FAB2_LIB.BASEBOARD_FAB2(SCH_1):PAGE74_I20@CHPSET_LIB.SKX_EXT_B(CHIPS)':
 'VSS'<1123>: CDS_PINID='VSS(1123)';
NODE_NAME     U2D1 G76
 '@BASEBOARD_FAB2_LIB.BASEBOARD_FAB2(SCH_1):PAGE74_I20@CHPSET_LIB.SKX_EXT_B(CHIPS)':
 'VSS'<1124>: CDS_PINID='VSS(1124)';
NODE_NAME     U2D1 G70
 '@BASEBOARD_FAB2_LIB.BASEBOARD_FAB2(SCH_1):PAGE74_I20@CHPSET_LIB.SKX_EXT_B(CHIPS)':
 'VSS'<1125>: CDS_PINID='VSS(1125)';
NODE_NAME     U2D1 G66
 '@BASEBOARD_FAB2_LIB.BASEBOARD_FAB2(SCH_1):PAGE74_I20@CHPSET_LIB.SKX_EXT_B(CHIPS)':
 'VSS'<1126>: CDS_PINID='VSS(1126)';
NODE_NAME     U2D1 G42
 '@BASEBOARD_FAB2_LIB.BASEBOARD_FAB2(SCH_1):PAGE74_I20@CHPSET_LIB.SKX_EXT_B(CHIPS)':
 'VSS'<1127>: CDS_PINID='VSS(1127)';
NODE_NAME     U2D1 G38
 '@BASEBOARD_FAB2_LIB.BASEBOARD_FAB2(SCH_1):PAGE74_I20@CHPSET_LIB.SKX_EXT_B(CHIPS)':
 'VSS'<1128>: CDS_PINID='VSS(1128)';
NODE_NAME     U2D1 G36
 '@BASEBOARD_FAB2_LIB.BASEBOARD_FAB2(SCH_1):PAGE74_I20@CHPSET_LIB.SKX_EXT_B(CHIPS)':
 'VSS'<1129>: CDS_PINID='VSS(1129)';
NODE_NAME     U2D1 G32
 '@BASEBOARD_FAB2_LIB.BASEBOARD_FAB2(SCH_1):PAGE74_I20@CHPSET_LIB.SKX_EXT_B(CHIPS)':
 'VSS'<1130>: CDS_PINID='VSS(1130)';
NODE_NAME     U2D1 G30
 '@BASEBOARD_FAB2_LIB.BASEBOARD_FAB2(SCH_1):PAGE74_I20@CHPSET_LIB.SKX_EXT_B(CHIPS)':
 'VSS'<1131>: CDS_PINID='VSS(1131)';
NODE_NAME     U2D1 G26
 '@BASEBOARD_FAB2_LIB.BASEBOARD_FAB2(SCH_1):PAGE74_I20@CHPSET_LIB.SKX_EXT_B(CHIPS)':
 'VSS'<1132>: CDS_PINID='VSS(1132)';
NODE_NAME     U2D1 G24
 '@BASEBOARD_FAB2_LIB.BASEBOARD_FAB2(SCH_1):PAGE74_I20@CHPSET_LIB.SKX_EXT_B(CHIPS)':
 'VSS'<1133>: CDS_PINID='VSS(1133)';
NODE_NAME     U2D1 G22
 '@BASEBOARD_FAB2_LIB.BASEBOARD_FAB2(SCH_1):PAGE74_I20@CHPSET_LIB.SKX_EXT_B(CHIPS)':
 'VSS'<1134>: CDS_PINID='VSS(1134)';
NODE_NAME     U2D1 G8
 '@BASEBOARD_FAB2_LIB.BASEBOARD_FAB2(SCH_1):PAGE74_I20@CHPSET_LIB.SKX_EXT_B(CHIPS)':
 'VSS'<1135>: CDS_PINID='VSS(1135)';
NODE_NAME     U2D1 G4
 '@BASEBOARD_FAB2_LIB.BASEBOARD_FAB2(SCH_1):PAGE74_I20@CHPSET_LIB.SKX_EXT_B(CHIPS)':
 'VSS'<1136>: CDS_PINID='VSS(1136)';
NODE_NAME     U2D1 F69
 '@BASEBOARD_FAB2_LIB.BASEBOARD_FAB2(SCH_1):PAGE74_I20@CHPSET_LIB.SKX_EXT_B(CHIPS)':
 'VSS'<1137>: CDS_PINID='VSS(1137)';
NODE_NAME     U2D1 F67
 '@BASEBOARD_FAB2_LIB.BASEBOARD_FAB2(SCH_1):PAGE74_I20@CHPSET_LIB.SKX_EXT_B(CHIPS)':
 'VSS'<1138>: CDS_PINID='VSS(1138)';
NODE_NAME     U2D1 F43
 '@BASEBOARD_FAB2_LIB.BASEBOARD_FAB2(SCH_1):PAGE74_I20@CHPSET_LIB.SKX_EXT_B(CHIPS)':
 'VSS'<1139>: CDS_PINID='VSS(1139)';
NODE_NAME     U2D1 F37
 '@BASEBOARD_FAB2_LIB.BASEBOARD_FAB2(SCH_1):PAGE74_I20@CHPSET_LIB.SKX_EXT_B(CHIPS)':
 'VSS'<1140>: CDS_PINID='VSS(1140)';
NODE_NAME     U2D1 F31
 '@BASEBOARD_FAB2_LIB.BASEBOARD_FAB2(SCH_1):PAGE74_I20@CHPSET_LIB.SKX_EXT_B(CHIPS)':
 'VSS'<1141>: CDS_PINID='VSS(1141)';
NODE_NAME     U2D1 F25
 '@BASEBOARD_FAB2_LIB.BASEBOARD_FAB2(SCH_1):PAGE74_I20@CHPSET_LIB.SKX_EXT_B(CHIPS)':
 'VSS'<1142>: CDS_PINID='VSS(1142)';
NODE_NAME     U2D1 F19
 '@BASEBOARD_FAB2_LIB.BASEBOARD_FAB2(SCH_1):PAGE74_I20@CHPSET_LIB.SKX_EXT_B(CHIPS)':
 'VSS'<1143>: CDS_PINID='VSS(1143)';
NODE_NAME     U2D1 F17
 '@BASEBOARD_FAB2_LIB.BASEBOARD_FAB2(SCH_1):PAGE74_I20@CHPSET_LIB.SKX_EXT_B(CHIPS)':
 'VSS'<1144>: CDS_PINID='VSS(1144)';
NODE_NAME     U2D1 F5
 '@BASEBOARD_FAB2_LIB.BASEBOARD_FAB2(SCH_1):PAGE74_I20@CHPSET_LIB.SKX_EXT_B(CHIPS)':
 'VSS'<1145>: CDS_PINID='VSS(1145)';
NODE_NAME     U2D1 E76
 '@BASEBOARD_FAB2_LIB.BASEBOARD_FAB2(SCH_1):PAGE74_I20@CHPSET_LIB.SKX_EXT_B(CHIPS)':
 'VSS'<1146>: CDS_PINID='VSS(1146)';
NODE_NAME     U2D1 E74
 '@BASEBOARD_FAB2_LIB.BASEBOARD_FAB2(SCH_1):PAGE74_I20@CHPSET_LIB.SKX_EXT_B(CHIPS)':
 'VSS'<1147>: CDS_PINID='VSS(1147)';
NODE_NAME     U2D1 E72
 '@BASEBOARD_FAB2_LIB.BASEBOARD_FAB2(SCH_1):PAGE74_I20@CHPSET_LIB.SKX_EXT_B(CHIPS)':
 'VSS'<1148>: CDS_PINID='VSS(1148)';
NODE_NAME     U2D1 E22
 '@BASEBOARD_FAB2_LIB.BASEBOARD_FAB2(SCH_1):PAGE74_I20@CHPSET_LIB.SKX_EXT_B(CHIPS)':
 'VSS'<1149>: CDS_PINID='VSS(1149)';
NODE_NAME     U2D1 E20
 '@BASEBOARD_FAB2_LIB.BASEBOARD_FAB2(SCH_1):PAGE74_I20@CHPSET_LIB.SKX_EXT_B(CHIPS)':
 'VSS'<1150>: CDS_PINID='VSS(1150)';
NODE_NAME     U2D1 E18
 '@BASEBOARD_FAB2_LIB.BASEBOARD_FAB2(SCH_1):PAGE74_I20@CHPSET_LIB.SKX_EXT_B(CHIPS)':
 'VSS'<1151>: CDS_PINID='VSS(1151)';
NODE_NAME     U2D1 E16
 '@BASEBOARD_FAB2_LIB.BASEBOARD_FAB2(SCH_1):PAGE74_I20@CHPSET_LIB.SKX_EXT_B(CHIPS)':
 'VSS'<1152>: CDS_PINID='VSS(1152)';
NODE_NAME     U2D1 E8
 '@BASEBOARD_FAB2_LIB.BASEBOARD_FAB2(SCH_1):PAGE74_I20@CHPSET_LIB.SKX_EXT_B(CHIPS)':
 'VSS'<1153>: CDS_PINID='VSS(1153)';
NODE_NAME     U2D1 E6
 '@BASEBOARD_FAB2_LIB.BASEBOARD_FAB2(SCH_1):PAGE74_I20@CHPSET_LIB.SKX_EXT_B(CHIPS)':
 'VSS'<1154>: CDS_PINID='VSS(1154)';
NODE_NAME     U2D1 D77
 '@BASEBOARD_FAB2_LIB.BASEBOARD_FAB2(SCH_1):PAGE74_I20@CHPSET_LIB.SKX_EXT_B(CHIPS)':
 'VSS'<1155>: CDS_PINID='VSS(1155)';
NODE_NAME     U2D1 D43
 '@BASEBOARD_FAB2_LIB.BASEBOARD_FAB2(SCH_1):PAGE74_I20@CHPSET_LIB.SKX_EXT_B(CHIPS)':
 'VSS'<1156>: CDS_PINID='VSS(1156)';
NODE_NAME     U2D1 D41
 '@BASEBOARD_FAB2_LIB.BASEBOARD_FAB2(SCH_1):PAGE74_I20@CHPSET_LIB.SKX_EXT_B(CHIPS)':
 'VSS'<1157>: CDS_PINID='VSS(1157)';
NODE_NAME     U2D1 D39
 '@BASEBOARD_FAB2_LIB.BASEBOARD_FAB2(SCH_1):PAGE74_I20@CHPSET_LIB.SKX_EXT_B(CHIPS)':
 'VSS'<1158>: CDS_PINID='VSS(1158)';
NODE_NAME     U2D1 D37
 '@BASEBOARD_FAB2_LIB.BASEBOARD_FAB2(SCH_1):PAGE74_I20@CHPSET_LIB.SKX_EXT_B(CHIPS)':
 'VSS'<1159>: CDS_PINID='VSS(1159)';
NODE_NAME     U2D1 D35
 '@BASEBOARD_FAB2_LIB.BASEBOARD_FAB2(SCH_1):PAGE74_I20@CHPSET_LIB.SKX_EXT_B(CHIPS)':
 'VSS'<1160>: CDS_PINID='VSS(1160)';
NODE_NAME     U2D1 D33
 '@BASEBOARD_FAB2_LIB.BASEBOARD_FAB2(SCH_1):PAGE74_I20@CHPSET_LIB.SKX_EXT_B(CHIPS)':
 'VSS'<1161>: CDS_PINID='VSS(1161)';
NODE_NAME     U2D1 D31
 '@BASEBOARD_FAB2_LIB.BASEBOARD_FAB2(SCH_1):PAGE74_I20@CHPSET_LIB.SKX_EXT_B(CHIPS)':
 'VSS'<1162>: CDS_PINID='VSS(1162)';
NODE_NAME     U2D1 D29
 '@BASEBOARD_FAB2_LIB.BASEBOARD_FAB2(SCH_1):PAGE74_I20@CHPSET_LIB.SKX_EXT_B(CHIPS)':
 'VSS'<1163>: CDS_PINID='VSS(1163)';
NODE_NAME     U2D1 D27
 '@BASEBOARD_FAB2_LIB.BASEBOARD_FAB2(SCH_1):PAGE74_I20@CHPSET_LIB.SKX_EXT_B(CHIPS)':
 'VSS'<1164>: CDS_PINID='VSS(1164)';
NODE_NAME     U2D1 D25
 '@BASEBOARD_FAB2_LIB.BASEBOARD_FAB2(SCH_1):PAGE74_I20@CHPSET_LIB.SKX_EXT_B(CHIPS)':
 'VSS'<1165>: CDS_PINID='VSS(1165)';
NODE_NAME     U2D1 D13
 '@BASEBOARD_FAB2_LIB.BASEBOARD_FAB2(SCH_1):PAGE74_I20@CHPSET_LIB.SKX_EXT_B(CHIPS)':
 'VSS'<1166>: CDS_PINID='VSS(1166)';
NODE_NAME     U2D1 D11
 '@BASEBOARD_FAB2_LIB.BASEBOARD_FAB2(SCH_1):PAGE74_I20@CHPSET_LIB.SKX_EXT_B(CHIPS)':
 'VSS'<1167>: CDS_PINID='VSS(1167)';
NODE_NAME     U2D1 CM27
 '@BASEBOARD_FAB2_LIB.BASEBOARD_FAB2(SCH_1):PAGE74_I20@CHPSET_LIB.SKX_EXT_B(CHIPS)':
 'VSS'<1168>: CDS_PINID='VSS(1168)';
NODE_NAME     U2D1 C78
 '@BASEBOARD_FAB2_LIB.BASEBOARD_FAB2(SCH_1):PAGE74_I20@CHPSET_LIB.SKX_EXT_B(CHIPS)':
 'VSS'<1169>: CDS_PINID='VSS(1169)';
NODE_NAME     U2D1 C76
 '@BASEBOARD_FAB2_LIB.BASEBOARD_FAB2(SCH_1):PAGE74_I20@CHPSET_LIB.SKX_EXT_B(CHIPS)':
 'VSS'<1170>: CDS_PINID='VSS(1170)';
NODE_NAME     U2D1 C16
 '@BASEBOARD_FAB2_LIB.BASEBOARD_FAB2(SCH_1):PAGE74_I20@CHPSET_LIB.SKX_EXT_B(CHIPS)':
 'VSS'<1171>: CDS_PINID='VSS(1171)';
NODE_NAME     U2D1 C14
 '@BASEBOARD_FAB2_LIB.BASEBOARD_FAB2(SCH_1):PAGE74_I20@CHPSET_LIB.SKX_EXT_B(CHIPS)':
 'VSS'<1172>: CDS_PINID='VSS(1172)';
NODE_NAME     U2D1 C12
 '@BASEBOARD_FAB2_LIB.BASEBOARD_FAB2(SCH_1):PAGE74_I20@CHPSET_LIB.SKX_EXT_B(CHIPS)':
 'VSS'<1173>: CDS_PINID='VSS(1173)';
NODE_NAME     U2D1 C10
 '@BASEBOARD_FAB2_LIB.BASEBOARD_FAB2(SCH_1):PAGE74_I20@CHPSET_LIB.SKX_EXT_B(CHIPS)':
 'VSS'<1174>: CDS_PINID='VSS(1174)';
NODE_NAME     U2D1 C8
 '@BASEBOARD_FAB2_LIB.BASEBOARD_FAB2(SCH_1):PAGE74_I20@CHPSET_LIB.SKX_EXT_B(CHIPS)':
 'VSS'<1175>: CDS_PINID='VSS(1175)';
NODE_NAME     U2D1 B75
 '@BASEBOARD_FAB2_LIB.BASEBOARD_FAB2(SCH_1):PAGE74_I20@CHPSET_LIB.SKX_EXT_B(CHIPS)':
 'VSS'<1176>: CDS_PINID='VSS(1176)';
NODE_NAME     U2D1 B71
 '@BASEBOARD_FAB2_LIB.BASEBOARD_FAB2(SCH_1):PAGE74_I20@CHPSET_LIB.SKX_EXT_B(CHIPS)':
 'VSS'<1177>: CDS_PINID='VSS(1177)';
NODE_NAME     U2D1 B37
 '@BASEBOARD_FAB2_LIB.BASEBOARD_FAB2(SCH_1):PAGE74_I20@CHPSET_LIB.SKX_EXT_B(CHIPS)':
 'VSS'<1178>: CDS_PINID='VSS(1178)';
NODE_NAME     U2D1 B31
 '@BASEBOARD_FAB2_LIB.BASEBOARD_FAB2(SCH_1):PAGE74_I20@CHPSET_LIB.SKX_EXT_B(CHIPS)':
 'VSS'<1179>: CDS_PINID='VSS(1179)';
NODE_NAME     U2D1 B25
 '@BASEBOARD_FAB2_LIB.BASEBOARD_FAB2(SCH_1):PAGE74_I20@CHPSET_LIB.SKX_EXT_B(CHIPS)':
 'VSS'<1180>: CDS_PINID='VSS(1180)';
NODE_NAME     U2D1 A38
 '@BASEBOARD_FAB2_LIB.BASEBOARD_FAB2(SCH_1):PAGE74_I20@CHPSET_LIB.SKX_EXT_B(CHIPS)':
 'VSS'<1181>: CDS_PINID='VSS(1181)';
NODE_NAME     U2D1 A36
 '@BASEBOARD_FAB2_LIB.BASEBOARD_FAB2(SCH_1):PAGE74_I20@CHPSET_LIB.SKX_EXT_B(CHIPS)':
 'VSS'<1182>: CDS_PINID='VSS(1182)';
NODE_NAME     U2D1 A32
 '@BASEBOARD_FAB2_LIB.BASEBOARD_FAB2(SCH_1):PAGE74_I20@CHPSET_LIB.SKX_EXT_B(CHIPS)':
 'VSS'<1183>: CDS_PINID='VSS(1183)';
NODE_NAME     U2D1 A30
 '@BASEBOARD_FAB2_LIB.BASEBOARD_FAB2(SCH_1):PAGE74_I20@CHPSET_LIB.SKX_EXT_B(CHIPS)':
 'VSS'<1184>: CDS_PINID='VSS(1184)';
NODE_NAME     U2D1 A26
 '@BASEBOARD_FAB2_LIB.BASEBOARD_FAB2(SCH_1):PAGE74_I20@CHPSET_LIB.SKX_EXT_B(CHIPS)':
 'VSS'<1185>: CDS_PINID='VSS(1185)';
NODE_NAME     U2D1 AC58
 '@BASEBOARD_FAB2_LIB.BASEBOARD_FAB2(SCH_1):PAGE74_I20@CHPSET_LIB.SKX_EXT_B(CHIPS)':
 'VSS'<1186>: CDS_PINID='VSS(1186)';
NODE_NAME     U2D1 AC60
 '@BASEBOARD_FAB2_LIB.BASEBOARD_FAB2(SCH_1):PAGE74_I20@CHPSET_LIB.SKX_EXT_B(CHIPS)':
 'VSS'<1187>: CDS_PINID='VSS(1187)';
NODE_NAME     U2D1 AC62
 '@BASEBOARD_FAB2_LIB.BASEBOARD_FAB2(SCH_1):PAGE74_I20@CHPSET_LIB.SKX_EXT_B(CHIPS)':
 'VSS'<1188>: CDS_PINID='VSS(1188)';
NODE_NAME     U2D1 AJ4
 '@BASEBOARD_FAB2_LIB.BASEBOARD_FAB2(SCH_1):PAGE74_I20@CHPSET_LIB.SKX_EXT_B(CHIPS)':
 'VSS'<1189>: CDS_PINID='VSS(1189)';
NODE_NAME     U2D1 AR6
 '@BASEBOARD_FAB2_LIB.BASEBOARD_FAB2(SCH_1):PAGE74_I20@CHPSET_LIB.SKX_EXT_B(CHIPS)':
 'VSS'<1190>: CDS_PINID='VSS(1190)';
NODE_NAME     U2D1 CG6
 '@BASEBOARD_FAB2_LIB.BASEBOARD_FAB2(SCH_1):PAGE74_I20@CHPSET_LIB.SKX_EXT_B(CHIPS)':
 'VSS'<1191>: CDS_PINID='VSS(1191)';
NODE_NAME     U2D1 CW6
 '@BASEBOARD_FAB2_LIB.BASEBOARD_FAB2(SCH_1):PAGE74_I20@CHPSET_LIB.SKX_EXT_B(CHIPS)':
 'VSS'<1192>: CDS_PINID='VSS(1192)';
NODE_NAME     U2D1 DE48
 '@BASEBOARD_FAB2_LIB.BASEBOARD_FAB2(SCH_1):PAGE74_I20@CHPSET_LIB.SKX_EXT_B(CHIPS)':
 'VSS'<1193>: CDS_PINID='VSS(1193)';
NODE_NAME     U2D1 DE50
 '@BASEBOARD_FAB2_LIB.BASEBOARD_FAB2(SCH_1):PAGE74_I20@CHPSET_LIB.SKX_EXT_B(CHIPS)':
 'VSS'<1194>: CDS_PINID='VSS(1194)';
NODE_NAME     U2D1 DE52
 '@BASEBOARD_FAB2_LIB.BASEBOARD_FAB2(SCH_1):PAGE74_I20@CHPSET_LIB.SKX_EXT_B(CHIPS)':
 'VSS'<1195>: CDS_PINID='VSS(1195)';
NODE_NAME     U2D1 DE54
 '@BASEBOARD_FAB2_LIB.BASEBOARD_FAB2(SCH_1):PAGE74_I20@CHPSET_LIB.SKX_EXT_B(CHIPS)':
 'VSS'<1196>: CDS_PINID='VSS(1196)';
NODE_NAME     U2D1 DE56
 '@BASEBOARD_FAB2_LIB.BASEBOARD_FAB2(SCH_1):PAGE74_I20@CHPSET_LIB.SKX_EXT_B(CHIPS)':
 'VSS'<1197>: CDS_PINID='VSS(1197)';
NODE_NAME     U2D1 DE58
 '@BASEBOARD_FAB2_LIB.BASEBOARD_FAB2(SCH_1):PAGE74_I20@CHPSET_LIB.SKX_EXT_B(CHIPS)':
 'VSS'<1198>: CDS_PINID='VSS(1198)';
NODE_NAME     U2D1 DE60
 '@BASEBOARD_FAB2_LIB.BASEBOARD_FAB2(SCH_1):PAGE74_I20@CHPSET_LIB.SKX_EXT_B(CHIPS)':
 'VSS'<1199>: CDS_PINID='VSS(1199)';
NODE_NAME     U2D1 DE62
 '@BASEBOARD_FAB2_LIB.BASEBOARD_FAB2(SCH_1):PAGE74_I20@CHPSET_LIB.SKX_EXT_B(CHIPS)':
 'VSS'<1200>: CDS_PINID='VSS(1200)';
NODE_NAME     U2D1 DL8
 '@BASEBOARD_FAB2_LIB.BASEBOARD_FAB2(SCH_1):PAGE74_I20@CHPSET_LIB.SKX_EXT_B(CHIPS)':
 'VSS'<1201>: CDS_PINID='VSS(1201)';
NODE_NAME     U2D1 DN18
 '@BASEBOARD_FAB2_LIB.BASEBOARD_FAB2(SCH_1):PAGE74_I20@CHPSET_LIB.SKX_EXT_B(CHIPS)':
 'VSS'<1202>: CDS_PINID='VSS(1202)';
NODE_NAME     U2D1 DP45
 '@BASEBOARD_FAB2_LIB.BASEBOARD_FAB2(SCH_1):PAGE74_I20@CHPSET_LIB.SKX_EXT_B(CHIPS)':
 'VSS'<1203>: CDS_PINID='VSS(1203)';
NODE_NAME     U2D1 DP47
 '@BASEBOARD_FAB2_LIB.BASEBOARD_FAB2(SCH_1):PAGE74_I20@CHPSET_LIB.SKX_EXT_B(CHIPS)':
 'VSS'<1204>: CDS_PINID='VSS(1204)';
NODE_NAME     U2D1 DP49
 '@BASEBOARD_FAB2_LIB.BASEBOARD_FAB2(SCH_1):PAGE74_I20@CHPSET_LIB.SKX_EXT_B(CHIPS)':
 'VSS'<1205>: CDS_PINID='VSS(1205)';
NODE_NAME     U2D1 DP51
 '@BASEBOARD_FAB2_LIB.BASEBOARD_FAB2(SCH_1):PAGE74_I20@CHPSET_LIB.SKX_EXT_B(CHIPS)':
 'VSS'<1206>: CDS_PINID='VSS(1206)';
NODE_NAME     U2D1 DP53
 '@BASEBOARD_FAB2_LIB.BASEBOARD_FAB2(SCH_1):PAGE74_I20@CHPSET_LIB.SKX_EXT_B(CHIPS)':
 'VSS'<1207>: CDS_PINID='VSS(1207)';
NODE_NAME     U2D1 DP55
 '@BASEBOARD_FAB2_LIB.BASEBOARD_FAB2(SCH_1):PAGE74_I20@CHPSET_LIB.SKX_EXT_B(CHIPS)':
 'VSS'<1208>: CDS_PINID='VSS(1208)';
NODE_NAME     U2D1 DP57
 '@BASEBOARD_FAB2_LIB.BASEBOARD_FAB2(SCH_1):PAGE74_I20@CHPSET_LIB.SKX_EXT_B(CHIPS)':
 'VSS'<1209>: CDS_PINID='VSS(1209)';
NODE_NAME     U2D1 DP59
 '@BASEBOARD_FAB2_LIB.BASEBOARD_FAB2(SCH_1):PAGE74_I20@CHPSET_LIB.SKX_EXT_B(CHIPS)':
 'VSS'<1210>: CDS_PINID='VSS(1210)';
NODE_NAME     U2D1 DP61
 '@BASEBOARD_FAB2_LIB.BASEBOARD_FAB2(SCH_1):PAGE74_I20@CHPSET_LIB.SKX_EXT_B(CHIPS)':
 'VSS'<1211>: CDS_PINID='VSS(1211)';
NODE_NAME     U2D1 DP63
 '@BASEBOARD_FAB2_LIB.BASEBOARD_FAB2(SCH_1):PAGE74_I20@CHPSET_LIB.SKX_EXT_B(CHIPS)':
 'VSS'<1212>: CDS_PINID='VSS(1212)';
NODE_NAME     U2D1 DP9
 '@BASEBOARD_FAB2_LIB.BASEBOARD_FAB2(SCH_1):PAGE74_I20@CHPSET_LIB.SKX_EXT_B(CHIPS)':
 'VSS'<1213>: CDS_PINID='VSS(1213)';
NODE_NAME     U2D1 DV19
 '@BASEBOARD_FAB2_LIB.BASEBOARD_FAB2(SCH_1):PAGE74_I20@CHPSET_LIB.SKX_EXT_B(CHIPS)':
 'VSS'<1214>: CDS_PINID='VSS(1214)';
NODE_NAME     U2D1 DY45
 '@BASEBOARD_FAB2_LIB.BASEBOARD_FAB2(SCH_1):PAGE74_I20@CHPSET_LIB.SKX_EXT_B(CHIPS)':
 'VSS'<1215>: CDS_PINID='VSS(1215)';
NODE_NAME     U2D1 DY47
 '@BASEBOARD_FAB2_LIB.BASEBOARD_FAB2(SCH_1):PAGE74_I20@CHPSET_LIB.SKX_EXT_B(CHIPS)':
 'VSS'<1216>: CDS_PINID='VSS(1216)';
NODE_NAME     U2D1 DY49
 '@BASEBOARD_FAB2_LIB.BASEBOARD_FAB2(SCH_1):PAGE74_I20@CHPSET_LIB.SKX_EXT_B(CHIPS)':
 'VSS'<1217>: CDS_PINID='VSS(1217)';
NODE_NAME     U2D1 DY51
 '@BASEBOARD_FAB2_LIB.BASEBOARD_FAB2(SCH_1):PAGE74_I20@CHPSET_LIB.SKX_EXT_B(CHIPS)':
 'VSS'<1218>: CDS_PINID='VSS(1218)';
NODE_NAME     U2D1 DY53
 '@BASEBOARD_FAB2_LIB.BASEBOARD_FAB2(SCH_1):PAGE74_I20@CHPSET_LIB.SKX_EXT_B(CHIPS)':
 'VSS'<1219>: CDS_PINID='VSS(1219)';
NODE_NAME     U2D1 DY55
 '@BASEBOARD_FAB2_LIB.BASEBOARD_FAB2(SCH_1):PAGE74_I20@CHPSET_LIB.SKX_EXT_B(CHIPS)':
 'VSS'<1220>: CDS_PINID='VSS(1220)';
NODE_NAME     U2D1 DY57
 '@BASEBOARD_FAB2_LIB.BASEBOARD_FAB2(SCH_1):PAGE74_I20@CHPSET_LIB.SKX_EXT_B(CHIPS)':
 'VSS'<1221>: CDS_PINID='VSS(1221)';
NODE_NAME     U2D1 DY59
 '@BASEBOARD_FAB2_LIB.BASEBOARD_FAB2(SCH_1):PAGE74_I20@CHPSET_LIB.SKX_EXT_B(CHIPS)':
 'VSS'<1222>: CDS_PINID='VSS(1222)';
NODE_NAME     U2D1 DY61
 '@BASEBOARD_FAB2_LIB.BASEBOARD_FAB2(SCH_1):PAGE74_I20@CHPSET_LIB.SKX_EXT_B(CHIPS)':
 'VSS'<1223>: CDS_PINID='VSS(1223)';
NODE_NAME     U2D1 DY63
 '@BASEBOARD_FAB2_LIB.BASEBOARD_FAB2(SCH_1):PAGE74_I20@CHPSET_LIB.SKX_EXT_B(CHIPS)':
 'VSS'<1224>: CDS_PINID='VSS(1224)';
NODE_NAME     U2D1 EA14
 '@BASEBOARD_FAB2_LIB.BASEBOARD_FAB2(SCH_1):PAGE74_I20@CHPSET_LIB.SKX_EXT_B(CHIPS)':
 'VSS'<1225>: CDS_PINID='VSS(1225)';
NODE_NAME     U2D1 L8
 '@BASEBOARD_FAB2_LIB.BASEBOARD_FAB2(SCH_1):PAGE74_I20@CHPSET_LIB.SKX_EXT_B(CHIPS)':
 'VSS'<1226>: CDS_PINID='VSS(1226)';
NODE_NAME     U2D1 V11
 '@BASEBOARD_FAB2_LIB.BASEBOARD_FAB2(SCH_1):PAGE74_I20@CHPSET_LIB.SKX_EXT_B(CHIPS)':
 'VSS'<1227>: CDS_PINID='VSS(1227)';
NODE_NAME     U2D1 E66
 '@BASEBOARD_FAB2_LIB.BASEBOARD_FAB2(SCH_1):PAGE74_I20@CHPSET_LIB.SKX_EXT_B(CHIPS)':
 'VSS'<1228>: CDS_PINID='VSS(1228)';
NODE_NAME     U2D1 ED69
 '@BASEBOARD_FAB2_LIB.BASEBOARD_FAB2(SCH_1):PAGE74_I20@CHPSET_LIB.SKX_EXT_B(CHIPS)':
 'VSS'<1229>: CDS_PINID='VSS(1229)';
NODE_NAME     U2D1 EE80
 '@BASEBOARD_FAB2_LIB.BASEBOARD_FAB2(SCH_1):PAGE74_I20@CHPSET_LIB.SKX_EXT_B(CHIPS)':
 'VSS'<1230>: CDS_PINID='VSS(1230)';
NODE_NAME     U2D1 EE8
 '@BASEBOARD_FAB2_LIB.BASEBOARD_FAB2(SCH_1):PAGE74_I20@CHPSET_LIB.SKX_EXT_B(CHIPS)':
 'VSS'<1231>: CDS_PINID='VSS(1231)';
NODE_NAME     U2D1 EE40
 '@BASEBOARD_FAB2_LIB.BASEBOARD_FAB2(SCH_1):PAGE74_I20@CHPSET_LIB.SKX_EXT_B(CHIPS)':
 'VSS'<1232>: CDS_PINID='VSS(1232)';
NODE_NAME     U2D1 ED81
 '@BASEBOARD_FAB2_LIB.BASEBOARD_FAB2(SCH_1):PAGE74_I20@CHPSET_LIB.SKX_EXT_B(CHIPS)':
 'VSS'<1233>: CDS_PINID='VSS(1233)';
NODE_NAME     U2D1 ED7
 '@BASEBOARD_FAB2_LIB.BASEBOARD_FAB2(SCH_1):PAGE74_I20@CHPSET_LIB.SKX_EXT_B(CHIPS)':
 'VSS'<1234>: CDS_PINID='VSS(1234)';
NODE_NAME     U2D1 ED41
 '@BASEBOARD_FAB2_LIB.BASEBOARD_FAB2(SCH_1):PAGE74_I20@CHPSET_LIB.SKX_EXT_B(CHIPS)':
 'VSS'<1235>: CDS_PINID='VSS(1235)';
NODE_NAME     U2D1 EC82
 '@BASEBOARD_FAB2_LIB.BASEBOARD_FAB2(SCH_1):PAGE74_I20@CHPSET_LIB.SKX_EXT_B(CHIPS)':
 'VSS'<1236>: CDS_PINID='VSS(1236)';
NODE_NAME     U2D1 EC6
 '@BASEBOARD_FAB2_LIB.BASEBOARD_FAB2(SCH_1):PAGE74_I20@CHPSET_LIB.SKX_EXT_B(CHIPS)':
 'VSS'<1237>: CDS_PINID='VSS(1237)';
NODE_NAME     U2D1 EC42
 '@BASEBOARD_FAB2_LIB.BASEBOARD_FAB2(SCH_1):PAGE74_I20@CHPSET_LIB.SKX_EXT_B(CHIPS)':
 'VSS'<1238>: CDS_PINID='VSS(1238)';
NODE_NAME     U2D1 DW2
 '@BASEBOARD_FAB2_LIB.BASEBOARD_FAB2(SCH_1):PAGE74_I20@CHPSET_LIB.SKX_EXT_B(CHIPS)':
 'VSS'<1239>: CDS_PINID='VSS(1239)';
NODE_NAME     U2D1 EB83
 '@BASEBOARD_FAB2_LIB.BASEBOARD_FAB2(SCH_1):PAGE74_I20@CHPSET_LIB.SKX_EXT_B(CHIPS)':
 'VSS'<1240>: CDS_PINID='VSS(1240)';
NODE_NAME     U2D1 EA84
 '@BASEBOARD_FAB2_LIB.BASEBOARD_FAB2(SCH_1):PAGE74_I20@CHPSET_LIB.SKX_EXT_B(CHIPS)':
 'VSS'<1241>: CDS_PINID='VSS(1241)';
NODE_NAME     U2D1 DY85
 '@BASEBOARD_FAB2_LIB.BASEBOARD_FAB2(SCH_1):PAGE74_I20@CHPSET_LIB.SKX_EXT_B(CHIPS)':
 'VSS'<1242>: CDS_PINID='VSS(1242)';
NODE_NAME     U2D1 J86
 '@BASEBOARD_FAB2_LIB.BASEBOARD_FAB2(SCH_1):PAGE74_I20@CHPSET_LIB.SKX_EXT_B(CHIPS)':
 'VSS'<1243>: CDS_PINID='VSS(1243)';
NODE_NAME     U2D1 E82
 '@BASEBOARD_FAB2_LIB.BASEBOARD_FAB2(SCH_1):PAGE74_I20@CHPSET_LIB.SKX_EXT_B(CHIPS)':
 'VSS'<1244>: CDS_PINID='VSS(1244)';
NODE_NAME     U2D1 D81
 '@BASEBOARD_FAB2_LIB.BASEBOARD_FAB2(SCH_1):PAGE74_I20@CHPSET_LIB.SKX_EXT_B(CHIPS)':
 'VSS'<1245>: CDS_PINID='VSS(1245)';
NODE_NAME     U2D1 D3
 '@BASEBOARD_FAB2_LIB.BASEBOARD_FAB2(SCH_1):PAGE74_I20@CHPSET_LIB.SKX_EXT_B(CHIPS)':
 'VSS'<1246>: CDS_PINID='VSS(1246)';
NODE_NAME     U2D1 C80
 '@BASEBOARD_FAB2_LIB.BASEBOARD_FAB2(SCH_1):PAGE74_I20@CHPSET_LIB.SKX_EXT_B(CHIPS)':
 'VSS'<1247>: CDS_PINID='VSS(1247)';
NODE_NAME     U2D1 C4
 '@BASEBOARD_FAB2_LIB.BASEBOARD_FAB2(SCH_1):PAGE74_I20@CHPSET_LIB.SKX_EXT_B(CHIPS)':
 'VSS'<1248>: CDS_PINID='VSS(1248)';
NODE_NAME     U2D1 B79
 '@BASEBOARD_FAB2_LIB.BASEBOARD_FAB2(SCH_1):PAGE74_I20@CHPSET_LIB.SKX_EXT_B(CHIPS)':
 'VSS'<1249>: CDS_PINID='VSS(1249)';
NODE_NAME     U2D1 B5
 '@BASEBOARD_FAB2_LIB.BASEBOARD_FAB2(SCH_1):PAGE74_I20@CHPSET_LIB.SKX_EXT_B(CHIPS)':
 'VSS'<1250>: CDS_PINID='VSS(1250)';
NODE_NAME     U2D1 B43
 '@BASEBOARD_FAB2_LIB.BASEBOARD_FAB2(SCH_1):PAGE74_I20@CHPSET_LIB.SKX_EXT_B(CHIPS)':
 'VSS'<1251>: CDS_PINID='VSS(1251)';
NODE_NAME     U2D1 A42
 '@BASEBOARD_FAB2_LIB.BASEBOARD_FAB2(SCH_1):PAGE74_I20@CHPSET_LIB.SKX_EXT_B(CHIPS)':
 'VSS'<1252>: CDS_PINID='VSS(1252)';
NODE_NAME     U2D1 B9
 '@BASEBOARD_FAB2_LIB.BASEBOARD_FAB2(SCH_1):PAGE74_I20@CHPSET_LIB.SKX_EXT_B(CHIPS)':
 'VSS'<1253>: CDS_PINID='VSS(1253)';
NODE_NAME     U2D1 AA16
 '@BASEBOARD_FAB2_LIB.BASEBOARD_FAB2(SCH_1):PAGE74_I21@CHPSET_LIB.SKX_EXT_B(CHIPS)':
 'VSS'<934>: CDS_PINID='VSS(934)';
NODE_NAME     U2D1 AA4
 '@BASEBOARD_FAB2_LIB.BASEBOARD_FAB2(SCH_1):PAGE74_I21@CHPSET_LIB.SKX_EXT_B(CHIPS)':
 'VSS'<935>: CDS_PINID='VSS(935)';
NODE_NAME     U2D1 Y85
 '@BASEBOARD_FAB2_LIB.BASEBOARD_FAB2(SCH_1):PAGE74_I21@CHPSET_LIB.SKX_EXT_B(CHIPS)':
 'VSS'<936>: CDS_PINID='VSS(936)';
NODE_NAME     U2D1 Y83
 '@BASEBOARD_FAB2_LIB.BASEBOARD_FAB2(SCH_1):PAGE74_I21@CHPSET_LIB.SKX_EXT_B(CHIPS)':
 'VSS'<937>: CDS_PINID='VSS(937)';
NODE_NAME     U2D1 Y81
 '@BASEBOARD_FAB2_LIB.BASEBOARD_FAB2(SCH_1):PAGE74_I21@CHPSET_LIB.SKX_EXT_B(CHIPS)':
 'VSS'<938>: CDS_PINID='VSS(938)';
NODE_NAME     U2D1 Y79
 '@BASEBOARD_FAB2_LIB.BASEBOARD_FAB2(SCH_1):PAGE74_I21@CHPSET_LIB.SKX_EXT_B(CHIPS)':
 'VSS'<939>: CDS_PINID='VSS(939)';
NODE_NAME     U2D1 Y73
 '@BASEBOARD_FAB2_LIB.BASEBOARD_FAB2(SCH_1):PAGE74_I21@CHPSET_LIB.SKX_EXT_B(CHIPS)':
 'VSS'<940>: CDS_PINID='VSS(940)';
NODE_NAME     U2D1 Y71
 '@BASEBOARD_FAB2_LIB.BASEBOARD_FAB2(SCH_1):PAGE74_I21@CHPSET_LIB.SKX_EXT_B(CHIPS)':
 'VSS'<941>: CDS_PINID='VSS(941)';
NODE_NAME     U2D1 Y9
 '@BASEBOARD_FAB2_LIB.BASEBOARD_FAB2(SCH_1):PAGE74_I21@CHPSET_LIB.SKX_EXT_B(CHIPS)':
 'VSS'<942>: CDS_PINID='VSS(942)';
NODE_NAME     U2D1 Y7
 '@BASEBOARD_FAB2_LIB.BASEBOARD_FAB2(SCH_1):PAGE74_I21@CHPSET_LIB.SKX_EXT_B(CHIPS)':
 'VSS'<943>: CDS_PINID='VSS(943)';
NODE_NAME     U2D1 Y67
 '@BASEBOARD_FAB2_LIB.BASEBOARD_FAB2(SCH_1):PAGE74_I21@CHPSET_LIB.SKX_EXT_B(CHIPS)':
 'VSS'<944>: CDS_PINID='VSS(944)';
NODE_NAME     U2D1 Y5
 '@BASEBOARD_FAB2_LIB.BASEBOARD_FAB2(SCH_1):PAGE74_I21@CHPSET_LIB.SKX_EXT_B(CHIPS)':
 'VSS'<945>: CDS_PINID='VSS(945)';
NODE_NAME     U2D1 Y17
 '@BASEBOARD_FAB2_LIB.BASEBOARD_FAB2(SCH_1):PAGE74_I21@CHPSET_LIB.SKX_EXT_B(CHIPS)':
 'VSS'<946>: CDS_PINID='VSS(946)';
NODE_NAME     U2D1 Y15
 '@BASEBOARD_FAB2_LIB.BASEBOARD_FAB2(SCH_1):PAGE74_I21@CHPSET_LIB.SKX_EXT_B(CHIPS)':
 'VSS'<947>: CDS_PINID='VSS(947)';
NODE_NAME     U2D1 W82
 '@BASEBOARD_FAB2_LIB.BASEBOARD_FAB2(SCH_1):PAGE74_I21@CHPSET_LIB.SKX_EXT_B(CHIPS)':
 'VSS'<948>: CDS_PINID='VSS(948)';
NODE_NAME     U2D1 W78
 '@BASEBOARD_FAB2_LIB.BASEBOARD_FAB2(SCH_1):PAGE74_I21@CHPSET_LIB.SKX_EXT_B(CHIPS)':
 'VSS'<949>: CDS_PINID='VSS(949)';
NODE_NAME     U2D1 W74
 '@BASEBOARD_FAB2_LIB.BASEBOARD_FAB2(SCH_1):PAGE74_I21@CHPSET_LIB.SKX_EXT_B(CHIPS)':
 'VSS'<950>: CDS_PINID='VSS(950)';
NODE_NAME     U2D1 W68
 '@BASEBOARD_FAB2_LIB.BASEBOARD_FAB2(SCH_1):PAGE74_I21@CHPSET_LIB.SKX_EXT_B(CHIPS)':
 'VSS'<951>: CDS_PINID='VSS(951)';
NODE_NAME     U2D1 W42
 '@BASEBOARD_FAB2_LIB.BASEBOARD_FAB2(SCH_1):PAGE74_I21@CHPSET_LIB.SKX_EXT_B(CHIPS)':
 'VSS'<952>: CDS_PINID='VSS(952)';
NODE_NAME     U2D1 W40
 '@BASEBOARD_FAB2_LIB.BASEBOARD_FAB2(SCH_1):PAGE74_I21@CHPSET_LIB.SKX_EXT_B(CHIPS)':
 'VSS'<953>: CDS_PINID='VSS(953)';
NODE_NAME     U2D1 W38
 '@BASEBOARD_FAB2_LIB.BASEBOARD_FAB2(SCH_1):PAGE74_I21@CHPSET_LIB.SKX_EXT_B(CHIPS)':
 'VSS'<954>: CDS_PINID='VSS(954)';
NODE_NAME     U2D1 W36
 '@BASEBOARD_FAB2_LIB.BASEBOARD_FAB2(SCH_1):PAGE74_I21@CHPSET_LIB.SKX_EXT_B(CHIPS)':
 'VSS'<955>: CDS_PINID='VSS(955)';
NODE_NAME     U2D1 W34
 '@BASEBOARD_FAB2_LIB.BASEBOARD_FAB2(SCH_1):PAGE74_I21@CHPSET_LIB.SKX_EXT_B(CHIPS)':
 'VSS'<956>: CDS_PINID='VSS(956)';
NODE_NAME     U2D1 W32
 '@BASEBOARD_FAB2_LIB.BASEBOARD_FAB2(SCH_1):PAGE74_I21@CHPSET_LIB.SKX_EXT_B(CHIPS)':
 'VSS'<957>: CDS_PINID='VSS(957)';
NODE_NAME     U2D1 W30
 '@BASEBOARD_FAB2_LIB.BASEBOARD_FAB2(SCH_1):PAGE74_I21@CHPSET_LIB.SKX_EXT_B(CHIPS)':
 'VSS'<958>: CDS_PINID='VSS(958)';
NODE_NAME     U2D1 W28
 '@BASEBOARD_FAB2_LIB.BASEBOARD_FAB2(SCH_1):PAGE74_I21@CHPSET_LIB.SKX_EXT_B(CHIPS)':
 'VSS'<959>: CDS_PINID='VSS(959)';
NODE_NAME     U2D1 W26
 '@BASEBOARD_FAB2_LIB.BASEBOARD_FAB2(SCH_1):PAGE74_I21@CHPSET_LIB.SKX_EXT_B(CHIPS)':
 'VSS'<960>: CDS_PINID='VSS(960)';
NODE_NAME     U2D1 W24
 '@BASEBOARD_FAB2_LIB.BASEBOARD_FAB2(SCH_1):PAGE74_I21@CHPSET_LIB.SKX_EXT_B(CHIPS)':
 'VSS'<961>: CDS_PINID='VSS(961)';
NODE_NAME     U2D1 W22
 '@BASEBOARD_FAB2_LIB.BASEBOARD_FAB2(SCH_1):PAGE74_I21@CHPSET_LIB.SKX_EXT_B(CHIPS)':
 'VSS'<962>: CDS_PINID='VSS(962)';
NODE_NAME     U2D1 W12
 '@BASEBOARD_FAB2_LIB.BASEBOARD_FAB2(SCH_1):PAGE74_I21@CHPSET_LIB.SKX_EXT_B(CHIPS)':
 'VSS'<963>: CDS_PINID='VSS(963)';
NODE_NAME     U2D1 AC56
 '@BASEBOARD_FAB2_LIB.BASEBOARD_FAB2(SCH_1):PAGE74_I21@CHPSET_LIB.SKX_EXT_B(CHIPS)':
 'VSS'<964>: CDS_PINID='VSS(964)';
NODE_NAME     U2D1 W8
 '@BASEBOARD_FAB2_LIB.BASEBOARD_FAB2(SCH_1):PAGE74_I21@CHPSET_LIB.SKX_EXT_B(CHIPS)':
 'VSS'<965>: CDS_PINID='VSS(965)';
NODE_NAME     U2D1 V83
 '@BASEBOARD_FAB2_LIB.BASEBOARD_FAB2(SCH_1):PAGE74_I21@CHPSET_LIB.SKX_EXT_B(CHIPS)':
 'VSS'<966>: CDS_PINID='VSS(966)';
NODE_NAME     U2D1 V77
 '@BASEBOARD_FAB2_LIB.BASEBOARD_FAB2(SCH_1):PAGE74_I21@CHPSET_LIB.SKX_EXT_B(CHIPS)':
 'VSS'<967>: CDS_PINID='VSS(967)';
NODE_NAME     U2D1 V75
 '@BASEBOARD_FAB2_LIB.BASEBOARD_FAB2(SCH_1):PAGE74_I21@CHPSET_LIB.SKX_EXT_B(CHIPS)':
 'VSS'<968>: CDS_PINID='VSS(968)';
NODE_NAME     U2D1 V73
 '@BASEBOARD_FAB2_LIB.BASEBOARD_FAB2(SCH_1):PAGE74_I21@CHPSET_LIB.SKX_EXT_B(CHIPS)':
 'VSS'<969>: CDS_PINID='VSS(969)';
NODE_NAME     U2D1 V43
 '@BASEBOARD_FAB2_LIB.BASEBOARD_FAB2(SCH_1):PAGE74_I21@CHPSET_LIB.SKX_EXT_B(CHIPS)':
 'VSS'<970>: CDS_PINID='VSS(970)';
NODE_NAME     U2D1 V23
 '@BASEBOARD_FAB2_LIB.BASEBOARD_FAB2(SCH_1):PAGE74_I21@CHPSET_LIB.SKX_EXT_B(CHIPS)':
 'VSS'<971>: CDS_PINID='VSS(971)';
NODE_NAME     U2D1 V21
 '@BASEBOARD_FAB2_LIB.BASEBOARD_FAB2(SCH_1):PAGE74_I21@CHPSET_LIB.SKX_EXT_B(CHIPS)':
 'VSS'<972>: CDS_PINID='VSS(972)';
NODE_NAME     U2D1 V15
 '@BASEBOARD_FAB2_LIB.BASEBOARD_FAB2(SCH_1):PAGE74_I21@CHPSET_LIB.SKX_EXT_B(CHIPS)':
 'VSS'<973>: CDS_PINID='VSS(973)';
NODE_NAME     U2D1 V13
 '@BASEBOARD_FAB2_LIB.BASEBOARD_FAB2(SCH_1):PAGE74_I21@CHPSET_LIB.SKX_EXT_B(CHIPS)':
 'VSS'<974>: CDS_PINID='VSS(974)';
NODE_NAME     U2D1 V9
 '@BASEBOARD_FAB2_LIB.BASEBOARD_FAB2(SCH_1):PAGE74_I21@CHPSET_LIB.SKX_EXT_B(CHIPS)':
 'VSS'<975>: CDS_PINID='VSS(975)';
NODE_NAME     U2D1 V5
 '@BASEBOARD_FAB2_LIB.BASEBOARD_FAB2(SCH_1):PAGE74_I21@CHPSET_LIB.SKX_EXT_B(CHIPS)':
 'VSS'<976>: CDS_PINID='VSS(976)';
NODE_NAME     U2D1 V1
 '@BASEBOARD_FAB2_LIB.BASEBOARD_FAB2(SCH_1):PAGE74_I21@CHPSET_LIB.SKX_EXT_B(CHIPS)':
 'VSS'<977>: CDS_PINID='VSS(977)';
NODE_NAME     U2D1 U86
 '@BASEBOARD_FAB2_LIB.BASEBOARD_FAB2(SCH_1):PAGE74_I21@CHPSET_LIB.SKX_EXT_B(CHIPS)':
 'VSS'<978>: CDS_PINID='VSS(978)';
NODE_NAME     U2D1 U80
 '@BASEBOARD_FAB2_LIB.BASEBOARD_FAB2(SCH_1):PAGE74_I21@CHPSET_LIB.SKX_EXT_B(CHIPS)':
 'VSS'<979>: CDS_PINID='VSS(979)';
NODE_NAME     U2D1 U78
 '@BASEBOARD_FAB2_LIB.BASEBOARD_FAB2(SCH_1):PAGE74_I21@CHPSET_LIB.SKX_EXT_B(CHIPS)':
 'VSS'<980>: CDS_PINID='VSS(980)';
NODE_NAME     U2D1 U76
 '@BASEBOARD_FAB2_LIB.BASEBOARD_FAB2(SCH_1):PAGE74_I21@CHPSET_LIB.SKX_EXT_B(CHIPS)':
 'VSS'<981>: CDS_PINID='VSS(981)';
NODE_NAME     U2D1 U74
 '@BASEBOARD_FAB2_LIB.BASEBOARD_FAB2(SCH_1):PAGE74_I21@CHPSET_LIB.SKX_EXT_B(CHIPS)':
 'VSS'<982>: CDS_PINID='VSS(982)';
NODE_NAME     U2D1 U70
 '@BASEBOARD_FAB2_LIB.BASEBOARD_FAB2(SCH_1):PAGE74_I21@CHPSET_LIB.SKX_EXT_B(CHIPS)':
 'VSS'<983>: CDS_PINID='VSS(983)';
NODE_NAME     U2D1 U68
 '@BASEBOARD_FAB2_LIB.BASEBOARD_FAB2(SCH_1):PAGE74_I21@CHPSET_LIB.SKX_EXT_B(CHIPS)':
 'VSS'<984>: CDS_PINID='VSS(984)';
NODE_NAME     U2D1 U42
 '@BASEBOARD_FAB2_LIB.BASEBOARD_FAB2(SCH_1):PAGE74_I21@CHPSET_LIB.SKX_EXT_B(CHIPS)':
 'VSS'<985>: CDS_PINID='VSS(985)';
NODE_NAME     U2D1 U36
 '@BASEBOARD_FAB2_LIB.BASEBOARD_FAB2(SCH_1):PAGE74_I21@CHPSET_LIB.SKX_EXT_B(CHIPS)':
 'VSS'<986>: CDS_PINID='VSS(986)';
NODE_NAME     U2D1 U30
 '@BASEBOARD_FAB2_LIB.BASEBOARD_FAB2(SCH_1):PAGE74_I21@CHPSET_LIB.SKX_EXT_B(CHIPS)':
 'VSS'<987>: CDS_PINID='VSS(987)';
NODE_NAME     U2D1 U24
 '@BASEBOARD_FAB2_LIB.BASEBOARD_FAB2(SCH_1):PAGE74_I21@CHPSET_LIB.SKX_EXT_B(CHIPS)':
 'VSS'<988>: CDS_PINID='VSS(988)';
NODE_NAME     U2D1 U22
 '@BASEBOARD_FAB2_LIB.BASEBOARD_FAB2(SCH_1):PAGE74_I21@CHPSET_LIB.SKX_EXT_B(CHIPS)':
 'VSS'<989>: CDS_PINID='VSS(989)';
NODE_NAME     U2D1 U20
 '@BASEBOARD_FAB2_LIB.BASEBOARD_FAB2(SCH_1):PAGE74_I21@CHPSET_LIB.SKX_EXT_B(CHIPS)':
 'VSS'<990>: CDS_PINID='VSS(990)';
NODE_NAME     U2D1 U6
 '@BASEBOARD_FAB2_LIB.BASEBOARD_FAB2(SCH_1):PAGE74_I21@CHPSET_LIB.SKX_EXT_B(CHIPS)':
 'VSS'<991>: CDS_PINID='VSS(991)';
NODE_NAME     U2D1 U4
 '@BASEBOARD_FAB2_LIB.BASEBOARD_FAB2(SCH_1):PAGE74_I21@CHPSET_LIB.SKX_EXT_B(CHIPS)':
 'VSS'<992>: CDS_PINID='VSS(992)';
NODE_NAME     U2D1 U2
 '@BASEBOARD_FAB2_LIB.BASEBOARD_FAB2(SCH_1):PAGE74_I21@CHPSET_LIB.SKX_EXT_B(CHIPS)':
 'VSS'<993>: CDS_PINID='VSS(993)';
NODE_NAME     U2D1 T85
 '@BASEBOARD_FAB2_LIB.BASEBOARD_FAB2(SCH_1):PAGE74_I21@CHPSET_LIB.SKX_EXT_B(CHIPS)':
 'VSS'<994>: CDS_PINID='VSS(994)';
NODE_NAME     U2D1 T83
 '@BASEBOARD_FAB2_LIB.BASEBOARD_FAB2(SCH_1):PAGE74_I21@CHPSET_LIB.SKX_EXT_B(CHIPS)':
 'VSS'<995>: CDS_PINID='VSS(995)';
NODE_NAME     U2D1 T77
 '@BASEBOARD_FAB2_LIB.BASEBOARD_FAB2(SCH_1):PAGE74_I21@CHPSET_LIB.SKX_EXT_B(CHIPS)':
 'VSS'<996>: CDS_PINID='VSS(996)';
NODE_NAME     U2D1 T73
 '@BASEBOARD_FAB2_LIB.BASEBOARD_FAB2(SCH_1):PAGE74_I21@CHPSET_LIB.SKX_EXT_B(CHIPS)':
 'VSS'<997>: CDS_PINID='VSS(997)';
NODE_NAME     U2D1 T65
 '@BASEBOARD_FAB2_LIB.BASEBOARD_FAB2(SCH_1):PAGE74_I21@CHPSET_LIB.SKX_EXT_B(CHIPS)':
 'VSS'<998>: CDS_PINID='VSS(998)';
NODE_NAME     U2D1 T41
 '@BASEBOARD_FAB2_LIB.BASEBOARD_FAB2(SCH_1):PAGE74_I21@CHPSET_LIB.SKX_EXT_B(CHIPS)':
 'VSS'<999>: CDS_PINID='VSS(999)';
NODE_NAME     U2D1 T37
 '@BASEBOARD_FAB2_LIB.BASEBOARD_FAB2(SCH_1):PAGE74_I21@CHPSET_LIB.SKX_EXT_B(CHIPS)':
 'VSS'<1000>: CDS_PINID='VSS(1000)';
NODE_NAME     U2D1 T35
 '@BASEBOARD_FAB2_LIB.BASEBOARD_FAB2(SCH_1):PAGE74_I21@CHPSET_LIB.SKX_EXT_B(CHIPS)':
 'VSS'<1001>: CDS_PINID='VSS(1001)';
NODE_NAME     U2D1 T31
 '@BASEBOARD_FAB2_LIB.BASEBOARD_FAB2(SCH_1):PAGE74_I21@CHPSET_LIB.SKX_EXT_B(CHIPS)':
 'VSS'<1002>: CDS_PINID='VSS(1002)';
NODE_NAME     U2D1 T29
 '@BASEBOARD_FAB2_LIB.BASEBOARD_FAB2(SCH_1):PAGE74_I21@CHPSET_LIB.SKX_EXT_B(CHIPS)':
 'VSS'<1003>: CDS_PINID='VSS(1003)';
NODE_NAME     U2D1 T25
 '@BASEBOARD_FAB2_LIB.BASEBOARD_FAB2(SCH_1):PAGE74_I21@CHPSET_LIB.SKX_EXT_B(CHIPS)':
 'VSS'<1004>: CDS_PINID='VSS(1004)';
NODE_NAME     U2D1 T17
 '@BASEBOARD_FAB2_LIB.BASEBOARD_FAB2(SCH_1):PAGE74_I21@CHPSET_LIB.SKX_EXT_B(CHIPS)':
 'VSS'<1005>: CDS_PINID='VSS(1005)';
NODE_NAME     U2D1 T13
 '@BASEBOARD_FAB2_LIB.BASEBOARD_FAB2(SCH_1):PAGE74_I21@CHPSET_LIB.SKX_EXT_B(CHIPS)':
 'VSS'<1006>: CDS_PINID='VSS(1006)';
NODE_NAME     U2D1 R86
 '@BASEBOARD_FAB2_LIB.BASEBOARD_FAB2(SCH_1):PAGE74_I21@CHPSET_LIB.SKX_EXT_B(CHIPS)':
 'VSS'<1007>: CDS_PINID='VSS(1007)';
NODE_NAME     U2D1 R78
 '@BASEBOARD_FAB2_LIB.BASEBOARD_FAB2(SCH_1):PAGE74_I21@CHPSET_LIB.SKX_EXT_B(CHIPS)':
 'VSS'<1008>: CDS_PINID='VSS(1008)';
NODE_NAME     U2D1 R72
 '@BASEBOARD_FAB2_LIB.BASEBOARD_FAB2(SCH_1):PAGE74_I21@CHPSET_LIB.SKX_EXT_B(CHIPS)':
 'VSS'<1009>: CDS_PINID='VSS(1009)';
NODE_NAME     U2D1 R68
 '@BASEBOARD_FAB2_LIB.BASEBOARD_FAB2(SCH_1):PAGE74_I21@CHPSET_LIB.SKX_EXT_B(CHIPS)':
 'VSS'<1010>: CDS_PINID='VSS(1010)';
NODE_NAME     U2D1 R40
 '@BASEBOARD_FAB2_LIB.BASEBOARD_FAB2(SCH_1):PAGE74_I21@CHPSET_LIB.SKX_EXT_B(CHIPS)':
 'VSS'<1011>: CDS_PINID='VSS(1011)';
NODE_NAME     U2D1 R38
 '@BASEBOARD_FAB2_LIB.BASEBOARD_FAB2(SCH_1):PAGE74_I21@CHPSET_LIB.SKX_EXT_B(CHIPS)':
 'VSS'<1012>: CDS_PINID='VSS(1012)';
NODE_NAME     U2D1 R34
 '@BASEBOARD_FAB2_LIB.BASEBOARD_FAB2(SCH_1):PAGE74_I21@CHPSET_LIB.SKX_EXT_B(CHIPS)':
 'VSS'<1013>: CDS_PINID='VSS(1013)';
NODE_NAME     U2D1 R32
 '@BASEBOARD_FAB2_LIB.BASEBOARD_FAB2(SCH_1):PAGE74_I21@CHPSET_LIB.SKX_EXT_B(CHIPS)':
 'VSS'<1014>: CDS_PINID='VSS(1014)';
NODE_NAME     U2D1 R28
 '@BASEBOARD_FAB2_LIB.BASEBOARD_FAB2(SCH_1):PAGE74_I21@CHPSET_LIB.SKX_EXT_B(CHIPS)':
 'VSS'<1015>: CDS_PINID='VSS(1015)';
NODE_NAME     U2D1 R26
 '@BASEBOARD_FAB2_LIB.BASEBOARD_FAB2(SCH_1):PAGE74_I21@CHPSET_LIB.SKX_EXT_B(CHIPS)':
 'VSS'<1016>: CDS_PINID='VSS(1016)';
NODE_NAME     U2D1 R22
 '@BASEBOARD_FAB2_LIB.BASEBOARD_FAB2(SCH_1):PAGE74_I21@CHPSET_LIB.SKX_EXT_B(CHIPS)':
 'VSS'<1017>: CDS_PINID='VSS(1017)';
NODE_NAME     U2D1 R4
 '@BASEBOARD_FAB2_LIB.BASEBOARD_FAB2(SCH_1):PAGE74_I21@CHPSET_LIB.SKX_EXT_B(CHIPS)':
 'VSS'<1018>: CDS_PINID='VSS(1018)';
NODE_NAME     U2D1 R2
 '@BASEBOARD_FAB2_LIB.BASEBOARD_FAB2(SCH_1):PAGE74_I21@CHPSET_LIB.SKX_EXT_B(CHIPS)':
 'VSS'<1019>: CDS_PINID='VSS(1019)';
NODE_NAME     U2D1 R18
 '@BASEBOARD_FAB2_LIB.BASEBOARD_FAB2(SCH_1):PAGE74_I21@CHPSET_LIB.SKX_EXT_B(CHIPS)':
 'VSS'<1020>: CDS_PINID='VSS(1020)';
NODE_NAME     U2D1 R14
 '@BASEBOARD_FAB2_LIB.BASEBOARD_FAB2(SCH_1):PAGE74_I21@CHPSET_LIB.SKX_EXT_B(CHIPS)':
 'VSS'<1021>: CDS_PINID='VSS(1021)';
NODE_NAME     U2D1 P83
 '@BASEBOARD_FAB2_LIB.BASEBOARD_FAB2(SCH_1):PAGE74_I21@CHPSET_LIB.SKX_EXT_B(CHIPS)':
 'VSS'<1022>: CDS_PINID='VSS(1022)';
NODE_NAME     U2D1 P81
 '@BASEBOARD_FAB2_LIB.BASEBOARD_FAB2(SCH_1):PAGE74_I21@CHPSET_LIB.SKX_EXT_B(CHIPS)':
 'VSS'<1023>: CDS_PINID='VSS(1023)';
NODE_NAME     U2D1 P71
 '@BASEBOARD_FAB2_LIB.BASEBOARD_FAB2(SCH_1):PAGE74_I21@CHPSET_LIB.SKX_EXT_B(CHIPS)':
 'VSS'<1024>: CDS_PINID='VSS(1024)';
NODE_NAME     U2D1 P69
 '@BASEBOARD_FAB2_LIB.BASEBOARD_FAB2(SCH_1):PAGE74_I21@CHPSET_LIB.SKX_EXT_B(CHIPS)':
 'VSS'<1025>: CDS_PINID='VSS(1025)';
NODE_NAME     U2D1 P67
 '@BASEBOARD_FAB2_LIB.BASEBOARD_FAB2(SCH_1):PAGE74_I21@CHPSET_LIB.SKX_EXT_B(CHIPS)':
 'VSS'<1026>: CDS_PINID='VSS(1026)';
NODE_NAME     U2D1 P39
 '@BASEBOARD_FAB2_LIB.BASEBOARD_FAB2(SCH_1):PAGE74_I21@CHPSET_LIB.SKX_EXT_B(CHIPS)':
 'VSS'<1027>: CDS_PINID='VSS(1027)';
NODE_NAME     U2D1 P33
 '@BASEBOARD_FAB2_LIB.BASEBOARD_FAB2(SCH_1):PAGE74_I21@CHPSET_LIB.SKX_EXT_B(CHIPS)':
 'VSS'<1028>: CDS_PINID='VSS(1028)';
NODE_NAME     U2D1 P27
 '@BASEBOARD_FAB2_LIB.BASEBOARD_FAB2(SCH_1):PAGE74_I21@CHPSET_LIB.SKX_EXT_B(CHIPS)':
 'VSS'<1029>: CDS_PINID='VSS(1029)';
NODE_NAME     U2D1 P15
 '@BASEBOARD_FAB2_LIB.BASEBOARD_FAB2(SCH_1):PAGE74_I21@CHPSET_LIB.SKX_EXT_B(CHIPS)':
 'VSS'<1030>: CDS_PINID='VSS(1030)';
NODE_NAME     U2D1 P11
 '@BASEBOARD_FAB2_LIB.BASEBOARD_FAB2(SCH_1):PAGE74_I21@CHPSET_LIB.SKX_EXT_B(CHIPS)':
 'VSS'<1031>: CDS_PINID='VSS(1031)';
NODE_NAME     U2D1 N8
 '@BASEBOARD_FAB2_LIB.BASEBOARD_FAB2(SCH_1):PAGE74_I21@CHPSET_LIB.SKX_EXT_B(CHIPS)':
 'VSS'<1032>: CDS_PINID='VSS(1032)';
NODE_NAME     U2D1 N4
 '@BASEBOARD_FAB2_LIB.BASEBOARD_FAB2(SCH_1):PAGE74_I21@CHPSET_LIB.SKX_EXT_B(CHIPS)':
 'VSS'<1033>: CDS_PINID='VSS(1033)';
NODE_NAME     U2D1 N78
 '@BASEBOARD_FAB2_LIB.BASEBOARD_FAB2(SCH_1):PAGE74_I21@CHPSET_LIB.SKX_EXT_B(CHIPS)':
 'VSS'<1034>: CDS_PINID='VSS(1034)';
NODE_NAME     U2D1 N76
 '@BASEBOARD_FAB2_LIB.BASEBOARD_FAB2(SCH_1):PAGE74_I21@CHPSET_LIB.SKX_EXT_B(CHIPS)':
 'VSS'<1035>: CDS_PINID='VSS(1035)';
NODE_NAME     U2D1 N74
 '@BASEBOARD_FAB2_LIB.BASEBOARD_FAB2(SCH_1):PAGE74_I21@CHPSET_LIB.SKX_EXT_B(CHIPS)':
 'VSS'<1036>: CDS_PINID='VSS(1036)';
NODE_NAME     U2D1 N72
 '@BASEBOARD_FAB2_LIB.BASEBOARD_FAB2(SCH_1):PAGE74_I21@CHPSET_LIB.SKX_EXT_B(CHIPS)':
 'VSS'<1037>: CDS_PINID='VSS(1037)';
NODE_NAME     U2D1 N70
 '@BASEBOARD_FAB2_LIB.BASEBOARD_FAB2(SCH_1):PAGE74_I21@CHPSET_LIB.SKX_EXT_B(CHIPS)':
 'VSS'<1038>: CDS_PINID='VSS(1038)';
NODE_NAME     U2D1 N66
 '@BASEBOARD_FAB2_LIB.BASEBOARD_FAB2(SCH_1):PAGE74_I21@CHPSET_LIB.SKX_EXT_B(CHIPS)':
 'VSS'<1039>: CDS_PINID='VSS(1039)';
NODE_NAME     U2D1 N6
 '@BASEBOARD_FAB2_LIB.BASEBOARD_FAB2(SCH_1):PAGE74_I21@CHPSET_LIB.SKX_EXT_B(CHIPS)':
 'VSS'<1040>: CDS_PINID='VSS(1040)';
NODE_NAME     U2D1 N22
 '@BASEBOARD_FAB2_LIB.BASEBOARD_FAB2(SCH_1):PAGE74_I21@CHPSET_LIB.SKX_EXT_B(CHIPS)':
 'VSS'<1041>: CDS_PINID='VSS(1041)';
NODE_NAME     U2D1 N20
 '@BASEBOARD_FAB2_LIB.BASEBOARD_FAB2(SCH_1):PAGE74_I21@CHPSET_LIB.SKX_EXT_B(CHIPS)':
 'VSS'<1042>: CDS_PINID='VSS(1042)';
NODE_NAME     U2D1 DM19
 '@BASEBOARD_FAB2_LIB.BASEBOARD_FAB2(SCH_1):PAGE74_I21@CHPSET_LIB.SKX_EXT_B(CHIPS)':
 'VSS'<1043>: CDS_PINID='VSS(1043)';
NODE_NAME     U2D1 M85
 '@BASEBOARD_FAB2_LIB.BASEBOARD_FAB2(SCH_1):PAGE74_I21@CHPSET_LIB.SKX_EXT_B(CHIPS)':
 'VSS'<1044>: CDS_PINID='VSS(1044)';
NODE_NAME     U2D1 M83
 '@BASEBOARD_FAB2_LIB.BASEBOARD_FAB2(SCH_1):PAGE74_I21@CHPSET_LIB.SKX_EXT_B(CHIPS)':
 'VSS'<1045>: CDS_PINID='VSS(1045)';
NODE_NAME     U2D1 M79
 '@BASEBOARD_FAB2_LIB.BASEBOARD_FAB2(SCH_1):PAGE74_I21@CHPSET_LIB.SKX_EXT_B(CHIPS)':
 'VSS'<1046>: CDS_PINID='VSS(1046)';
NODE_NAME     U2D1 M71
 '@BASEBOARD_FAB2_LIB.BASEBOARD_FAB2(SCH_1):PAGE74_I21@CHPSET_LIB.SKX_EXT_B(CHIPS)':
 'VSS'<1047>: CDS_PINID='VSS(1047)';
NODE_NAME     U2D1 M65
 '@BASEBOARD_FAB2_LIB.BASEBOARD_FAB2(SCH_1):PAGE74_I21@CHPSET_LIB.SKX_EXT_B(CHIPS)':
 'VSS'<1048>: CDS_PINID='VSS(1048)';
NODE_NAME     U2D1 M43
 '@BASEBOARD_FAB2_LIB.BASEBOARD_FAB2(SCH_1):PAGE74_I21@CHPSET_LIB.SKX_EXT_B(CHIPS)':
 'VSS'<1049>: CDS_PINID='VSS(1049)';
NODE_NAME     U2D1 M41
 '@BASEBOARD_FAB2_LIB.BASEBOARD_FAB2(SCH_1):PAGE74_I21@CHPSET_LIB.SKX_EXT_B(CHIPS)':
 'VSS'<1050>: CDS_PINID='VSS(1050)';
NODE_NAME     U2D1 M39
 '@BASEBOARD_FAB2_LIB.BASEBOARD_FAB2(SCH_1):PAGE74_I21@CHPSET_LIB.SKX_EXT_B(CHIPS)':
 'VSS'<1051>: CDS_PINID='VSS(1051)';
NODE_NAME     U2D1 M37
 '@BASEBOARD_FAB2_LIB.BASEBOARD_FAB2(SCH_1):PAGE74_I21@CHPSET_LIB.SKX_EXT_B(CHIPS)':
 'VSS'<1052>: CDS_PINID='VSS(1052)';
NODE_NAME     U2D1 M35
 '@BASEBOARD_FAB2_LIB.BASEBOARD_FAB2(SCH_1):PAGE74_I21@CHPSET_LIB.SKX_EXT_B(CHIPS)':
 'VSS'<1053>: CDS_PINID='VSS(1053)';
NODE_NAME     U2D1 M33
 '@BASEBOARD_FAB2_LIB.BASEBOARD_FAB2(SCH_1):PAGE74_I21@CHPSET_LIB.SKX_EXT_B(CHIPS)':
 'VSS'<1054>: CDS_PINID='VSS(1054)';
NODE_NAME     U2D1 M31
 '@BASEBOARD_FAB2_LIB.BASEBOARD_FAB2(SCH_1):PAGE74_I21@CHPSET_LIB.SKX_EXT_B(CHIPS)':
 'VSS'<1055>: CDS_PINID='VSS(1055)';
NODE_NAME     U2D1 M29
 '@BASEBOARD_FAB2_LIB.BASEBOARD_FAB2(SCH_1):PAGE74_I21@CHPSET_LIB.SKX_EXT_B(CHIPS)':
 'VSS'<1056>: CDS_PINID='VSS(1056)';
NODE_NAME     U2D1 M27
 '@BASEBOARD_FAB2_LIB.BASEBOARD_FAB2(SCH_1):PAGE74_I21@CHPSET_LIB.SKX_EXT_B(CHIPS)':
 'VSS'<1057>: CDS_PINID='VSS(1057)';
NODE_NAME     U2D1 M25
 '@BASEBOARD_FAB2_LIB.BASEBOARD_FAB2(SCH_1):PAGE74_I21@CHPSET_LIB.SKX_EXT_B(CHIPS)':
 'VSS'<1058>: CDS_PINID='VSS(1058)';
NODE_NAME     U2D1 M23
 '@BASEBOARD_FAB2_LIB.BASEBOARD_FAB2(SCH_1):PAGE74_I21@CHPSET_LIB.SKX_EXT_B(CHIPS)':
 'VSS'<1059>: CDS_PINID='VSS(1059)';
NODE_NAME     U2D1 M19
 '@BASEBOARD_FAB2_LIB.BASEBOARD_FAB2(SCH_1):PAGE74_I21@CHPSET_LIB.SKX_EXT_B(CHIPS)':
 'VSS'<1060>: CDS_PINID='VSS(1060)';
NODE_NAME     U2D1 M17
 '@BASEBOARD_FAB2_LIB.BASEBOARD_FAB2(SCH_1):PAGE74_I21@CHPSET_LIB.SKX_EXT_B(CHIPS)':
 'VSS'<1061>: CDS_PINID='VSS(1061)';
NODE_NAME     U2D1 M15
 '@BASEBOARD_FAB2_LIB.BASEBOARD_FAB2(SCH_1):PAGE74_I21@CHPSET_LIB.SKX_EXT_B(CHIPS)':
 'VSS'<1062>: CDS_PINID='VSS(1062)';
NODE_NAME     U2D1 CT7
 '@BASEBOARD_FAB2_LIB.BASEBOARD_FAB2(SCH_1):PAGE74_I21@CHPSET_LIB.SKX_EXT_B(CHIPS)':
 'VSS'<1063>: CDS_PINID='VSS(1063)';
NODE_NAME     U2D1 BT9
 '@BASEBOARD_FAB2_LIB.BASEBOARD_FAB2(SCH_1):PAGE74_I21@CHPSET_LIB.SKX_EXT_B(CHIPS)':
 'VSS'<1064>: CDS_PINID='VSS(1064)';
NODE_NAME     U2D1 L82
 '@BASEBOARD_FAB2_LIB.BASEBOARD_FAB2(SCH_1):PAGE74_I21@CHPSET_LIB.SKX_EXT_B(CHIPS)':
 'VSS'<1065>: CDS_PINID='VSS(1065)';
NODE_NAME     U2D1 L80
 '@BASEBOARD_FAB2_LIB.BASEBOARD_FAB2(SCH_1):PAGE74_I21@CHPSET_LIB.SKX_EXT_B(CHIPS)':
 'VSS'<1066>: CDS_PINID='VSS(1066)';
NODE_NAME     U2D1 L78
 '@BASEBOARD_FAB2_LIB.BASEBOARD_FAB2(SCH_1):PAGE74_I21@CHPSET_LIB.SKX_EXT_B(CHIPS)':
 'VSS'<1067>: CDS_PINID='VSS(1067)';
NODE_NAME     U2D1 L72
 '@BASEBOARD_FAB2_LIB.BASEBOARD_FAB2(SCH_1):PAGE74_I21@CHPSET_LIB.SKX_EXT_B(CHIPS)':
 'VSS'<1068>: CDS_PINID='VSS(1068)';
NODE_NAME     U2D1 L22
 '@BASEBOARD_FAB2_LIB.BASEBOARD_FAB2(SCH_1):PAGE74_I21@CHPSET_LIB.SKX_EXT_B(CHIPS)':
 'VSS'<1069>: CDS_PINID='VSS(1069)';
NODE_NAME     U2D1 L20
 '@BASEBOARD_FAB2_LIB.BASEBOARD_FAB2(SCH_1):PAGE74_I21@CHPSET_LIB.SKX_EXT_B(CHIPS)':
 'VSS'<1070>: CDS_PINID='VSS(1070)';
NODE_NAME     U2D1 L6
 '@BASEBOARD_FAB2_LIB.BASEBOARD_FAB2(SCH_1):PAGE74_I21@CHPSET_LIB.SKX_EXT_B(CHIPS)':
 'VSS'<1071>: CDS_PINID='VSS(1071)';
NODE_NAME     U2D1 L2
 '@BASEBOARD_FAB2_LIB.BASEBOARD_FAB2(SCH_1):PAGE74_I21@CHPSET_LIB.SKX_EXT_B(CHIPS)':
 'VSS'<1072>: CDS_PINID='VSS(1072)';
NODE_NAME     U2D1 L10
 '@BASEBOARD_FAB2_LIB.BASEBOARD_FAB2(SCH_1):PAGE74_I21@CHPSET_LIB.SKX_EXT_B(CHIPS)':
 'VSS'<1073>: CDS_PINID='VSS(1073)';
NODE_NAME     U2D1 K85
 '@BASEBOARD_FAB2_LIB.BASEBOARD_FAB2(SCH_1):PAGE74_I21@CHPSET_LIB.SKX_EXT_B(CHIPS)':
 'VSS'<1074>: CDS_PINID='VSS(1074)';
NODE_NAME     U2D1 K83
 '@BASEBOARD_FAB2_LIB.BASEBOARD_FAB2(SCH_1):PAGE74_I21@CHPSET_LIB.SKX_EXT_B(CHIPS)':
 'VSS'<1075>: CDS_PINID='VSS(1075)';
NODE_NAME     U2D1 K81
 '@BASEBOARD_FAB2_LIB.BASEBOARD_FAB2(SCH_1):PAGE74_I21@CHPSET_LIB.SKX_EXT_B(CHIPS)':
 'VSS'<1076>: CDS_PINID='VSS(1076)';
NODE_NAME     U2D1 K77
 '@BASEBOARD_FAB2_LIB.BASEBOARD_FAB2(SCH_1):PAGE74_I21@CHPSET_LIB.SKX_EXT_B(CHIPS)':
 'VSS'<1077>: CDS_PINID='VSS(1077)';
NODE_NAME     U2D1 K73
 '@BASEBOARD_FAB2_LIB.BASEBOARD_FAB2(SCH_1):PAGE74_I21@CHPSET_LIB.SKX_EXT_B(CHIPS)':
 'VSS'<1078>: CDS_PINID='VSS(1078)';
NODE_NAME     U2D1 K71
 '@BASEBOARD_FAB2_LIB.BASEBOARD_FAB2(SCH_1):PAGE74_I21@CHPSET_LIB.SKX_EXT_B(CHIPS)':
 'VSS'<1079>: CDS_PINID='VSS(1079)';
NODE_NAME     U2D1 K69
 '@BASEBOARD_FAB2_LIB.BASEBOARD_FAB2(SCH_1):PAGE74_I21@CHPSET_LIB.SKX_EXT_B(CHIPS)':
 'VSS'<1080>: CDS_PINID='VSS(1080)';
NODE_NAME     U2D1 K67
 '@BASEBOARD_FAB2_LIB.BASEBOARD_FAB2(SCH_1):PAGE74_I21@CHPSET_LIB.SKX_EXT_B(CHIPS)':
 'VSS'<1081>: CDS_PINID='VSS(1081)';
NODE_NAME     U2D1 K65
 '@BASEBOARD_FAB2_LIB.BASEBOARD_FAB2(SCH_1):PAGE74_I21@CHPSET_LIB.SKX_EXT_B(CHIPS)':
 'VSS'<1082>: CDS_PINID='VSS(1082)';
NODE_NAME     U2D1 K39
 '@BASEBOARD_FAB2_LIB.BASEBOARD_FAB2(SCH_1):PAGE74_I21@CHPSET_LIB.SKX_EXT_B(CHIPS)':
 'VSS'<1083>: CDS_PINID='VSS(1083)';
NODE_NAME     U2D1 K33
 '@BASEBOARD_FAB2_LIB.BASEBOARD_FAB2(SCH_1):PAGE74_I21@CHPSET_LIB.SKX_EXT_B(CHIPS)':
 'VSS'<1084>: CDS_PINID='VSS(1084)';
NODE_NAME     U2D1 K27
 '@BASEBOARD_FAB2_LIB.BASEBOARD_FAB2(SCH_1):PAGE74_I21@CHPSET_LIB.SKX_EXT_B(CHIPS)':
 'VSS'<1085>: CDS_PINID='VSS(1085)';
NODE_NAME     U2D1 DB7
 '@BASEBOARD_FAB2_LIB.BASEBOARD_FAB2(SCH_1):PAGE74_I21@CHPSET_LIB.SKX_EXT_B(CHIPS)':
 'VSS'<1086>: CDS_PINID='VSS(1086)';
NODE_NAME     U2D1 K17
 '@BASEBOARD_FAB2_LIB.BASEBOARD_FAB2(SCH_1):PAGE74_I21@CHPSET_LIB.SKX_EXT_B(CHIPS)':
 'VSS'<1087>: CDS_PINID='VSS(1087)';
NODE_NAME     U2D1 K13
 '@BASEBOARD_FAB2_LIB.BASEBOARD_FAB2(SCH_1):PAGE74_I21@CHPSET_LIB.SKX_EXT_B(CHIPS)':
 'VSS'<1088>: CDS_PINID='VSS(1088)';
NODE_NAME     U2D1 K11
 '@BASEBOARD_FAB2_LIB.BASEBOARD_FAB2(SCH_1):PAGE74_I21@CHPSET_LIB.SKX_EXT_B(CHIPS)':
 'VSS'<1089>: CDS_PINID='VSS(1089)';
NODE_NAME     U2D1 K1
 '@BASEBOARD_FAB2_LIB.BASEBOARD_FAB2(SCH_1):PAGE74_I21@CHPSET_LIB.SKX_EXT_B(CHIPS)':
 'VSS'<1090>: CDS_PINID='VSS(1090)';
NODE_NAME     U2D1 J84
 '@BASEBOARD_FAB2_LIB.BASEBOARD_FAB2(SCH_1):PAGE74_I21@CHPSET_LIB.SKX_EXT_B(CHIPS)':
 'VSS'<1091>: CDS_PINID='VSS(1091)';
NODE_NAME     U2D1 J82
 '@BASEBOARD_FAB2_LIB.BASEBOARD_FAB2(SCH_1):PAGE74_I21@CHPSET_LIB.SKX_EXT_B(CHIPS)':
 'VSS'<1092>: CDS_PINID='VSS(1092)';
NODE_NAME     U2D1 J76
 '@BASEBOARD_FAB2_LIB.BASEBOARD_FAB2(SCH_1):PAGE74_I21@CHPSET_LIB.SKX_EXT_B(CHIPS)':
 'VSS'<1093>: CDS_PINID='VSS(1093)';
NODE_NAME     U2D1 AL68
 '@BASEBOARD_FAB2_LIB.BASEBOARD_FAB2(SCH_1):PAGE74_I22@CHPSET_LIB.SKX_EXT_B(CHIPS)':
 'VSS'<774>: CDS_PINID='VSS(774)';
NODE_NAME     U2D1 AL64
 '@BASEBOARD_FAB2_LIB.BASEBOARD_FAB2(SCH_1):PAGE74_I22@CHPSET_LIB.SKX_EXT_B(CHIPS)':
 'VSS'<775>: CDS_PINID='VSS(775)';
NODE_NAME     U2D1 AL56
 '@BASEBOARD_FAB2_LIB.BASEBOARD_FAB2(SCH_1):PAGE74_I22@CHPSET_LIB.SKX_EXT_B(CHIPS)':
 'VSS'<776>: CDS_PINID='VSS(776)';
NODE_NAME     U2D1 AL32
 '@BASEBOARD_FAB2_LIB.BASEBOARD_FAB2(SCH_1):PAGE74_I22@CHPSET_LIB.SKX_EXT_B(CHIPS)':
 'VSS'<777>: CDS_PINID='VSS(777)';
NODE_NAME     U2D1 AL30
 '@BASEBOARD_FAB2_LIB.BASEBOARD_FAB2(SCH_1):PAGE74_I22@CHPSET_LIB.SKX_EXT_B(CHIPS)':
 'VSS'<778>: CDS_PINID='VSS(778)';
NODE_NAME     U2D1 AL24
 '@BASEBOARD_FAB2_LIB.BASEBOARD_FAB2(SCH_1):PAGE74_I22@CHPSET_LIB.SKX_EXT_B(CHIPS)':
 'VSS'<779>: CDS_PINID='VSS(779)';
NODE_NAME     U2D1 AL10
 '@BASEBOARD_FAB2_LIB.BASEBOARD_FAB2(SCH_1):PAGE74_I22@CHPSET_LIB.SKX_EXT_B(CHIPS)':
 'VSS'<780>: CDS_PINID='VSS(780)';
NODE_NAME     U2D1 AL4
 '@BASEBOARD_FAB2_LIB.BASEBOARD_FAB2(SCH_1):PAGE74_I22@CHPSET_LIB.SKX_EXT_B(CHIPS)':
 'VSS'<781>: CDS_PINID='VSS(781)';
NODE_NAME     U2D1 AK85
 '@BASEBOARD_FAB2_LIB.BASEBOARD_FAB2(SCH_1):PAGE74_I22@CHPSET_LIB.SKX_EXT_B(CHIPS)':
 'VSS'<782>: CDS_PINID='VSS(782)';
NODE_NAME     U2D1 AK83
 '@BASEBOARD_FAB2_LIB.BASEBOARD_FAB2(SCH_1):PAGE74_I22@CHPSET_LIB.SKX_EXT_B(CHIPS)':
 'VSS'<783>: CDS_PINID='VSS(783)';
NODE_NAME     U2D1 AK81
 '@BASEBOARD_FAB2_LIB.BASEBOARD_FAB2(SCH_1):PAGE74_I22@CHPSET_LIB.SKX_EXT_B(CHIPS)':
 'VSS'<784>: CDS_PINID='VSS(784)';
NODE_NAME     U2D1 AK79
 '@BASEBOARD_FAB2_LIB.BASEBOARD_FAB2(SCH_1):PAGE74_I22@CHPSET_LIB.SKX_EXT_B(CHIPS)':
 'VSS'<785>: CDS_PINID='VSS(785)';
NODE_NAME     U2D1 AK73
 '@BASEBOARD_FAB2_LIB.BASEBOARD_FAB2(SCH_1):PAGE74_I22@CHPSET_LIB.SKX_EXT_B(CHIPS)':
 'VSS'<786>: CDS_PINID='VSS(786)';
NODE_NAME     U2D1 AK67
 '@BASEBOARD_FAB2_LIB.BASEBOARD_FAB2(SCH_1):PAGE74_I22@CHPSET_LIB.SKX_EXT_B(CHIPS)':
 'VSS'<787>: CDS_PINID='VSS(787)';
NODE_NAME     U2D1 AK65
 '@BASEBOARD_FAB2_LIB.BASEBOARD_FAB2(SCH_1):PAGE74_I22@CHPSET_LIB.SKX_EXT_B(CHIPS)':
 'VSS'<788>: CDS_PINID='VSS(788)';
NODE_NAME     U2D1 AK55
 '@BASEBOARD_FAB2_LIB.BASEBOARD_FAB2(SCH_1):PAGE74_I22@CHPSET_LIB.SKX_EXT_B(CHIPS)':
 'VSS'<789>: CDS_PINID='VSS(789)';
NODE_NAME     U2D1 AK33
 '@BASEBOARD_FAB2_LIB.BASEBOARD_FAB2(SCH_1):PAGE74_I22@CHPSET_LIB.SKX_EXT_B(CHIPS)':
 'VSS'<790>: CDS_PINID='VSS(790)';
NODE_NAME     U2D1 AK31
 '@BASEBOARD_FAB2_LIB.BASEBOARD_FAB2(SCH_1):PAGE74_I22@CHPSET_LIB.SKX_EXT_B(CHIPS)':
 'VSS'<791>: CDS_PINID='VSS(791)';
NODE_NAME     U2D1 AK29
 '@BASEBOARD_FAB2_LIB.BASEBOARD_FAB2(SCH_1):PAGE74_I22@CHPSET_LIB.SKX_EXT_B(CHIPS)':
 'VSS'<792>: CDS_PINID='VSS(792)';
NODE_NAME     U2D1 AK25
 '@BASEBOARD_FAB2_LIB.BASEBOARD_FAB2(SCH_1):PAGE74_I22@CHPSET_LIB.SKX_EXT_B(CHIPS)':
 'VSS'<793>: CDS_PINID='VSS(793)';
NODE_NAME     U2D1 AK23
 '@BASEBOARD_FAB2_LIB.BASEBOARD_FAB2(SCH_1):PAGE74_I22@CHPSET_LIB.SKX_EXT_B(CHIPS)':
 'VSS'<794>: CDS_PINID='VSS(794)';
NODE_NAME     U2D1 AK19
 '@BASEBOARD_FAB2_LIB.BASEBOARD_FAB2(SCH_1):PAGE74_I22@CHPSET_LIB.SKX_EXT_B(CHIPS)':
 'VSS'<795>: CDS_PINID='VSS(795)';
NODE_NAME     U2D1 AK13
 '@BASEBOARD_FAB2_LIB.BASEBOARD_FAB2(SCH_1):PAGE74_I22@CHPSET_LIB.SKX_EXT_B(CHIPS)':
 'VSS'<796>: CDS_PINID='VSS(796)';
NODE_NAME     U2D1 AK9
 '@BASEBOARD_FAB2_LIB.BASEBOARD_FAB2(SCH_1):PAGE74_I22@CHPSET_LIB.SKX_EXT_B(CHIPS)':
 'VSS'<797>: CDS_PINID='VSS(797)';
NODE_NAME     U2D1 AJ86
 '@BASEBOARD_FAB2_LIB.BASEBOARD_FAB2(SCH_1):PAGE74_I22@CHPSET_LIB.SKX_EXT_B(CHIPS)':
 'VSS'<798>: CDS_PINID='VSS(798)';
NODE_NAME     U2D1 AJ82
 '@BASEBOARD_FAB2_LIB.BASEBOARD_FAB2(SCH_1):PAGE74_I22@CHPSET_LIB.SKX_EXT_B(CHIPS)':
 'VSS'<799>: CDS_PINID='VSS(799)';
NODE_NAME     U2D1 AJ78
 '@BASEBOARD_FAB2_LIB.BASEBOARD_FAB2(SCH_1):PAGE74_I22@CHPSET_LIB.SKX_EXT_B(CHIPS)':
 'VSS'<800>: CDS_PINID='VSS(800)';
NODE_NAME     U2D1 AJ74
 '@BASEBOARD_FAB2_LIB.BASEBOARD_FAB2(SCH_1):PAGE74_I22@CHPSET_LIB.SKX_EXT_B(CHIPS)':
 'VSS'<801>: CDS_PINID='VSS(801)';
NODE_NAME     U2D1 AJ68
 '@BASEBOARD_FAB2_LIB.BASEBOARD_FAB2(SCH_1):PAGE74_I22@CHPSET_LIB.SKX_EXT_B(CHIPS)':
 'VSS'<802>: CDS_PINID='VSS(802)';
NODE_NAME     U2D1 AJ66
 '@BASEBOARD_FAB2_LIB.BASEBOARD_FAB2(SCH_1):PAGE74_I22@CHPSET_LIB.SKX_EXT_B(CHIPS)':
 'VSS'<803>: CDS_PINID='VSS(803)';
NODE_NAME     U2D1 AJ54
 '@BASEBOARD_FAB2_LIB.BASEBOARD_FAB2(SCH_1):PAGE74_I22@CHPSET_LIB.SKX_EXT_B(CHIPS)':
 'VSS'<804>: CDS_PINID='VSS(804)';
NODE_NAME     U2D1 AJ52
 '@BASEBOARD_FAB2_LIB.BASEBOARD_FAB2(SCH_1):PAGE74_I22@CHPSET_LIB.SKX_EXT_B(CHIPS)':
 'VSS'<805>: CDS_PINID='VSS(805)';
NODE_NAME     U2D1 AJ50
 '@BASEBOARD_FAB2_LIB.BASEBOARD_FAB2(SCH_1):PAGE74_I22@CHPSET_LIB.SKX_EXT_B(CHIPS)':
 'VSS'<806>: CDS_PINID='VSS(806)';
NODE_NAME     U2D1 AJ48
 '@BASEBOARD_FAB2_LIB.BASEBOARD_FAB2(SCH_1):PAGE74_I22@CHPSET_LIB.SKX_EXT_B(CHIPS)':
 'VSS'<807>: CDS_PINID='VSS(807)';
NODE_NAME     U2D1 AJ46
 '@BASEBOARD_FAB2_LIB.BASEBOARD_FAB2(SCH_1):PAGE74_I22@CHPSET_LIB.SKX_EXT_B(CHIPS)':
 'VSS'<808>: CDS_PINID='VSS(808)';
NODE_NAME     U2D1 AJ34
 '@BASEBOARD_FAB2_LIB.BASEBOARD_FAB2(SCH_1):PAGE74_I22@CHPSET_LIB.SKX_EXT_B(CHIPS)':
 'VSS'<809>: CDS_PINID='VSS(809)';
NODE_NAME     U2D1 AJ32
 '@BASEBOARD_FAB2_LIB.BASEBOARD_FAB2(SCH_1):PAGE74_I22@CHPSET_LIB.SKX_EXT_B(CHIPS)':
 'VSS'<810>: CDS_PINID='VSS(810)';
NODE_NAME     U2D1 AJ28
 '@BASEBOARD_FAB2_LIB.BASEBOARD_FAB2(SCH_1):PAGE74_I22@CHPSET_LIB.SKX_EXT_B(CHIPS)':
 'VSS'<811>: CDS_PINID='VSS(811)';
NODE_NAME     U2D1 AJ26
 '@BASEBOARD_FAB2_LIB.BASEBOARD_FAB2(SCH_1):PAGE74_I22@CHPSET_LIB.SKX_EXT_B(CHIPS)':
 'VSS'<812>: CDS_PINID='VSS(812)';
NODE_NAME     U2D1 AJ22
 '@BASEBOARD_FAB2_LIB.BASEBOARD_FAB2(SCH_1):PAGE74_I22@CHPSET_LIB.SKX_EXT_B(CHIPS)':
 'VSS'<813>: CDS_PINID='VSS(813)';
NODE_NAME     U2D1 AJ8
 '@BASEBOARD_FAB2_LIB.BASEBOARD_FAB2(SCH_1):PAGE74_I22@CHPSET_LIB.SKX_EXT_B(CHIPS)':
 'VSS'<814>: CDS_PINID='VSS(814)';
NODE_NAME     U2D1 AH83
 '@BASEBOARD_FAB2_LIB.BASEBOARD_FAB2(SCH_1):PAGE74_I22@CHPSET_LIB.SKX_EXT_B(CHIPS)':
 'VSS'<815>: CDS_PINID='VSS(815)';
NODE_NAME     U2D1 AH77
 '@BASEBOARD_FAB2_LIB.BASEBOARD_FAB2(SCH_1):PAGE74_I22@CHPSET_LIB.SKX_EXT_B(CHIPS)':
 'VSS'<816>: CDS_PINID='VSS(816)';
NODE_NAME     U2D1 AH75
 '@BASEBOARD_FAB2_LIB.BASEBOARD_FAB2(SCH_1):PAGE74_I22@CHPSET_LIB.SKX_EXT_B(CHIPS)':
 'VSS'<817>: CDS_PINID='VSS(817)';
NODE_NAME     U2D1 AH69
 '@BASEBOARD_FAB2_LIB.BASEBOARD_FAB2(SCH_1):PAGE74_I22@CHPSET_LIB.SKX_EXT_B(CHIPS)':
 'VSS'<818>: CDS_PINID='VSS(818)';
NODE_NAME     U2D1 AH65
 '@BASEBOARD_FAB2_LIB.BASEBOARD_FAB2(SCH_1):PAGE74_I22@CHPSET_LIB.SKX_EXT_B(CHIPS)':
 'VSS'<819>: CDS_PINID='VSS(819)';
NODE_NAME     U2D1 AH61
 '@BASEBOARD_FAB2_LIB.BASEBOARD_FAB2(SCH_1):PAGE74_I22@CHPSET_LIB.SKX_EXT_B(CHIPS)':
 'VSS'<820>: CDS_PINID='VSS(820)';
NODE_NAME     U2D1 AH59
 '@BASEBOARD_FAB2_LIB.BASEBOARD_FAB2(SCH_1):PAGE74_I22@CHPSET_LIB.SKX_EXT_B(CHIPS)':
 'VSS'<821>: CDS_PINID='VSS(821)';
NODE_NAME     U2D1 AH53
 '@BASEBOARD_FAB2_LIB.BASEBOARD_FAB2(SCH_1):PAGE74_I22@CHPSET_LIB.SKX_EXT_B(CHIPS)':
 'VSS'<822>: CDS_PINID='VSS(822)';
NODE_NAME     U2D1 AH51
 '@BASEBOARD_FAB2_LIB.BASEBOARD_FAB2(SCH_1):PAGE74_I22@CHPSET_LIB.SKX_EXT_B(CHIPS)':
 'VSS'<823>: CDS_PINID='VSS(823)';
NODE_NAME     U2D1 AH49
 '@BASEBOARD_FAB2_LIB.BASEBOARD_FAB2(SCH_1):PAGE74_I22@CHPSET_LIB.SKX_EXT_B(CHIPS)':
 'VSS'<824>: CDS_PINID='VSS(824)';
NODE_NAME     U2D1 AH47
 '@BASEBOARD_FAB2_LIB.BASEBOARD_FAB2(SCH_1):PAGE74_I22@CHPSET_LIB.SKX_EXT_B(CHIPS)':
 'VSS'<825>: CDS_PINID='VSS(825)';
NODE_NAME     U2D1 AH45
 '@BASEBOARD_FAB2_LIB.BASEBOARD_FAB2(SCH_1):PAGE74_I22@CHPSET_LIB.SKX_EXT_B(CHIPS)':
 'VSS'<826>: CDS_PINID='VSS(826)';
NODE_NAME     U2D1 AH35
 '@BASEBOARD_FAB2_LIB.BASEBOARD_FAB2(SCH_1):PAGE74_I22@CHPSET_LIB.SKX_EXT_B(CHIPS)':
 'VSS'<827>: CDS_PINID='VSS(827)';
NODE_NAME     U2D1 AH33
 '@BASEBOARD_FAB2_LIB.BASEBOARD_FAB2(SCH_1):PAGE74_I22@CHPSET_LIB.SKX_EXT_B(CHIPS)':
 'VSS'<828>: CDS_PINID='VSS(828)';
NODE_NAME     U2D1 AH27
 '@BASEBOARD_FAB2_LIB.BASEBOARD_FAB2(SCH_1):PAGE74_I22@CHPSET_LIB.SKX_EXT_B(CHIPS)':
 'VSS'<829>: CDS_PINID='VSS(829)';
NODE_NAME     U2D1 AH21
 '@BASEBOARD_FAB2_LIB.BASEBOARD_FAB2(SCH_1):PAGE74_I22@CHPSET_LIB.SKX_EXT_B(CHIPS)':
 'VSS'<830>: CDS_PINID='VSS(830)';
NODE_NAME     U2D1 AH5
 '@BASEBOARD_FAB2_LIB.BASEBOARD_FAB2(SCH_1):PAGE74_I22@CHPSET_LIB.SKX_EXT_B(CHIPS)':
 'VSS'<831>: CDS_PINID='VSS(831)';
NODE_NAME     U2D1 AH1
 '@BASEBOARD_FAB2_LIB.BASEBOARD_FAB2(SCH_1):PAGE74_I22@CHPSET_LIB.SKX_EXT_B(CHIPS)':
 'VSS'<832>: CDS_PINID='VSS(832)';
NODE_NAME     U2D1 AG80
 '@BASEBOARD_FAB2_LIB.BASEBOARD_FAB2(SCH_1):PAGE74_I22@CHPSET_LIB.SKX_EXT_B(CHIPS)':
 'VSS'<833>: CDS_PINID='VSS(833)';
NODE_NAME     U2D1 AG78
 '@BASEBOARD_FAB2_LIB.BASEBOARD_FAB2(SCH_1):PAGE74_I22@CHPSET_LIB.SKX_EXT_B(CHIPS)':
 'VSS'<834>: CDS_PINID='VSS(834)';
NODE_NAME     U2D1 AG76
 '@BASEBOARD_FAB2_LIB.BASEBOARD_FAB2(SCH_1):PAGE74_I22@CHPSET_LIB.SKX_EXT_B(CHIPS)':
 'VSS'<835>: CDS_PINID='VSS(835)';
NODE_NAME     U2D1 AG74
 '@BASEBOARD_FAB2_LIB.BASEBOARD_FAB2(SCH_1):PAGE74_I22@CHPSET_LIB.SKX_EXT_B(CHIPS)':
 'VSS'<836>: CDS_PINID='VSS(836)';
NODE_NAME     U2D1 AG70
 '@BASEBOARD_FAB2_LIB.BASEBOARD_FAB2(SCH_1):PAGE74_I22@CHPSET_LIB.SKX_EXT_B(CHIPS)':
 'VSS'<837>: CDS_PINID='VSS(837)';
NODE_NAME     U2D1 AG64
 '@BASEBOARD_FAB2_LIB.BASEBOARD_FAB2(SCH_1):PAGE74_I22@CHPSET_LIB.SKX_EXT_B(CHIPS)':
 'VSS'<838>: CDS_PINID='VSS(838)';
NODE_NAME     U2D1 AG36
 '@BASEBOARD_FAB2_LIB.BASEBOARD_FAB2(SCH_1):PAGE74_I22@CHPSET_LIB.SKX_EXT_B(CHIPS)':
 'VSS'<839>: CDS_PINID='VSS(839)';
NODE_NAME     U2D1 AG18
 '@BASEBOARD_FAB2_LIB.BASEBOARD_FAB2(SCH_1):PAGE74_I22@CHPSET_LIB.SKX_EXT_B(CHIPS)':
 'VSS'<840>: CDS_PINID='VSS(840)';
NODE_NAME     U2D1 AG14
 '@BASEBOARD_FAB2_LIB.BASEBOARD_FAB2(SCH_1):PAGE74_I22@CHPSET_LIB.SKX_EXT_B(CHIPS)':
 'VSS'<841>: CDS_PINID='VSS(841)';
NODE_NAME     U2D1 AG12
 '@BASEBOARD_FAB2_LIB.BASEBOARD_FAB2(SCH_1):PAGE74_I22@CHPSET_LIB.SKX_EXT_B(CHIPS)':
 'VSS'<842>: CDS_PINID='VSS(842)';
NODE_NAME     U2D1 AF85
 '@BASEBOARD_FAB2_LIB.BASEBOARD_FAB2(SCH_1):PAGE74_I22@CHPSET_LIB.SKX_EXT_B(CHIPS)':
 'VSS'<843>: CDS_PINID='VSS(843)';
NODE_NAME     U2D1 AF83
 '@BASEBOARD_FAB2_LIB.BASEBOARD_FAB2(SCH_1):PAGE74_I22@CHPSET_LIB.SKX_EXT_B(CHIPS)':
 'VSS'<844>: CDS_PINID='VSS(844)';
NODE_NAME     U2D1 AF77
 '@BASEBOARD_FAB2_LIB.BASEBOARD_FAB2(SCH_1):PAGE74_I22@CHPSET_LIB.SKX_EXT_B(CHIPS)':
 'VSS'<845>: CDS_PINID='VSS(845)';
NODE_NAME     U2D1 AF73
 '@BASEBOARD_FAB2_LIB.BASEBOARD_FAB2(SCH_1):PAGE74_I22@CHPSET_LIB.SKX_EXT_B(CHIPS)':
 'VSS'<846>: CDS_PINID='VSS(846)';
NODE_NAME     U2D1 AF41
 '@BASEBOARD_FAB2_LIB.BASEBOARD_FAB2(SCH_1):PAGE74_I22@CHPSET_LIB.SKX_EXT_B(CHIPS)':
 'VSS'<847>: CDS_PINID='VSS(847)';
NODE_NAME     U2D1 AF39
 '@BASEBOARD_FAB2_LIB.BASEBOARD_FAB2(SCH_1):PAGE74_I22@CHPSET_LIB.SKX_EXT_B(CHIPS)':
 'VSS'<848>: CDS_PINID='VSS(848)';
NODE_NAME     U2D1 AF37
 '@BASEBOARD_FAB2_LIB.BASEBOARD_FAB2(SCH_1):PAGE74_I22@CHPSET_LIB.SKX_EXT_B(CHIPS)':
 'VSS'<849>: CDS_PINID='VSS(849)';
NODE_NAME     U2D1 AF33
 '@BASEBOARD_FAB2_LIB.BASEBOARD_FAB2(SCH_1):PAGE74_I22@CHPSET_LIB.SKX_EXT_B(CHIPS)':
 'VSS'<850>: CDS_PINID='VSS(850)';
NODE_NAME     U2D1 AF31
 '@BASEBOARD_FAB2_LIB.BASEBOARD_FAB2(SCH_1):PAGE74_I22@CHPSET_LIB.SKX_EXT_B(CHIPS)':
 'VSS'<851>: CDS_PINID='VSS(851)';
NODE_NAME     U2D1 AF29
 '@BASEBOARD_FAB2_LIB.BASEBOARD_FAB2(SCH_1):PAGE74_I22@CHPSET_LIB.SKX_EXT_B(CHIPS)':
 'VSS'<852>: CDS_PINID='VSS(852)';
NODE_NAME     U2D1 AF27
 '@BASEBOARD_FAB2_LIB.BASEBOARD_FAB2(SCH_1):PAGE74_I22@CHPSET_LIB.SKX_EXT_B(CHIPS)':
 'VSS'<853>: CDS_PINID='VSS(853)';
NODE_NAME     U2D1 AF25
 '@BASEBOARD_FAB2_LIB.BASEBOARD_FAB2(SCH_1):PAGE74_I22@CHPSET_LIB.SKX_EXT_B(CHIPS)':
 'VSS'<854>: CDS_PINID='VSS(854)';
NODE_NAME     U2D1 AF23
 '@BASEBOARD_FAB2_LIB.BASEBOARD_FAB2(SCH_1):PAGE74_I22@CHPSET_LIB.SKX_EXT_B(CHIPS)':
 'VSS'<855>: CDS_PINID='VSS(855)';
NODE_NAME     U2D1 AF21
 '@BASEBOARD_FAB2_LIB.BASEBOARD_FAB2(SCH_1):PAGE74_I22@CHPSET_LIB.SKX_EXT_B(CHIPS)':
 'VSS'<856>: CDS_PINID='VSS(856)';
NODE_NAME     U2D1 AF9
 '@BASEBOARD_FAB2_LIB.BASEBOARD_FAB2(SCH_1):PAGE74_I22@CHPSET_LIB.SKX_EXT_B(CHIPS)':
 'VSS'<857>: CDS_PINID='VSS(857)';
NODE_NAME     U2D1 AC52
 '@BASEBOARD_FAB2_LIB.BASEBOARD_FAB2(SCH_1):PAGE74_I22@CHPSET_LIB.SKX_EXT_B(CHIPS)':
 'VSS'<858>: CDS_PINID='VSS(858)';
NODE_NAME     U2D1 AF1
 '@BASEBOARD_FAB2_LIB.BASEBOARD_FAB2(SCH_1):PAGE74_I22@CHPSET_LIB.SKX_EXT_B(CHIPS)':
 'VSS'<859>: CDS_PINID='VSS(859)';
NODE_NAME     U2D1 AE78
 '@BASEBOARD_FAB2_LIB.BASEBOARD_FAB2(SCH_1):PAGE74_I22@CHPSET_LIB.SKX_EXT_B(CHIPS)':
 'VSS'<860>: CDS_PINID='VSS(860)';
NODE_NAME     U2D1 AE70
 '@BASEBOARD_FAB2_LIB.BASEBOARD_FAB2(SCH_1):PAGE74_I22@CHPSET_LIB.SKX_EXT_B(CHIPS)':
 'VSS'<861>: CDS_PINID='VSS(861)';
NODE_NAME     U2D1 AE68
 '@BASEBOARD_FAB2_LIB.BASEBOARD_FAB2(SCH_1):PAGE74_I22@CHPSET_LIB.SKX_EXT_B(CHIPS)':
 'VSS'<862>: CDS_PINID='VSS(862)';
NODE_NAME     U2D1 AE66
 '@BASEBOARD_FAB2_LIB.BASEBOARD_FAB2(SCH_1):PAGE74_I22@CHPSET_LIB.SKX_EXT_B(CHIPS)':
 'VSS'<863>: CDS_PINID='VSS(863)';
NODE_NAME     U2D1 AE64
 '@BASEBOARD_FAB2_LIB.BASEBOARD_FAB2(SCH_1):PAGE74_I22@CHPSET_LIB.SKX_EXT_B(CHIPS)':
 'VSS'<864>: CDS_PINID='VSS(864)';
NODE_NAME     U2D1 AE42
 '@BASEBOARD_FAB2_LIB.BASEBOARD_FAB2(SCH_1):PAGE74_I22@CHPSET_LIB.SKX_EXT_B(CHIPS)':
 'VSS'<865>: CDS_PINID='VSS(865)';
NODE_NAME     U2D1 AE40
 '@BASEBOARD_FAB2_LIB.BASEBOARD_FAB2(SCH_1):PAGE74_I22@CHPSET_LIB.SKX_EXT_B(CHIPS)':
 'VSS'<866>: CDS_PINID='VSS(866)';
NODE_NAME     U2D1 AE38
 '@BASEBOARD_FAB2_LIB.BASEBOARD_FAB2(SCH_1):PAGE74_I22@CHPSET_LIB.SKX_EXT_B(CHIPS)':
 'VSS'<867>: CDS_PINID='VSS(867)';
NODE_NAME     U2D1 AE16
 '@BASEBOARD_FAB2_LIB.BASEBOARD_FAB2(SCH_1):PAGE74_I22@CHPSET_LIB.SKX_EXT_B(CHIPS)':
 'VSS'<868>: CDS_PINID='VSS(868)';
NODE_NAME     U2D1 AC54
 '@BASEBOARD_FAB2_LIB.BASEBOARD_FAB2(SCH_1):PAGE74_I22@CHPSET_LIB.SKX_EXT_B(CHIPS)':
 'VSS'<869>: CDS_PINID='VSS(869)';
NODE_NAME     U2D1 AE8
 '@BASEBOARD_FAB2_LIB.BASEBOARD_FAB2(SCH_1):PAGE74_I22@CHPSET_LIB.SKX_EXT_B(CHIPS)':
 'VSS'<870>: CDS_PINID='VSS(870)';
NODE_NAME     U2D1 AE4
 '@BASEBOARD_FAB2_LIB.BASEBOARD_FAB2(SCH_1):PAGE74_I22@CHPSET_LIB.SKX_EXT_B(CHIPS)':
 'VSS'<871>: CDS_PINID='VSS(871)';
NODE_NAME     U2D1 AD85
 '@BASEBOARD_FAB2_LIB.BASEBOARD_FAB2(SCH_1):PAGE74_I22@CHPSET_LIB.SKX_EXT_B(CHIPS)':
 'VSS'<872>: CDS_PINID='VSS(872)';
NODE_NAME     U2D1 AD83
 '@BASEBOARD_FAB2_LIB.BASEBOARD_FAB2(SCH_1):PAGE74_I22@CHPSET_LIB.SKX_EXT_B(CHIPS)':
 'VSS'<873>: CDS_PINID='VSS(873)';
NODE_NAME     U2D1 AD81
 '@BASEBOARD_FAB2_LIB.BASEBOARD_FAB2(SCH_1):PAGE74_I22@CHPSET_LIB.SKX_EXT_B(CHIPS)':
 'VSS'<874>: CDS_PINID='VSS(874)';
NODE_NAME     U2D1 AD75
 '@BASEBOARD_FAB2_LIB.BASEBOARD_FAB2(SCH_1):PAGE74_I22@CHPSET_LIB.SKX_EXT_B(CHIPS)':
 'VSS'<875>: CDS_PINID='VSS(875)';
NODE_NAME     U2D1 AD73
 '@BASEBOARD_FAB2_LIB.BASEBOARD_FAB2(SCH_1):PAGE74_I22@CHPSET_LIB.SKX_EXT_B(CHIPS)':
 'VSS'<876>: CDS_PINID='VSS(876)';
NODE_NAME     U2D1 AD71
 '@BASEBOARD_FAB2_LIB.BASEBOARD_FAB2(SCH_1):PAGE74_I22@CHPSET_LIB.SKX_EXT_B(CHIPS)':
 'VSS'<877>: CDS_PINID='VSS(877)';
NODE_NAME     U2D1 AD43
 '@BASEBOARD_FAB2_LIB.BASEBOARD_FAB2(SCH_1):PAGE74_I22@CHPSET_LIB.SKX_EXT_B(CHIPS)':
 'VSS'<878>: CDS_PINID='VSS(878)';
NODE_NAME     U2D1 AD39
 '@BASEBOARD_FAB2_LIB.BASEBOARD_FAB2(SCH_1):PAGE74_I22@CHPSET_LIB.SKX_EXT_B(CHIPS)':
 'VSS'<879>: CDS_PINID='VSS(879)';
NODE_NAME     U2D1 AD33
 '@BASEBOARD_FAB2_LIB.BASEBOARD_FAB2(SCH_1):PAGE74_I22@CHPSET_LIB.SKX_EXT_B(CHIPS)':
 'VSS'<880>: CDS_PINID='VSS(880)';
NODE_NAME     U2D1 AD27
 '@BASEBOARD_FAB2_LIB.BASEBOARD_FAB2(SCH_1):PAGE74_I22@CHPSET_LIB.SKX_EXT_B(CHIPS)':
 'VSS'<881>: CDS_PINID='VSS(881)';
NODE_NAME     U2D1 AD21
 '@BASEBOARD_FAB2_LIB.BASEBOARD_FAB2(SCH_1):PAGE74_I22@CHPSET_LIB.SKX_EXT_B(CHIPS)':
 'VSS'<882>: CDS_PINID='VSS(882)';
NODE_NAME     U2D1 AD19
 '@BASEBOARD_FAB2_LIB.BASEBOARD_FAB2(SCH_1):PAGE74_I22@CHPSET_LIB.SKX_EXT_B(CHIPS)':
 'VSS'<883>: CDS_PINID='VSS(883)';
NODE_NAME     U2D1 AD15
 '@BASEBOARD_FAB2_LIB.BASEBOARD_FAB2(SCH_1):PAGE74_I22@CHPSET_LIB.SKX_EXT_B(CHIPS)':
 'VSS'<884>: CDS_PINID='VSS(884)';
NODE_NAME     U2D1 AD13
 '@BASEBOARD_FAB2_LIB.BASEBOARD_FAB2(SCH_1):PAGE74_I22@CHPSET_LIB.SKX_EXT_B(CHIPS)':
 'VSS'<885>: CDS_PINID='VSS(885)';
NODE_NAME     U2D1 AD11
 '@BASEBOARD_FAB2_LIB.BASEBOARD_FAB2(SCH_1):PAGE74_I22@CHPSET_LIB.SKX_EXT_B(CHIPS)':
 'VSS'<886>: CDS_PINID='VSS(886)';
NODE_NAME     U2D1 AD9
 '@BASEBOARD_FAB2_LIB.BASEBOARD_FAB2(SCH_1):PAGE74_I22@CHPSET_LIB.SKX_EXT_B(CHIPS)':
 'VSS'<887>: CDS_PINID='VSS(887)';
NODE_NAME     U2D1 AD7
 '@BASEBOARD_FAB2_LIB.BASEBOARD_FAB2(SCH_1):PAGE74_I22@CHPSET_LIB.SKX_EXT_B(CHIPS)':
 'VSS'<888>: CDS_PINID='VSS(888)';
NODE_NAME     U2D1 AD3
 '@BASEBOARD_FAB2_LIB.BASEBOARD_FAB2(SCH_1):PAGE74_I22@CHPSET_LIB.SKX_EXT_B(CHIPS)':
 'VSS'<889>: CDS_PINID='VSS(889)';
NODE_NAME     U2D1 AC86
 '@BASEBOARD_FAB2_LIB.BASEBOARD_FAB2(SCH_1):PAGE74_I22@CHPSET_LIB.SKX_EXT_B(CHIPS)':
 'VSS'<890>: CDS_PINID='VSS(890)';
NODE_NAME     U2D1 AC84
 '@BASEBOARD_FAB2_LIB.BASEBOARD_FAB2(SCH_1):PAGE74_I22@CHPSET_LIB.SKX_EXT_B(CHIPS)':
 'VSS'<891>: CDS_PINID='VSS(891)';
NODE_NAME     U2D1 AC78
 '@BASEBOARD_FAB2_LIB.BASEBOARD_FAB2(SCH_1):PAGE74_I22@CHPSET_LIB.SKX_EXT_B(CHIPS)':
 'VSS'<892>: CDS_PINID='VSS(892)';
NODE_NAME     U2D1 AC72
 '@BASEBOARD_FAB2_LIB.BASEBOARD_FAB2(SCH_1):PAGE74_I22@CHPSET_LIB.SKX_EXT_B(CHIPS)':
 'VSS'<893>: CDS_PINID='VSS(893)';
NODE_NAME     U2D1 AC70
 '@BASEBOARD_FAB2_LIB.BASEBOARD_FAB2(SCH_1):PAGE74_I22@CHPSET_LIB.SKX_EXT_B(CHIPS)':
 'VSS'<894>: CDS_PINID='VSS(894)';
NODE_NAME     U2D1 AC64
 '@BASEBOARD_FAB2_LIB.BASEBOARD_FAB2(SCH_1):PAGE74_I22@CHPSET_LIB.SKX_EXT_B(CHIPS)':
 'VSS'<895>: CDS_PINID='VSS(895)';
NODE_NAME     U2D1 AC40
 '@BASEBOARD_FAB2_LIB.BASEBOARD_FAB2(SCH_1):PAGE74_I22@CHPSET_LIB.SKX_EXT_B(CHIPS)':
 'VSS'<896>: CDS_PINID='VSS(896)';
NODE_NAME     U2D1 AC38
 '@BASEBOARD_FAB2_LIB.BASEBOARD_FAB2(SCH_1):PAGE74_I22@CHPSET_LIB.SKX_EXT_B(CHIPS)':
 'VSS'<897>: CDS_PINID='VSS(897)';
NODE_NAME     U2D1 AC34
 '@BASEBOARD_FAB2_LIB.BASEBOARD_FAB2(SCH_1):PAGE74_I22@CHPSET_LIB.SKX_EXT_B(CHIPS)':
 'VSS'<898>: CDS_PINID='VSS(898)';
NODE_NAME     U2D1 AC32
 '@BASEBOARD_FAB2_LIB.BASEBOARD_FAB2(SCH_1):PAGE74_I22@CHPSET_LIB.SKX_EXT_B(CHIPS)':
 'VSS'<899>: CDS_PINID='VSS(899)';
NODE_NAME     U2D1 AC28
 '@BASEBOARD_FAB2_LIB.BASEBOARD_FAB2(SCH_1):PAGE74_I22@CHPSET_LIB.SKX_EXT_B(CHIPS)':
 'VSS'<900>: CDS_PINID='VSS(900)';
NODE_NAME     U2D1 AC26
 '@BASEBOARD_FAB2_LIB.BASEBOARD_FAB2(SCH_1):PAGE74_I22@CHPSET_LIB.SKX_EXT_B(CHIPS)':
 'VSS'<901>: CDS_PINID='VSS(901)';
NODE_NAME     U2D1 AC22
 '@BASEBOARD_FAB2_LIB.BASEBOARD_FAB2(SCH_1):PAGE74_I22@CHPSET_LIB.SKX_EXT_B(CHIPS)':
 'VSS'<902>: CDS_PINID='VSS(902)';
NODE_NAME     U2D1 AC18
 '@BASEBOARD_FAB2_LIB.BASEBOARD_FAB2(SCH_1):PAGE74_I22@CHPSET_LIB.SKX_EXT_B(CHIPS)':
 'VSS'<903>: CDS_PINID='VSS(903)';
NODE_NAME     U2D1 AB85
 '@BASEBOARD_FAB2_LIB.BASEBOARD_FAB2(SCH_1):PAGE74_I22@CHPSET_LIB.SKX_EXT_B(CHIPS)':
 'VSS'<904>: CDS_PINID='VSS(904)';
NODE_NAME     U2D1 AB83
 '@BASEBOARD_FAB2_LIB.BASEBOARD_FAB2(SCH_1):PAGE74_I22@CHPSET_LIB.SKX_EXT_B(CHIPS)':
 'VSS'<905>: CDS_PINID='VSS(905)';
NODE_NAME     U2D1 AB79
 '@BASEBOARD_FAB2_LIB.BASEBOARD_FAB2(SCH_1):PAGE74_I22@CHPSET_LIB.SKX_EXT_B(CHIPS)':
 'VSS'<906>: CDS_PINID='VSS(906)';
NODE_NAME     U2D1 AB73
 '@BASEBOARD_FAB2_LIB.BASEBOARD_FAB2(SCH_1):PAGE74_I22@CHPSET_LIB.SKX_EXT_B(CHIPS)':
 'VSS'<907>: CDS_PINID='VSS(907)';
NODE_NAME     U2D1 AB69
 '@BASEBOARD_FAB2_LIB.BASEBOARD_FAB2(SCH_1):PAGE74_I22@CHPSET_LIB.SKX_EXT_B(CHIPS)':
 'VSS'<908>: CDS_PINID='VSS(908)';
NODE_NAME     U2D1 AB65
 '@BASEBOARD_FAB2_LIB.BASEBOARD_FAB2(SCH_1):PAGE74_I22@CHPSET_LIB.SKX_EXT_B(CHIPS)':
 'VSS'<909>: CDS_PINID='VSS(909)';
NODE_NAME     U2D1 AB41
 '@BASEBOARD_FAB2_LIB.BASEBOARD_FAB2(SCH_1):PAGE74_I22@CHPSET_LIB.SKX_EXT_B(CHIPS)':
 'VSS'<910>: CDS_PINID='VSS(910)';
NODE_NAME     U2D1 AB37
 '@BASEBOARD_FAB2_LIB.BASEBOARD_FAB2(SCH_1):PAGE74_I22@CHPSET_LIB.SKX_EXT_B(CHIPS)':
 'VSS'<911>: CDS_PINID='VSS(911)';
NODE_NAME     U2D1 AB35
 '@BASEBOARD_FAB2_LIB.BASEBOARD_FAB2(SCH_1):PAGE74_I22@CHPSET_LIB.SKX_EXT_B(CHIPS)':
 'VSS'<912>: CDS_PINID='VSS(912)';
NODE_NAME     U2D1 AB31
 '@BASEBOARD_FAB2_LIB.BASEBOARD_FAB2(SCH_1):PAGE74_I22@CHPSET_LIB.SKX_EXT_B(CHIPS)':
 'VSS'<913>: CDS_PINID='VSS(913)';
NODE_NAME     U2D1 AB29
 '@BASEBOARD_FAB2_LIB.BASEBOARD_FAB2(SCH_1):PAGE74_I22@CHPSET_LIB.SKX_EXT_B(CHIPS)':
 'VSS'<914>: CDS_PINID='VSS(914)';
NODE_NAME     U2D1 AB25
 '@BASEBOARD_FAB2_LIB.BASEBOARD_FAB2(SCH_1):PAGE74_I22@CHPSET_LIB.SKX_EXT_B(CHIPS)':
 'VSS'<915>: CDS_PINID='VSS(915)';
NODE_NAME     U2D1 AB23
 '@BASEBOARD_FAB2_LIB.BASEBOARD_FAB2(SCH_1):PAGE74_I22@CHPSET_LIB.SKX_EXT_B(CHIPS)':
 'VSS'<916>: CDS_PINID='VSS(916)';
NODE_NAME     U2D1 AB21
 '@BASEBOARD_FAB2_LIB.BASEBOARD_FAB2(SCH_1):PAGE74_I22@CHPSET_LIB.SKX_EXT_B(CHIPS)':
 'VSS'<917>: CDS_PINID='VSS(917)';
NODE_NAME     U2D1 AB11
 '@BASEBOARD_FAB2_LIB.BASEBOARD_FAB2(SCH_1):PAGE74_I22@CHPSET_LIB.SKX_EXT_B(CHIPS)':
 'VSS'<918>: CDS_PINID='VSS(918)';
NODE_NAME     U2D1 AB5
 '@BASEBOARD_FAB2_LIB.BASEBOARD_FAB2(SCH_1):PAGE74_I22@CHPSET_LIB.SKX_EXT_B(CHIPS)':
 'VSS'<919>: CDS_PINID='VSS(919)';
NODE_NAME     U2D1 AB1
 '@BASEBOARD_FAB2_LIB.BASEBOARD_FAB2(SCH_1):PAGE74_I22@CHPSET_LIB.SKX_EXT_B(CHIPS)':
 'VSS'<920>: CDS_PINID='VSS(920)';
NODE_NAME     U2D1 AA82
 '@BASEBOARD_FAB2_LIB.BASEBOARD_FAB2(SCH_1):PAGE74_I22@CHPSET_LIB.SKX_EXT_B(CHIPS)':
 'VSS'<921>: CDS_PINID='VSS(921)';
NODE_NAME     U2D1 AA80
 '@BASEBOARD_FAB2_LIB.BASEBOARD_FAB2(SCH_1):PAGE74_I22@CHPSET_LIB.SKX_EXT_B(CHIPS)':
 'VSS'<922>: CDS_PINID='VSS(922)';
NODE_NAME     U2D1 AA78
 '@BASEBOARD_FAB2_LIB.BASEBOARD_FAB2(SCH_1):PAGE74_I22@CHPSET_LIB.SKX_EXT_B(CHIPS)':
 'VSS'<923>: CDS_PINID='VSS(923)';
NODE_NAME     U2D1 AA76
 '@BASEBOARD_FAB2_LIB.BASEBOARD_FAB2(SCH_1):PAGE74_I22@CHPSET_LIB.SKX_EXT_B(CHIPS)':
 'VSS'<924>: CDS_PINID='VSS(924)';
NODE_NAME     U2D1 AA68
 '@BASEBOARD_FAB2_LIB.BASEBOARD_FAB2(SCH_1):PAGE74_I22@CHPSET_LIB.SKX_EXT_B(CHIPS)':
 'VSS'<925>: CDS_PINID='VSS(925)';
NODE_NAME     U2D1 AA66
 '@BASEBOARD_FAB2_LIB.BASEBOARD_FAB2(SCH_1):PAGE74_I22@CHPSET_LIB.SKX_EXT_B(CHIPS)':
 'VSS'<926>: CDS_PINID='VSS(926)';
NODE_NAME     U2D1 AA64
 '@BASEBOARD_FAB2_LIB.BASEBOARD_FAB2(SCH_1):PAGE74_I22@CHPSET_LIB.SKX_EXT_B(CHIPS)':
 'VSS'<927>: CDS_PINID='VSS(927)';
NODE_NAME     U2D1 AA42
 '@BASEBOARD_FAB2_LIB.BASEBOARD_FAB2(SCH_1):PAGE74_I22@CHPSET_LIB.SKX_EXT_B(CHIPS)':
 'VSS'<928>: CDS_PINID='VSS(928)';
NODE_NAME     U2D1 AA36
 '@BASEBOARD_FAB2_LIB.BASEBOARD_FAB2(SCH_1):PAGE74_I22@CHPSET_LIB.SKX_EXT_B(CHIPS)':
 'VSS'<929>: CDS_PINID='VSS(929)';
NODE_NAME     U2D1 AA30
 '@BASEBOARD_FAB2_LIB.BASEBOARD_FAB2(SCH_1):PAGE74_I22@CHPSET_LIB.SKX_EXT_B(CHIPS)':
 'VSS'<930>: CDS_PINID='VSS(930)';
NODE_NAME     U2D1 AA24
 '@BASEBOARD_FAB2_LIB.BASEBOARD_FAB2(SCH_1):PAGE74_I22@CHPSET_LIB.SKX_EXT_B(CHIPS)':
 'VSS'<931>: CDS_PINID='VSS(931)';
NODE_NAME     U2D1 AA22
 '@BASEBOARD_FAB2_LIB.BASEBOARD_FAB2(SCH_1):PAGE74_I22@CHPSET_LIB.SKX_EXT_B(CHIPS)':
 'VSS'<932>: CDS_PINID='VSS(932)';
NODE_NAME     U2D1 AA18
 '@BASEBOARD_FAB2_LIB.BASEBOARD_FAB2(SCH_1):PAGE74_I22@CHPSET_LIB.SKX_EXT_B(CHIPS)':
 'VSS'<933>: CDS_PINID='VSS(933)';
NODE_NAME     U2D1 BG72
 '@BASEBOARD_FAB2_LIB.BASEBOARD_FAB2(SCH_1):PAGE74_I23@CHPSET_LIB.SKX_EXT_B(CHIPS)':
 'VSS'<614>: CDS_PINID='VSS(614)';
NODE_NAME     U2D1 BG24
 '@BASEBOARD_FAB2_LIB.BASEBOARD_FAB2(SCH_1):PAGE74_I23@CHPSET_LIB.SKX_EXT_B(CHIPS)':
 'VSS'<615>: CDS_PINID='VSS(615)';
NODE_NAME     U2D1 BG22
 '@BASEBOARD_FAB2_LIB.BASEBOARD_FAB2(SCH_1):PAGE74_I23@CHPSET_LIB.SKX_EXT_B(CHIPS)':
 'VSS'<616>: CDS_PINID='VSS(616)';
NODE_NAME     U2D1 BG10
 '@BASEBOARD_FAB2_LIB.BASEBOARD_FAB2(SCH_1):PAGE74_I23@CHPSET_LIB.SKX_EXT_B(CHIPS)':
 'VSS'<617>: CDS_PINID='VSS(617)';
NODE_NAME     U2D1 BG8
 '@BASEBOARD_FAB2_LIB.BASEBOARD_FAB2(SCH_1):PAGE74_I23@CHPSET_LIB.SKX_EXT_B(CHIPS)':
 'VSS'<618>: CDS_PINID='VSS(618)';
NODE_NAME     U2D1 BG6
 '@BASEBOARD_FAB2_LIB.BASEBOARD_FAB2(SCH_1):PAGE74_I23@CHPSET_LIB.SKX_EXT_B(CHIPS)':
 'VSS'<619>: CDS_PINID='VSS(619)';
NODE_NAME     U2D1 BF71
 '@BASEBOARD_FAB2_LIB.BASEBOARD_FAB2(SCH_1):PAGE74_I23@CHPSET_LIB.SKX_EXT_B(CHIPS)':
 'VSS'<620>: CDS_PINID='VSS(620)';
NODE_NAME     U2D1 BF69
 '@BASEBOARD_FAB2_LIB.BASEBOARD_FAB2(SCH_1):PAGE74_I23@CHPSET_LIB.SKX_EXT_B(CHIPS)':
 'VSS'<621>: CDS_PINID='VSS(621)';
NODE_NAME     U2D1 BF67
 '@BASEBOARD_FAB2_LIB.BASEBOARD_FAB2(SCH_1):PAGE74_I23@CHPSET_LIB.SKX_EXT_B(CHIPS)':
 'VSS'<622>: CDS_PINID='VSS(622)';
NODE_NAME     U2D1 BF65
 '@BASEBOARD_FAB2_LIB.BASEBOARD_FAB2(SCH_1):PAGE74_I23@CHPSET_LIB.SKX_EXT_B(CHIPS)':
 'VSS'<623>: CDS_PINID='VSS(623)';
NODE_NAME     U2D1 BF63
 '@BASEBOARD_FAB2_LIB.BASEBOARD_FAB2(SCH_1):PAGE74_I23@CHPSET_LIB.SKX_EXT_B(CHIPS)':
 'VSS'<624>: CDS_PINID='VSS(624)';
NODE_NAME     U2D1 BF25
 '@BASEBOARD_FAB2_LIB.BASEBOARD_FAB2(SCH_1):PAGE74_I23@CHPSET_LIB.SKX_EXT_B(CHIPS)':
 'VSS'<625>: CDS_PINID='VSS(625)';
NODE_NAME     U2D1 BF19
 '@BASEBOARD_FAB2_LIB.BASEBOARD_FAB2(SCH_1):PAGE74_I23@CHPSET_LIB.SKX_EXT_B(CHIPS)':
 'VSS'<626>: CDS_PINID='VSS(626)';
NODE_NAME     U2D1 BF17
 '@BASEBOARD_FAB2_LIB.BASEBOARD_FAB2(SCH_1):PAGE74_I23@CHPSET_LIB.SKX_EXT_B(CHIPS)':
 'VSS'<627>: CDS_PINID='VSS(627)';
NODE_NAME     U2D1 BF15
 '@BASEBOARD_FAB2_LIB.BASEBOARD_FAB2(SCH_1):PAGE74_I23@CHPSET_LIB.SKX_EXT_B(CHIPS)':
 'VSS'<628>: CDS_PINID='VSS(628)';
NODE_NAME     U2D1 BF9
 '@BASEBOARD_FAB2_LIB.BASEBOARD_FAB2(SCH_1):PAGE74_I23@CHPSET_LIB.SKX_EXT_B(CHIPS)':
 'VSS'<629>: CDS_PINID='VSS(629)';
NODE_NAME     U2D1 BE70
 '@BASEBOARD_FAB2_LIB.BASEBOARD_FAB2(SCH_1):PAGE74_I23@CHPSET_LIB.SKX_EXT_B(CHIPS)':
 'VSS'<630>: CDS_PINID='VSS(630)';
NODE_NAME     U2D1 BE68
 '@BASEBOARD_FAB2_LIB.BASEBOARD_FAB2(SCH_1):PAGE74_I23@CHPSET_LIB.SKX_EXT_B(CHIPS)':
 'VSS'<631>: CDS_PINID='VSS(631)';
NODE_NAME     U2D1 BE66
 '@BASEBOARD_FAB2_LIB.BASEBOARD_FAB2(SCH_1):PAGE74_I23@CHPSET_LIB.SKX_EXT_B(CHIPS)':
 'VSS'<632>: CDS_PINID='VSS(632)';
NODE_NAME     U2D1 BE64
 '@BASEBOARD_FAB2_LIB.BASEBOARD_FAB2(SCH_1):PAGE74_I23@CHPSET_LIB.SKX_EXT_B(CHIPS)':
 'VSS'<633>: CDS_PINID='VSS(633)';
NODE_NAME     U2D1 BE26
 '@BASEBOARD_FAB2_LIB.BASEBOARD_FAB2(SCH_1):PAGE74_I23@CHPSET_LIB.SKX_EXT_B(CHIPS)':
 'VSS'<634>: CDS_PINID='VSS(634)';
NODE_NAME     U2D1 BE10
 '@BASEBOARD_FAB2_LIB.BASEBOARD_FAB2(SCH_1):PAGE74_I23@CHPSET_LIB.SKX_EXT_B(CHIPS)':
 'VSS'<635>: CDS_PINID='VSS(635)';
NODE_NAME     U2D1 BE8
 '@BASEBOARD_FAB2_LIB.BASEBOARD_FAB2(SCH_1):PAGE74_I23@CHPSET_LIB.SKX_EXT_B(CHIPS)':
 'VSS'<636>: CDS_PINID='VSS(636)';
NODE_NAME     U2D1 BE6
 '@BASEBOARD_FAB2_LIB.BASEBOARD_FAB2(SCH_1):PAGE74_I23@CHPSET_LIB.SKX_EXT_B(CHIPS)':
 'VSS'<637>: CDS_PINID='VSS(637)';
NODE_NAME     U2D1 BE4
 '@BASEBOARD_FAB2_LIB.BASEBOARD_FAB2(SCH_1):PAGE74_I23@CHPSET_LIB.SKX_EXT_B(CHIPS)':
 'VSS'<638>: CDS_PINID='VSS(638)';
NODE_NAME     U2D1 BD71
 '@BASEBOARD_FAB2_LIB.BASEBOARD_FAB2(SCH_1):PAGE74_I23@CHPSET_LIB.SKX_EXT_B(CHIPS)':
 'VSS'<639>: CDS_PINID='VSS(639)';
NODE_NAME     U2D1 BD63
 '@BASEBOARD_FAB2_LIB.BASEBOARD_FAB2(SCH_1):PAGE74_I23@CHPSET_LIB.SKX_EXT_B(CHIPS)':
 'VSS'<640>: CDS_PINID='VSS(640)';
NODE_NAME     U2D1 BD27
 '@BASEBOARD_FAB2_LIB.BASEBOARD_FAB2(SCH_1):PAGE74_I23@CHPSET_LIB.SKX_EXT_B(CHIPS)':
 'VSS'<641>: CDS_PINID='VSS(641)';
NODE_NAME     U2D1 BD21
 '@BASEBOARD_FAB2_LIB.BASEBOARD_FAB2(SCH_1):PAGE74_I23@CHPSET_LIB.SKX_EXT_B(CHIPS)':
 'VSS'<642>: CDS_PINID='VSS(642)';
NODE_NAME     U2D1 BD15
 '@BASEBOARD_FAB2_LIB.BASEBOARD_FAB2(SCH_1):PAGE74_I23@CHPSET_LIB.SKX_EXT_B(CHIPS)':
 'VSS'<643>: CDS_PINID='VSS(643)';
NODE_NAME     U2D1 BD11
 '@BASEBOARD_FAB2_LIB.BASEBOARD_FAB2(SCH_1):PAGE74_I23@CHPSET_LIB.SKX_EXT_B(CHIPS)':
 'VSS'<644>: CDS_PINID='VSS(644)';
NODE_NAME     U2D1 BD5
 '@BASEBOARD_FAB2_LIB.BASEBOARD_FAB2(SCH_1):PAGE74_I23@CHPSET_LIB.SKX_EXT_B(CHIPS)':
 'VSS'<645>: CDS_PINID='VSS(645)';
NODE_NAME     U2D1 BC82
 '@BASEBOARD_FAB2_LIB.BASEBOARD_FAB2(SCH_1):PAGE74_I23@CHPSET_LIB.SKX_EXT_B(CHIPS)':
 'VSS'<646>: CDS_PINID='VSS(646)';
NODE_NAME     U2D1 BC80
 '@BASEBOARD_FAB2_LIB.BASEBOARD_FAB2(SCH_1):PAGE74_I23@CHPSET_LIB.SKX_EXT_B(CHIPS)':
 'VSS'<647>: CDS_PINID='VSS(647)';
NODE_NAME     U2D1 BC78
 '@BASEBOARD_FAB2_LIB.BASEBOARD_FAB2(SCH_1):PAGE74_I23@CHPSET_LIB.SKX_EXT_B(CHIPS)':
 'VSS'<648>: CDS_PINID='VSS(648)';
NODE_NAME     U2D1 BC76
 '@BASEBOARD_FAB2_LIB.BASEBOARD_FAB2(SCH_1):PAGE74_I23@CHPSET_LIB.SKX_EXT_B(CHIPS)':
 'VSS'<649>: CDS_PINID='VSS(649)';
NODE_NAME     U2D1 BC74
 '@BASEBOARD_FAB2_LIB.BASEBOARD_FAB2(SCH_1):PAGE74_I23@CHPSET_LIB.SKX_EXT_B(CHIPS)':
 'VSS'<650>: CDS_PINID='VSS(650)';
NODE_NAME     U2D1 BC72
 '@BASEBOARD_FAB2_LIB.BASEBOARD_FAB2(SCH_1):PAGE74_I23@CHPSET_LIB.SKX_EXT_B(CHIPS)':
 'VSS'<651>: CDS_PINID='VSS(651)';
NODE_NAME     U2D1 BC70
 '@BASEBOARD_FAB2_LIB.BASEBOARD_FAB2(SCH_1):PAGE74_I23@CHPSET_LIB.SKX_EXT_B(CHIPS)':
 'VSS'<652>: CDS_PINID='VSS(652)';
NODE_NAME     U2D1 BC16
 '@BASEBOARD_FAB2_LIB.BASEBOARD_FAB2(SCH_1):PAGE74_I23@CHPSET_LIB.SKX_EXT_B(CHIPS)':
 'VSS'<653>: CDS_PINID='VSS(653)';
NODE_NAME     U2D1 BC12
 '@BASEBOARD_FAB2_LIB.BASEBOARD_FAB2(SCH_1):PAGE74_I23@CHPSET_LIB.SKX_EXT_B(CHIPS)':
 'VSS'<654>: CDS_PINID='VSS(654)';
NODE_NAME     U2D1 BC8
 '@BASEBOARD_FAB2_LIB.BASEBOARD_FAB2(SCH_1):PAGE74_I23@CHPSET_LIB.SKX_EXT_B(CHIPS)':
 'VSS'<655>: CDS_PINID='VSS(655)';
NODE_NAME     U2D1 BC4
 '@BASEBOARD_FAB2_LIB.BASEBOARD_FAB2(SCH_1):PAGE74_I23@CHPSET_LIB.SKX_EXT_B(CHIPS)':
 'VSS'<656>: CDS_PINID='VSS(656)';
NODE_NAME     U2D1 BB83
 '@BASEBOARD_FAB2_LIB.BASEBOARD_FAB2(SCH_1):PAGE74_I23@CHPSET_LIB.SKX_EXT_B(CHIPS)':
 'VSS'<657>: CDS_PINID='VSS(657)';
NODE_NAME     U2D1 BB81
 '@BASEBOARD_FAB2_LIB.BASEBOARD_FAB2(SCH_1):PAGE74_I23@CHPSET_LIB.SKX_EXT_B(CHIPS)':
 'VSS'<658>: CDS_PINID='VSS(658)';
NODE_NAME     U2D1 BB79
 '@BASEBOARD_FAB2_LIB.BASEBOARD_FAB2(SCH_1):PAGE74_I23@CHPSET_LIB.SKX_EXT_B(CHIPS)':
 'VSS'<659>: CDS_PINID='VSS(659)';
NODE_NAME     U2D1 BB77
 '@BASEBOARD_FAB2_LIB.BASEBOARD_FAB2(SCH_1):PAGE74_I23@CHPSET_LIB.SKX_EXT_B(CHIPS)':
 'VSS'<660>: CDS_PINID='VSS(660)';
NODE_NAME     U2D1 BB75
 '@BASEBOARD_FAB2_LIB.BASEBOARD_FAB2(SCH_1):PAGE74_I23@CHPSET_LIB.SKX_EXT_B(CHIPS)':
 'VSS'<661>: CDS_PINID='VSS(661)';
NODE_NAME     U2D1 BB73
 '@BASEBOARD_FAB2_LIB.BASEBOARD_FAB2(SCH_1):PAGE74_I23@CHPSET_LIB.SKX_EXT_B(CHIPS)':
 'VSS'<662>: CDS_PINID='VSS(662)';
NODE_NAME     U2D1 BB69
 '@BASEBOARD_FAB2_LIB.BASEBOARD_FAB2(SCH_1):PAGE74_I23@CHPSET_LIB.SKX_EXT_B(CHIPS)':
 'VSS'<663>: CDS_PINID='VSS(663)';
NODE_NAME     U2D1 BB63
 '@BASEBOARD_FAB2_LIB.BASEBOARD_FAB2(SCH_1):PAGE74_I23@CHPSET_LIB.SKX_EXT_B(CHIPS)':
 'VSS'<664>: CDS_PINID='VSS(664)';
NODE_NAME     U2D1 BB23
 '@BASEBOARD_FAB2_LIB.BASEBOARD_FAB2(SCH_1):PAGE74_I23@CHPSET_LIB.SKX_EXT_B(CHIPS)':
 'VSS'<665>: CDS_PINID='VSS(665)';
NODE_NAME     U2D1 BB19
 '@BASEBOARD_FAB2_LIB.BASEBOARD_FAB2(SCH_1):PAGE74_I23@CHPSET_LIB.SKX_EXT_B(CHIPS)':
 'VSS'<666>: CDS_PINID='VSS(666)';
NODE_NAME     U2D1 BA84
 '@BASEBOARD_FAB2_LIB.BASEBOARD_FAB2(SCH_1):PAGE74_I23@CHPSET_LIB.SKX_EXT_B(CHIPS)':
 'VSS'<667>: CDS_PINID='VSS(667)';
NODE_NAME     U2D1 BA80
 '@BASEBOARD_FAB2_LIB.BASEBOARD_FAB2(SCH_1):PAGE74_I23@CHPSET_LIB.SKX_EXT_B(CHIPS)':
 'VSS'<668>: CDS_PINID='VSS(668)';
NODE_NAME     U2D1 BA74
 '@BASEBOARD_FAB2_LIB.BASEBOARD_FAB2(SCH_1):PAGE74_I23@CHPSET_LIB.SKX_EXT_B(CHIPS)':
 'VSS'<669>: CDS_PINID='VSS(669)';
NODE_NAME     U2D1 BA68
 '@BASEBOARD_FAB2_LIB.BASEBOARD_FAB2(SCH_1):PAGE74_I23@CHPSET_LIB.SKX_EXT_B(CHIPS)':
 'VSS'<670>: CDS_PINID='VSS(670)';
NODE_NAME     U2D1 BA62
 '@BASEBOARD_FAB2_LIB.BASEBOARD_FAB2(SCH_1):PAGE74_I23@CHPSET_LIB.SKX_EXT_B(CHIPS)':
 'VSS'<671>: CDS_PINID='VSS(671)';
NODE_NAME     U2D1 BA12
 '@BASEBOARD_FAB2_LIB.BASEBOARD_FAB2(SCH_1):PAGE74_I23@CHPSET_LIB.SKX_EXT_B(CHIPS)':
 'VSS'<672>: CDS_PINID='VSS(672)';
NODE_NAME     U2D1 BA6
 '@BASEBOARD_FAB2_LIB.BASEBOARD_FAB2(SCH_1):PAGE74_I23@CHPSET_LIB.SKX_EXT_B(CHIPS)':
 'VSS'<673>: CDS_PINID='VSS(673)';
NODE_NAME     U2D1 BA2
 '@BASEBOARD_FAB2_LIB.BASEBOARD_FAB2(SCH_1):PAGE74_I23@CHPSET_LIB.SKX_EXT_B(CHIPS)':
 'VSS'<674>: CDS_PINID='VSS(674)';
NODE_NAME     U2D1 AY81
 '@BASEBOARD_FAB2_LIB.BASEBOARD_FAB2(SCH_1):PAGE74_I23@CHPSET_LIB.SKX_EXT_B(CHIPS)':
 'VSS'<675>: CDS_PINID='VSS(675)';
NODE_NAME     U2D1 AY79
 '@BASEBOARD_FAB2_LIB.BASEBOARD_FAB2(SCH_1):PAGE74_I23@CHPSET_LIB.SKX_EXT_B(CHIPS)':
 'VSS'<676>: CDS_PINID='VSS(676)';
NODE_NAME     U2D1 AY63
 '@BASEBOARD_FAB2_LIB.BASEBOARD_FAB2(SCH_1):PAGE74_I23@CHPSET_LIB.SKX_EXT_B(CHIPS)':
 'VSS'<677>: CDS_PINID='VSS(677)';
NODE_NAME     U2D1 AY25
 '@BASEBOARD_FAB2_LIB.BASEBOARD_FAB2(SCH_1):PAGE74_I23@CHPSET_LIB.SKX_EXT_B(CHIPS)':
 'VSS'<678>: CDS_PINID='VSS(678)';
NODE_NAME     U2D1 AY23
 '@BASEBOARD_FAB2_LIB.BASEBOARD_FAB2(SCH_1):PAGE74_I23@CHPSET_LIB.SKX_EXT_B(CHIPS)':
 'VSS'<679>: CDS_PINID='VSS(679)';
NODE_NAME     U2D1 AY21
 '@BASEBOARD_FAB2_LIB.BASEBOARD_FAB2(SCH_1):PAGE74_I23@CHPSET_LIB.SKX_EXT_B(CHIPS)':
 'VSS'<680>: CDS_PINID='VSS(680)';
NODE_NAME     U2D1 AY17
 '@BASEBOARD_FAB2_LIB.BASEBOARD_FAB2(SCH_1):PAGE74_I23@CHPSET_LIB.SKX_EXT_B(CHIPS)':
 'VSS'<681>: CDS_PINID='VSS(681)';
NODE_NAME     U2D1 AY15
 '@BASEBOARD_FAB2_LIB.BASEBOARD_FAB2(SCH_1):PAGE74_I23@CHPSET_LIB.SKX_EXT_B(CHIPS)':
 'VSS'<682>: CDS_PINID='VSS(682)';
NODE_NAME     U2D1 AY5
 '@BASEBOARD_FAB2_LIB.BASEBOARD_FAB2(SCH_1):PAGE74_I23@CHPSET_LIB.SKX_EXT_B(CHIPS)':
 'VSS'<683>: CDS_PINID='VSS(683)';
NODE_NAME     U2D1 AW84
 '@BASEBOARD_FAB2_LIB.BASEBOARD_FAB2(SCH_1):PAGE74_I23@CHPSET_LIB.SKX_EXT_B(CHIPS)':
 'VSS'<684>: CDS_PINID='VSS(684)';
NODE_NAME     U2D1 AW82
 '@BASEBOARD_FAB2_LIB.BASEBOARD_FAB2(SCH_1):PAGE74_I23@CHPSET_LIB.SKX_EXT_B(CHIPS)':
 'VSS'<685>: CDS_PINID='VSS(685)';
NODE_NAME     U2D1 AW78
 '@BASEBOARD_FAB2_LIB.BASEBOARD_FAB2(SCH_1):PAGE74_I23@CHPSET_LIB.SKX_EXT_B(CHIPS)':
 'VSS'<686>: CDS_PINID='VSS(686)';
NODE_NAME     U2D1 AW74
 '@BASEBOARD_FAB2_LIB.BASEBOARD_FAB2(SCH_1):PAGE74_I23@CHPSET_LIB.SKX_EXT_B(CHIPS)':
 'VSS'<687>: CDS_PINID='VSS(687)';
NODE_NAME     U2D1 AW72
 '@BASEBOARD_FAB2_LIB.BASEBOARD_FAB2(SCH_1):PAGE74_I23@CHPSET_LIB.SKX_EXT_B(CHIPS)':
 'VSS'<688>: CDS_PINID='VSS(688)';
NODE_NAME     U2D1 AW70
 '@BASEBOARD_FAB2_LIB.BASEBOARD_FAB2(SCH_1):PAGE74_I23@CHPSET_LIB.SKX_EXT_B(CHIPS)':
 'VSS'<689>: CDS_PINID='VSS(689)';
NODE_NAME     U2D1 AW68
 '@BASEBOARD_FAB2_LIB.BASEBOARD_FAB2(SCH_1):PAGE74_I23@CHPSET_LIB.SKX_EXT_B(CHIPS)':
 'VSS'<690>: CDS_PINID='VSS(690)';
NODE_NAME     U2D1 AW66
 '@BASEBOARD_FAB2_LIB.BASEBOARD_FAB2(SCH_1):PAGE74_I23@CHPSET_LIB.SKX_EXT_B(CHIPS)':
 'VSS'<691>: CDS_PINID='VSS(691)';
NODE_NAME     U2D1 AW62
 '@BASEBOARD_FAB2_LIB.BASEBOARD_FAB2(SCH_1):PAGE74_I23@CHPSET_LIB.SKX_EXT_B(CHIPS)':
 'VSS'<692>: CDS_PINID='VSS(692)';
NODE_NAME     U2D1 AW10
 '@BASEBOARD_FAB2_LIB.BASEBOARD_FAB2(SCH_1):PAGE74_I23@CHPSET_LIB.SKX_EXT_B(CHIPS)':
 'VSS'<693>: CDS_PINID='VSS(693)';
NODE_NAME     U2D1 AW2
 '@BASEBOARD_FAB2_LIB.BASEBOARD_FAB2(SCH_1):PAGE74_I23@CHPSET_LIB.SKX_EXT_B(CHIPS)':
 'VSS'<694>: CDS_PINID='VSS(694)';
NODE_NAME     U2D1 AV83
 '@BASEBOARD_FAB2_LIB.BASEBOARD_FAB2(SCH_1):PAGE74_I23@CHPSET_LIB.SKX_EXT_B(CHIPS)':
 'VSS'<695>: CDS_PINID='VSS(695)';
NODE_NAME     U2D1 AV75
 '@BASEBOARD_FAB2_LIB.BASEBOARD_FAB2(SCH_1):PAGE74_I23@CHPSET_LIB.SKX_EXT_B(CHIPS)':
 'VSS'<696>: CDS_PINID='VSS(696)';
NODE_NAME     U2D1 AV67
 '@BASEBOARD_FAB2_LIB.BASEBOARD_FAB2(SCH_1):PAGE74_I23@CHPSET_LIB.SKX_EXT_B(CHIPS)':
 'VSS'<697>: CDS_PINID='VSS(697)';
NODE_NAME     U2D1 AV65
 '@BASEBOARD_FAB2_LIB.BASEBOARD_FAB2(SCH_1):PAGE74_I23@CHPSET_LIB.SKX_EXT_B(CHIPS)':
 'VSS'<698>: CDS_PINID='VSS(698)';
NODE_NAME     U2D1 AV63
 '@BASEBOARD_FAB2_LIB.BASEBOARD_FAB2(SCH_1):PAGE74_I23@CHPSET_LIB.SKX_EXT_B(CHIPS)':
 'VSS'<699>: CDS_PINID='VSS(699)';
NODE_NAME     U2D1 AV25
 '@BASEBOARD_FAB2_LIB.BASEBOARD_FAB2(SCH_1):PAGE74_I23@CHPSET_LIB.SKX_EXT_B(CHIPS)':
 'VSS'<700>: CDS_PINID='VSS(700)';
NODE_NAME     U2D1 AV23
 '@BASEBOARD_FAB2_LIB.BASEBOARD_FAB2(SCH_1):PAGE74_I23@CHPSET_LIB.SKX_EXT_B(CHIPS)':
 'VSS'<701>: CDS_PINID='VSS(701)';
NODE_NAME     U2D1 AV19
 '@BASEBOARD_FAB2_LIB.BASEBOARD_FAB2(SCH_1):PAGE74_I23@CHPSET_LIB.SKX_EXT_B(CHIPS)':
 'VSS'<702>: CDS_PINID='VSS(702)';
NODE_NAME     U2D1 AV13
 '@BASEBOARD_FAB2_LIB.BASEBOARD_FAB2(SCH_1):PAGE74_I23@CHPSET_LIB.SKX_EXT_B(CHIPS)':
 'VSS'<703>: CDS_PINID='VSS(703)';
NODE_NAME     U2D1 AV11
 '@BASEBOARD_FAB2_LIB.BASEBOARD_FAB2(SCH_1):PAGE74_I23@CHPSET_LIB.SKX_EXT_B(CHIPS)':
 'VSS'<704>: CDS_PINID='VSS(704)';
NODE_NAME     U2D1 AV7
 '@BASEBOARD_FAB2_LIB.BASEBOARD_FAB2(SCH_1):PAGE74_I23@CHPSET_LIB.SKX_EXT_B(CHIPS)':
 'VSS'<705>: CDS_PINID='VSS(705)';
NODE_NAME     U2D1 AV3
 '@BASEBOARD_FAB2_LIB.BASEBOARD_FAB2(SCH_1):PAGE74_I23@CHPSET_LIB.SKX_EXT_B(CHIPS)':
 'VSS'<706>: CDS_PINID='VSS(706)';
NODE_NAME     U2D1 AV1
 '@BASEBOARD_FAB2_LIB.BASEBOARD_FAB2(SCH_1):PAGE74_I23@CHPSET_LIB.SKX_EXT_B(CHIPS)':
 'VSS'<707>: CDS_PINID='VSS(707)';
NODE_NAME     U2D1 AU86
 '@BASEBOARD_FAB2_LIB.BASEBOARD_FAB2(SCH_1):PAGE74_I23@CHPSET_LIB.SKX_EXT_B(CHIPS)':
 'VSS'<708>: CDS_PINID='VSS(708)';
NODE_NAME     U2D1 AU84
 '@BASEBOARD_FAB2_LIB.BASEBOARD_FAB2(SCH_1):PAGE74_I23@CHPSET_LIB.SKX_EXT_B(CHIPS)':
 'VSS'<709>: CDS_PINID='VSS(709)';
NODE_NAME     U2D1 AU80
 '@BASEBOARD_FAB2_LIB.BASEBOARD_FAB2(SCH_1):PAGE74_I23@CHPSET_LIB.SKX_EXT_B(CHIPS)':
 'VSS'<710>: CDS_PINID='VSS(710)';
NODE_NAME     U2D1 AU78
 '@BASEBOARD_FAB2_LIB.BASEBOARD_FAB2(SCH_1):PAGE74_I23@CHPSET_LIB.SKX_EXT_B(CHIPS)':
 'VSS'<711>: CDS_PINID='VSS(711)';
NODE_NAME     U2D1 AU76
 '@BASEBOARD_FAB2_LIB.BASEBOARD_FAB2(SCH_1):PAGE74_I23@CHPSET_LIB.SKX_EXT_B(CHIPS)':
 'VSS'<712>: CDS_PINID='VSS(712)';
NODE_NAME     U2D1 AU74
 '@BASEBOARD_FAB2_LIB.BASEBOARD_FAB2(SCH_1):PAGE74_I23@CHPSET_LIB.SKX_EXT_B(CHIPS)':
 'VSS'<713>: CDS_PINID='VSS(713)';
NODE_NAME     U2D1 AU68
 '@BASEBOARD_FAB2_LIB.BASEBOARD_FAB2(SCH_1):PAGE74_I23@CHPSET_LIB.SKX_EXT_B(CHIPS)':
 'VSS'<714>: CDS_PINID='VSS(714)';
NODE_NAME     U2D1 AU64
 '@BASEBOARD_FAB2_LIB.BASEBOARD_FAB2(SCH_1):PAGE74_I23@CHPSET_LIB.SKX_EXT_B(CHIPS)':
 'VSS'<715>: CDS_PINID='VSS(715)';
NODE_NAME     U2D1 AU62
 '@BASEBOARD_FAB2_LIB.BASEBOARD_FAB2(SCH_1):PAGE74_I23@CHPSET_LIB.SKX_EXT_B(CHIPS)':
 'VSS'<716>: CDS_PINID='VSS(716)';
NODE_NAME     U2D1 AU28
 '@BASEBOARD_FAB2_LIB.BASEBOARD_FAB2(SCH_1):PAGE74_I23@CHPSET_LIB.SKX_EXT_B(CHIPS)':
 'VSS'<717>: CDS_PINID='VSS(717)';
NODE_NAME     U2D1 AU26
 '@BASEBOARD_FAB2_LIB.BASEBOARD_FAB2(SCH_1):PAGE74_I23@CHPSET_LIB.SKX_EXT_B(CHIPS)':
 'VSS'<718>: CDS_PINID='VSS(718)';
NODE_NAME     U2D1 AU6
 '@BASEBOARD_FAB2_LIB.BASEBOARD_FAB2(SCH_1):PAGE74_I23@CHPSET_LIB.SKX_EXT_B(CHIPS)':
 'VSS'<719>: CDS_PINID='VSS(719)';
NODE_NAME     U2D1 AU2
 '@BASEBOARD_FAB2_LIB.BASEBOARD_FAB2(SCH_1):PAGE74_I23@CHPSET_LIB.SKX_EXT_B(CHIPS)':
 'VSS'<720>: CDS_PINID='VSS(720)';
NODE_NAME     U2D1 AT85
 '@BASEBOARD_FAB2_LIB.BASEBOARD_FAB2(SCH_1):PAGE74_I23@CHPSET_LIB.SKX_EXT_B(CHIPS)':
 'VSS'<721>: CDS_PINID='VSS(721)';
NODE_NAME     U2D1 AT83
 '@BASEBOARD_FAB2_LIB.BASEBOARD_FAB2(SCH_1):PAGE74_I23@CHPSET_LIB.SKX_EXT_B(CHIPS)':
 'VSS'<722>: CDS_PINID='VSS(722)';
NODE_NAME     U2D1 AT77
 '@BASEBOARD_FAB2_LIB.BASEBOARD_FAB2(SCH_1):PAGE74_I23@CHPSET_LIB.SKX_EXT_B(CHIPS)':
 'VSS'<723>: CDS_PINID='VSS(723)';
NODE_NAME     U2D1 AT73
 '@BASEBOARD_FAB2_LIB.BASEBOARD_FAB2(SCH_1):PAGE74_I23@CHPSET_LIB.SKX_EXT_B(CHIPS)':
 'VSS'<724>: CDS_PINID='VSS(724)';
NODE_NAME     U2D1 AT69
 '@BASEBOARD_FAB2_LIB.BASEBOARD_FAB2(SCH_1):PAGE74_I23@CHPSET_LIB.SKX_EXT_B(CHIPS)':
 'VSS'<725>: CDS_PINID='VSS(725)';
NODE_NAME     U2D1 AT63
 '@BASEBOARD_FAB2_LIB.BASEBOARD_FAB2(SCH_1):PAGE74_I23@CHPSET_LIB.SKX_EXT_B(CHIPS)':
 'VSS'<726>: CDS_PINID='VSS(726)';
NODE_NAME     U2D1 AT61
 '@BASEBOARD_FAB2_LIB.BASEBOARD_FAB2(SCH_1):PAGE74_I23@CHPSET_LIB.SKX_EXT_B(CHIPS)':
 'VSS'<727>: CDS_PINID='VSS(727)';
NODE_NAME     U2D1 AT27
 '@BASEBOARD_FAB2_LIB.BASEBOARD_FAB2(SCH_1):PAGE74_I23@CHPSET_LIB.SKX_EXT_B(CHIPS)':
 'VSS'<728>: CDS_PINID='VSS(728)';
NODE_NAME     U2D1 AT21
 '@BASEBOARD_FAB2_LIB.BASEBOARD_FAB2(SCH_1):PAGE74_I23@CHPSET_LIB.SKX_EXT_B(CHIPS)':
 'VSS'<729>: CDS_PINID='VSS(729)';
NODE_NAME     U2D1 AT17
 '@BASEBOARD_FAB2_LIB.BASEBOARD_FAB2(SCH_1):PAGE74_I23@CHPSET_LIB.SKX_EXT_B(CHIPS)':
 'VSS'<730>: CDS_PINID='VSS(730)';
NODE_NAME     U2D1 AT15
 '@BASEBOARD_FAB2_LIB.BASEBOARD_FAB2(SCH_1):PAGE74_I23@CHPSET_LIB.SKX_EXT_B(CHIPS)':
 'VSS'<731>: CDS_PINID='VSS(731)';
NODE_NAME     U2D1 P63
 '@BASEBOARD_FAB2_LIB.BASEBOARD_FAB2(SCH_1):PAGE74_I23@CHPSET_LIB.SKX_EXT_B(CHIPS)':
 'VSS'<732>: CDS_PINID='VSS(732)';
NODE_NAME     U2D1 AC48
 '@BASEBOARD_FAB2_LIB.BASEBOARD_FAB2(SCH_1):PAGE74_I23@CHPSET_LIB.SKX_EXT_B(CHIPS)':
 'VSS'<733>: CDS_PINID='VSS(733)';
NODE_NAME     U2D1 AR78
 '@BASEBOARD_FAB2_LIB.BASEBOARD_FAB2(SCH_1):PAGE74_I23@CHPSET_LIB.SKX_EXT_B(CHIPS)':
 'VSS'<734>: CDS_PINID='VSS(734)';
NODE_NAME     U2D1 AR72
 '@BASEBOARD_FAB2_LIB.BASEBOARD_FAB2(SCH_1):PAGE74_I23@CHPSET_LIB.SKX_EXT_B(CHIPS)':
 'VSS'<735>: CDS_PINID='VSS(735)';
NODE_NAME     U2D1 AR60
 '@BASEBOARD_FAB2_LIB.BASEBOARD_FAB2(SCH_1):PAGE74_I23@CHPSET_LIB.SKX_EXT_B(CHIPS)':
 'VSS'<736>: CDS_PINID='VSS(736)';
NODE_NAME     U2D1 AR30
 '@BASEBOARD_FAB2_LIB.BASEBOARD_FAB2(SCH_1):PAGE74_I23@CHPSET_LIB.SKX_EXT_B(CHIPS)':
 'VSS'<737>: CDS_PINID='VSS(737)';
NODE_NAME     U2D1 AR24
 '@BASEBOARD_FAB2_LIB.BASEBOARD_FAB2(SCH_1):PAGE74_I23@CHPSET_LIB.SKX_EXT_B(CHIPS)':
 'VSS'<738>: CDS_PINID='VSS(738)';
NODE_NAME     U2D1 AR10
 '@BASEBOARD_FAB2_LIB.BASEBOARD_FAB2(SCH_1):PAGE74_I23@CHPSET_LIB.SKX_EXT_B(CHIPS)':
 'VSS'<739>: CDS_PINID='VSS(739)';
NODE_NAME     U2D1 AP85
 '@BASEBOARD_FAB2_LIB.BASEBOARD_FAB2(SCH_1):PAGE74_I23@CHPSET_LIB.SKX_EXT_B(CHIPS)':
 'VSS'<740>: CDS_PINID='VSS(740)';
NODE_NAME     U2D1 AP83
 '@BASEBOARD_FAB2_LIB.BASEBOARD_FAB2(SCH_1):PAGE74_I23@CHPSET_LIB.SKX_EXT_B(CHIPS)':
 'VSS'<741>: CDS_PINID='VSS(741)';
NODE_NAME     U2D1 AP81
 '@BASEBOARD_FAB2_LIB.BASEBOARD_FAB2(SCH_1):PAGE74_I23@CHPSET_LIB.SKX_EXT_B(CHIPS)':
 'VSS'<742>: CDS_PINID='VSS(742)';
NODE_NAME     U2D1 AP75
 '@BASEBOARD_FAB2_LIB.BASEBOARD_FAB2(SCH_1):PAGE74_I23@CHPSET_LIB.SKX_EXT_B(CHIPS)':
 'VSS'<743>: CDS_PINID='VSS(743)';
NODE_NAME     U2D1 AP73
 '@BASEBOARD_FAB2_LIB.BASEBOARD_FAB2(SCH_1):PAGE74_I23@CHPSET_LIB.SKX_EXT_B(CHIPS)':
 'VSS'<744>: CDS_PINID='VSS(744)';
NODE_NAME     U2D1 AP69
 '@BASEBOARD_FAB2_LIB.BASEBOARD_FAB2(SCH_1):PAGE74_I23@CHPSET_LIB.SKX_EXT_B(CHIPS)':
 'VSS'<745>: CDS_PINID='VSS(745)';
NODE_NAME     U2D1 AP67
 '@BASEBOARD_FAB2_LIB.BASEBOARD_FAB2(SCH_1):PAGE74_I23@CHPSET_LIB.SKX_EXT_B(CHIPS)':
 'VSS'<746>: CDS_PINID='VSS(746)';
NODE_NAME     U2D1 AP65
 '@BASEBOARD_FAB2_LIB.BASEBOARD_FAB2(SCH_1):PAGE74_I23@CHPSET_LIB.SKX_EXT_B(CHIPS)':
 'VSS'<747>: CDS_PINID='VSS(747)';
NODE_NAME     U2D1 AP63
 '@BASEBOARD_FAB2_LIB.BASEBOARD_FAB2(SCH_1):PAGE74_I23@CHPSET_LIB.SKX_EXT_B(CHIPS)':
 'VSS'<748>: CDS_PINID='VSS(748)';
NODE_NAME     U2D1 AP59
 '@BASEBOARD_FAB2_LIB.BASEBOARD_FAB2(SCH_1):PAGE74_I23@CHPSET_LIB.SKX_EXT_B(CHIPS)':
 'VSS'<749>: CDS_PINID='VSS(749)';
NODE_NAME     U2D1 AP31
 '@BASEBOARD_FAB2_LIB.BASEBOARD_FAB2(SCH_1):PAGE74_I23@CHPSET_LIB.SKX_EXT_B(CHIPS)':
 'VSS'<750>: CDS_PINID='VSS(750)';
NODE_NAME     U2D1 AP19
 '@BASEBOARD_FAB2_LIB.BASEBOARD_FAB2(SCH_1):PAGE74_I23@CHPSET_LIB.SKX_EXT_B(CHIPS)':
 'VSS'<751>: CDS_PINID='VSS(751)';
NODE_NAME     U2D1 AP13
 '@BASEBOARD_FAB2_LIB.BASEBOARD_FAB2(SCH_1):PAGE74_I23@CHPSET_LIB.SKX_EXT_B(CHIPS)':
 'VSS'<752>: CDS_PINID='VSS(752)';
NODE_NAME     U2D1 AP9
 '@BASEBOARD_FAB2_LIB.BASEBOARD_FAB2(SCH_1):PAGE74_I23@CHPSET_LIB.SKX_EXT_B(CHIPS)':
 'VSS'<753>: CDS_PINID='VSS(753)';
NODE_NAME     U2D1 AP5
 '@BASEBOARD_FAB2_LIB.BASEBOARD_FAB2(SCH_1):PAGE74_I23@CHPSET_LIB.SKX_EXT_B(CHIPS)':
 'VSS'<754>: CDS_PINID='VSS(754)';
NODE_NAME     U2D1 AN78
 '@BASEBOARD_FAB2_LIB.BASEBOARD_FAB2(SCH_1):PAGE74_I23@CHPSET_LIB.SKX_EXT_B(CHIPS)':
 'VSS'<755>: CDS_PINID='VSS(755)';
NODE_NAME     U2D1 AN58
 '@BASEBOARD_FAB2_LIB.BASEBOARD_FAB2(SCH_1):PAGE74_I23@CHPSET_LIB.SKX_EXT_B(CHIPS)':
 'VSS'<756>: CDS_PINID='VSS(756)';
NODE_NAME     U2D1 AN28
 '@BASEBOARD_FAB2_LIB.BASEBOARD_FAB2(SCH_1):PAGE74_I23@CHPSET_LIB.SKX_EXT_B(CHIPS)':
 'VSS'<757>: CDS_PINID='VSS(757)';
NODE_NAME     U2D1 AN6
 '@BASEBOARD_FAB2_LIB.BASEBOARD_FAB2(SCH_1):PAGE74_I23@CHPSET_LIB.SKX_EXT_B(CHIPS)':
 'VSS'<758>: CDS_PINID='VSS(758)';
NODE_NAME     U2D1 AN2
 '@BASEBOARD_FAB2_LIB.BASEBOARD_FAB2(SCH_1):PAGE74_I23@CHPSET_LIB.SKX_EXT_B(CHIPS)':
 'VSS'<759>: CDS_PINID='VSS(759)';
NODE_NAME     U2D1 AM83
 '@BASEBOARD_FAB2_LIB.BASEBOARD_FAB2(SCH_1):PAGE74_I23@CHPSET_LIB.SKX_EXT_B(CHIPS)':
 'VSS'<760>: CDS_PINID='VSS(760)';
NODE_NAME     U2D1 AM79
 '@BASEBOARD_FAB2_LIB.BASEBOARD_FAB2(SCH_1):PAGE74_I23@CHPSET_LIB.SKX_EXT_B(CHIPS)':
 'VSS'<761>: CDS_PINID='VSS(761)';
NODE_NAME     U2D1 AM73
 '@BASEBOARD_FAB2_LIB.BASEBOARD_FAB2(SCH_1):PAGE74_I23@CHPSET_LIB.SKX_EXT_B(CHIPS)':
 'VSS'<762>: CDS_PINID='VSS(762)';
NODE_NAME     U2D1 AM69
 '@BASEBOARD_FAB2_LIB.BASEBOARD_FAB2(SCH_1):PAGE74_I23@CHPSET_LIB.SKX_EXT_B(CHIPS)':
 'VSS'<763>: CDS_PINID='VSS(763)';
NODE_NAME     U2D1 AM63
 '@BASEBOARD_FAB2_LIB.BASEBOARD_FAB2(SCH_1):PAGE74_I23@CHPSET_LIB.SKX_EXT_B(CHIPS)':
 'VSS'<764>: CDS_PINID='VSS(764)';
NODE_NAME     U2D1 AM57
 '@BASEBOARD_FAB2_LIB.BASEBOARD_FAB2(SCH_1):PAGE74_I23@CHPSET_LIB.SKX_EXT_B(CHIPS)':
 'VSS'<765>: CDS_PINID='VSS(765)';
NODE_NAME     U2D1 AM31
 '@BASEBOARD_FAB2_LIB.BASEBOARD_FAB2(SCH_1):PAGE74_I23@CHPSET_LIB.SKX_EXT_B(CHIPS)':
 'VSS'<766>: CDS_PINID='VSS(766)';
NODE_NAME     U2D1 AC50
 '@BASEBOARD_FAB2_LIB.BASEBOARD_FAB2(SCH_1):PAGE74_I23@CHPSET_LIB.SKX_EXT_B(CHIPS)':
 'VSS'<767>: CDS_PINID='VSS(767)';
NODE_NAME     U2D1 AM1
 '@BASEBOARD_FAB2_LIB.BASEBOARD_FAB2(SCH_1):PAGE74_I23@CHPSET_LIB.SKX_EXT_B(CHIPS)':
 'VSS'<768>: CDS_PINID='VSS(768)';
NODE_NAME     U2D1 AL86
 '@BASEBOARD_FAB2_LIB.BASEBOARD_FAB2(SCH_1):PAGE74_I23@CHPSET_LIB.SKX_EXT_B(CHIPS)':
 'VSS'<769>: CDS_PINID='VSS(769)';
NODE_NAME     U2D1 AL82
 '@BASEBOARD_FAB2_LIB.BASEBOARD_FAB2(SCH_1):PAGE74_I23@CHPSET_LIB.SKX_EXT_B(CHIPS)':
 'VSS'<770>: CDS_PINID='VSS(770)';
NODE_NAME     U2D1 AL80
 '@BASEBOARD_FAB2_LIB.BASEBOARD_FAB2(SCH_1):PAGE74_I23@CHPSET_LIB.SKX_EXT_B(CHIPS)':
 'VSS'<771>: CDS_PINID='VSS(771)';
NODE_NAME     U2D1 AL78
 '@BASEBOARD_FAB2_LIB.BASEBOARD_FAB2(SCH_1):PAGE74_I23@CHPSET_LIB.SKX_EXT_B(CHIPS)':
 'VSS'<772>: CDS_PINID='VSS(772)';
NODE_NAME     U2D1 AL76
 '@BASEBOARD_FAB2_LIB.BASEBOARD_FAB2(SCH_1):PAGE74_I23@CHPSET_LIB.SKX_EXT_B(CHIPS)':
 'VSS'<773>: CDS_PINID='VSS(773)';
NODE_NAME     U2D1 P49
 '@BASEBOARD_FAB2_LIB.BASEBOARD_FAB2(SCH_1):PAGE75_I17@CHPSET_LIB.SKX_EXT_B(CHIPS)':
 'VSS'<454>: CDS_PINID='VSS(454)';
NODE_NAME     U2D1 CJ12
 '@BASEBOARD_FAB2_LIB.BASEBOARD_FAB2(SCH_1):PAGE75_I17@CHPSET_LIB.SKX_EXT_B(CHIPS)':
 'VSS'<455>: CDS_PINID='VSS(455)';
NODE_NAME     U2D1 CJ10
 '@BASEBOARD_FAB2_LIB.BASEBOARD_FAB2(SCH_1):PAGE75_I17@CHPSET_LIB.SKX_EXT_B(CHIPS)':
 'VSS'<456>: CDS_PINID='VSS(456)';
NODE_NAME     U2D1 CJ8
 '@BASEBOARD_FAB2_LIB.BASEBOARD_FAB2(SCH_1):PAGE75_I17@CHPSET_LIB.SKX_EXT_B(CHIPS)':
 'VSS'<457>: CDS_PINID='VSS(457)';
NODE_NAME     U2D1 CJ6
 '@BASEBOARD_FAB2_LIB.BASEBOARD_FAB2(SCH_1):PAGE75_I17@CHPSET_LIB.SKX_EXT_B(CHIPS)':
 'VSS'<458>: CDS_PINID='VSS(458)';
NODE_NAME     U2D1 CJ2
 '@BASEBOARD_FAB2_LIB.BASEBOARD_FAB2(SCH_1):PAGE75_I17@CHPSET_LIB.SKX_EXT_B(CHIPS)':
 'VSS'<459>: CDS_PINID='VSS(459)';
NODE_NAME     U2D1 CH83
 '@BASEBOARD_FAB2_LIB.BASEBOARD_FAB2(SCH_1):PAGE75_I17@CHPSET_LIB.SKX_EXT_B(CHIPS)':
 'VSS'<460>: CDS_PINID='VSS(460)';
NODE_NAME     U2D1 CH81
 '@BASEBOARD_FAB2_LIB.BASEBOARD_FAB2(SCH_1):PAGE75_I17@CHPSET_LIB.SKX_EXT_B(CHIPS)':
 'VSS'<461>: CDS_PINID='VSS(461)';
NODE_NAME     U2D1 CH79
 '@BASEBOARD_FAB2_LIB.BASEBOARD_FAB2(SCH_1):PAGE75_I17@CHPSET_LIB.SKX_EXT_B(CHIPS)':
 'VSS'<462>: CDS_PINID='VSS(462)';
NODE_NAME     U2D1 CH73
 '@BASEBOARD_FAB2_LIB.BASEBOARD_FAB2(SCH_1):PAGE75_I17@CHPSET_LIB.SKX_EXT_B(CHIPS)':
 'VSS'<463>: CDS_PINID='VSS(463)';
NODE_NAME     U2D1 CH67
 '@BASEBOARD_FAB2_LIB.BASEBOARD_FAB2(SCH_1):PAGE75_I17@CHPSET_LIB.SKX_EXT_B(CHIPS)':
 'VSS'<464>: CDS_PINID='VSS(464)';
NODE_NAME     U2D1 CH63
 '@BASEBOARD_FAB2_LIB.BASEBOARD_FAB2(SCH_1):PAGE75_I17@CHPSET_LIB.SKX_EXT_B(CHIPS)':
 'VSS'<465>: CDS_PINID='VSS(465)';
NODE_NAME     U2D1 CH19
 '@BASEBOARD_FAB2_LIB.BASEBOARD_FAB2(SCH_1):PAGE75_I17@CHPSET_LIB.SKX_EXT_B(CHIPS)':
 'VSS'<466>: CDS_PINID='VSS(466)';
NODE_NAME     U2D1 CH15
 '@BASEBOARD_FAB2_LIB.BASEBOARD_FAB2(SCH_1):PAGE75_I17@CHPSET_LIB.SKX_EXT_B(CHIPS)':
 'VSS'<467>: CDS_PINID='VSS(467)';
NODE_NAME     U2D1 CH3
 '@BASEBOARD_FAB2_LIB.BASEBOARD_FAB2(SCH_1):PAGE75_I17@CHPSET_LIB.SKX_EXT_B(CHIPS)':
 'VSS'<468>: CDS_PINID='VSS(468)';
NODE_NAME     U2D1 CH1
 '@BASEBOARD_FAB2_LIB.BASEBOARD_FAB2(SCH_1):PAGE75_I17@CHPSET_LIB.SKX_EXT_B(CHIPS)':
 'VSS'<469>: CDS_PINID='VSS(469)';
NODE_NAME     U2D1 CG80
 '@BASEBOARD_FAB2_LIB.BASEBOARD_FAB2(SCH_1):PAGE75_I17@CHPSET_LIB.SKX_EXT_B(CHIPS)':
 'VSS'<470>: CDS_PINID='VSS(470)';
NODE_NAME     U2D1 CG72
 '@BASEBOARD_FAB2_LIB.BASEBOARD_FAB2(SCH_1):PAGE75_I17@CHPSET_LIB.SKX_EXT_B(CHIPS)':
 'VSS'<471>: CDS_PINID='VSS(471)';
NODE_NAME     U2D1 CG68
 '@BASEBOARD_FAB2_LIB.BASEBOARD_FAB2(SCH_1):PAGE75_I17@CHPSET_LIB.SKX_EXT_B(CHIPS)':
 'VSS'<472>: CDS_PINID='VSS(472)';
NODE_NAME     U2D1 CG62
 '@BASEBOARD_FAB2_LIB.BASEBOARD_FAB2(SCH_1):PAGE75_I17@CHPSET_LIB.SKX_EXT_B(CHIPS)':
 'VSS'<473>: CDS_PINID='VSS(473)';
NODE_NAME     U2D1 CG22
 '@BASEBOARD_FAB2_LIB.BASEBOARD_FAB2(SCH_1):PAGE75_I17@CHPSET_LIB.SKX_EXT_B(CHIPS)':
 'VSS'<474>: CDS_PINID='VSS(474)';
NODE_NAME     U2D1 CG18
 '@BASEBOARD_FAB2_LIB.BASEBOARD_FAB2(SCH_1):PAGE75_I17@CHPSET_LIB.SKX_EXT_B(CHIPS)':
 'VSS'<475>: CDS_PINID='VSS(475)';
NODE_NAME     U2D1 P51
 '@BASEBOARD_FAB2_LIB.BASEBOARD_FAB2(SCH_1):PAGE75_I17@CHPSET_LIB.SKX_EXT_B(CHIPS)':
 'VSS'<476>: CDS_PINID='VSS(476)';
NODE_NAME     U2D1 CF83
 '@BASEBOARD_FAB2_LIB.BASEBOARD_FAB2(SCH_1):PAGE75_I17@CHPSET_LIB.SKX_EXT_B(CHIPS)':
 'VSS'<477>: CDS_PINID='VSS(477)';
NODE_NAME     U2D1 CF77
 '@BASEBOARD_FAB2_LIB.BASEBOARD_FAB2(SCH_1):PAGE75_I17@CHPSET_LIB.SKX_EXT_B(CHIPS)':
 'VSS'<478>: CDS_PINID='VSS(478)';
NODE_NAME     U2D1 CF71
 '@BASEBOARD_FAB2_LIB.BASEBOARD_FAB2(SCH_1):PAGE75_I17@CHPSET_LIB.SKX_EXT_B(CHIPS)':
 'VSS'<479>: CDS_PINID='VSS(479)';
NODE_NAME     U2D1 CF69
 '@BASEBOARD_FAB2_LIB.BASEBOARD_FAB2(SCH_1):PAGE75_I17@CHPSET_LIB.SKX_EXT_B(CHIPS)':
 'VSS'<480>: CDS_PINID='VSS(480)';
NODE_NAME     U2D1 CF63
 '@BASEBOARD_FAB2_LIB.BASEBOARD_FAB2(SCH_1):PAGE75_I17@CHPSET_LIB.SKX_EXT_B(CHIPS)':
 'VSS'<481>: CDS_PINID='VSS(481)';
NODE_NAME     U2D1 CF9
 '@BASEBOARD_FAB2_LIB.BASEBOARD_FAB2(SCH_1):PAGE75_I17@CHPSET_LIB.SKX_EXT_B(CHIPS)':
 'VSS'<482>: CDS_PINID='VSS(482)';
NODE_NAME     U2D1 P53
 '@BASEBOARD_FAB2_LIB.BASEBOARD_FAB2(SCH_1):PAGE75_I17@CHPSET_LIB.SKX_EXT_B(CHIPS)':
 'VSS'<483>: CDS_PINID='VSS(483)';
NODE_NAME     U2D1 CE82
 '@BASEBOARD_FAB2_LIB.BASEBOARD_FAB2(SCH_1):PAGE75_I17@CHPSET_LIB.SKX_EXT_B(CHIPS)':
 'VSS'<484>: CDS_PINID='VSS(484)';
NODE_NAME     U2D1 CE70
 '@BASEBOARD_FAB2_LIB.BASEBOARD_FAB2(SCH_1):PAGE75_I17@CHPSET_LIB.SKX_EXT_B(CHIPS)':
 'VSS'<485>: CDS_PINID='VSS(485)';
NODE_NAME     U2D1 CE62
 '@BASEBOARD_FAB2_LIB.BASEBOARD_FAB2(SCH_1):PAGE75_I17@CHPSET_LIB.SKX_EXT_B(CHIPS)':
 'VSS'<486>: CDS_PINID='VSS(486)';
NODE_NAME     U2D1 CE26
 '@BASEBOARD_FAB2_LIB.BASEBOARD_FAB2(SCH_1):PAGE75_I17@CHPSET_LIB.SKX_EXT_B(CHIPS)':
 'VSS'<487>: CDS_PINID='VSS(487)';
NODE_NAME     U2D1 CE20
 '@BASEBOARD_FAB2_LIB.BASEBOARD_FAB2(SCH_1):PAGE75_I17@CHPSET_LIB.SKX_EXT_B(CHIPS)':
 'VSS'<488>: CDS_PINID='VSS(488)';
NODE_NAME     U2D1 CE14
 '@BASEBOARD_FAB2_LIB.BASEBOARD_FAB2(SCH_1):PAGE75_I17@CHPSET_LIB.SKX_EXT_B(CHIPS)':
 'VSS'<489>: CDS_PINID='VSS(489)';
NODE_NAME     U2D1 CE10
 '@BASEBOARD_FAB2_LIB.BASEBOARD_FAB2(SCH_1):PAGE75_I17@CHPSET_LIB.SKX_EXT_B(CHIPS)':
 'VSS'<490>: CDS_PINID='VSS(490)';
NODE_NAME     U2D1 CD81
 '@BASEBOARD_FAB2_LIB.BASEBOARD_FAB2(SCH_1):PAGE75_I17@CHPSET_LIB.SKX_EXT_B(CHIPS)':
 'VSS'<491>: CDS_PINID='VSS(491)';
NODE_NAME     U2D1 CD79
 '@BASEBOARD_FAB2_LIB.BASEBOARD_FAB2(SCH_1):PAGE75_I17@CHPSET_LIB.SKX_EXT_B(CHIPS)':
 'VSS'<492>: CDS_PINID='VSS(492)';
NODE_NAME     U2D1 CD77
 '@BASEBOARD_FAB2_LIB.BASEBOARD_FAB2(SCH_1):PAGE75_I17@CHPSET_LIB.SKX_EXT_B(CHIPS)':
 'VSS'<493>: CDS_PINID='VSS(493)';
NODE_NAME     U2D1 CD75
 '@BASEBOARD_FAB2_LIB.BASEBOARD_FAB2(SCH_1):PAGE75_I17@CHPSET_LIB.SKX_EXT_B(CHIPS)':
 'VSS'<494>: CDS_PINID='VSS(494)';
NODE_NAME     U2D1 CD73
 '@BASEBOARD_FAB2_LIB.BASEBOARD_FAB2(SCH_1):PAGE75_I17@CHPSET_LIB.SKX_EXT_B(CHIPS)':
 'VSS'<495>: CDS_PINID='VSS(495)';
NODE_NAME     U2D1 CD63
 '@BASEBOARD_FAB2_LIB.BASEBOARD_FAB2(SCH_1):PAGE75_I17@CHPSET_LIB.SKX_EXT_B(CHIPS)':
 'VSS'<496>: CDS_PINID='VSS(496)';
NODE_NAME     U2D1 CD13
 '@BASEBOARD_FAB2_LIB.BASEBOARD_FAB2(SCH_1):PAGE75_I17@CHPSET_LIB.SKX_EXT_B(CHIPS)':
 'VSS'<497>: CDS_PINID='VSS(497)';
NODE_NAME     U2D1 CD5
 '@BASEBOARD_FAB2_LIB.BASEBOARD_FAB2(SCH_1):PAGE75_I17@CHPSET_LIB.SKX_EXT_B(CHIPS)':
 'VSS'<498>: CDS_PINID='VSS(498)';
NODE_NAME     U2D1 CC82
 '@BASEBOARD_FAB2_LIB.BASEBOARD_FAB2(SCH_1):PAGE75_I17@CHPSET_LIB.SKX_EXT_B(CHIPS)':
 'VSS'<499>: CDS_PINID='VSS(499)';
NODE_NAME     U2D1 CC80
 '@BASEBOARD_FAB2_LIB.BASEBOARD_FAB2(SCH_1):PAGE75_I17@CHPSET_LIB.SKX_EXT_B(CHIPS)':
 'VSS'<500>: CDS_PINID='VSS(500)';
NODE_NAME     U2D1 CC78
 '@BASEBOARD_FAB2_LIB.BASEBOARD_FAB2(SCH_1):PAGE75_I17@CHPSET_LIB.SKX_EXT_B(CHIPS)':
 'VSS'<501>: CDS_PINID='VSS(501)';
NODE_NAME     U2D1 CC76
 '@BASEBOARD_FAB2_LIB.BASEBOARD_FAB2(SCH_1):PAGE75_I17@CHPSET_LIB.SKX_EXT_B(CHIPS)':
 'VSS'<502>: CDS_PINID='VSS(502)';
NODE_NAME     U2D1 CC74
 '@BASEBOARD_FAB2_LIB.BASEBOARD_FAB2(SCH_1):PAGE75_I17@CHPSET_LIB.SKX_EXT_B(CHIPS)':
 'VSS'<503>: CDS_PINID='VSS(503)';
NODE_NAME     U2D1 CC72
 '@BASEBOARD_FAB2_LIB.BASEBOARD_FAB2(SCH_1):PAGE75_I17@CHPSET_LIB.SKX_EXT_B(CHIPS)':
 'VSS'<504>: CDS_PINID='VSS(504)';
NODE_NAME     U2D1 CC64
 '@BASEBOARD_FAB2_LIB.BASEBOARD_FAB2(SCH_1):PAGE75_I17@CHPSET_LIB.SKX_EXT_B(CHIPS)':
 'VSS'<505>: CDS_PINID='VSS(505)';
NODE_NAME     U2D1 CC24
 '@BASEBOARD_FAB2_LIB.BASEBOARD_FAB2(SCH_1):PAGE75_I17@CHPSET_LIB.SKX_EXT_B(CHIPS)':
 'VSS'<506>: CDS_PINID='VSS(506)';
NODE_NAME     U2D1 CC18
 '@BASEBOARD_FAB2_LIB.BASEBOARD_FAB2(SCH_1):PAGE75_I17@CHPSET_LIB.SKX_EXT_B(CHIPS)':
 'VSS'<507>: CDS_PINID='VSS(507)';
NODE_NAME     U2D1 CC16
 '@BASEBOARD_FAB2_LIB.BASEBOARD_FAB2(SCH_1):PAGE75_I17@CHPSET_LIB.SKX_EXT_B(CHIPS)':
 'VSS'<508>: CDS_PINID='VSS(508)';
NODE_NAME     U2D1 CC4
 '@BASEBOARD_FAB2_LIB.BASEBOARD_FAB2(SCH_1):PAGE75_I17@CHPSET_LIB.SKX_EXT_B(CHIPS)':
 'VSS'<509>: CDS_PINID='VSS(509)';
NODE_NAME     U2D1 CB71
 '@BASEBOARD_FAB2_LIB.BASEBOARD_FAB2(SCH_1):PAGE75_I17@CHPSET_LIB.SKX_EXT_B(CHIPS)':
 'VSS'<510>: CDS_PINID='VSS(510)';
NODE_NAME     U2D1 CB63
 '@BASEBOARD_FAB2_LIB.BASEBOARD_FAB2(SCH_1):PAGE75_I17@CHPSET_LIB.SKX_EXT_B(CHIPS)':
 'VSS'<511>: CDS_PINID='VSS(511)';
NODE_NAME     U2D1 CB27
 '@BASEBOARD_FAB2_LIB.BASEBOARD_FAB2(SCH_1):PAGE75_I17@CHPSET_LIB.SKX_EXT_B(CHIPS)':
 'VSS'<512>: CDS_PINID='VSS(512)';
NODE_NAME     U2D1 CB9
 '@BASEBOARD_FAB2_LIB.BASEBOARD_FAB2(SCH_1):PAGE75_I17@CHPSET_LIB.SKX_EXT_B(CHIPS)':
 'VSS'<513>: CDS_PINID='VSS(513)';
NODE_NAME     U2D1 CB7
 '@BASEBOARD_FAB2_LIB.BASEBOARD_FAB2(SCH_1):PAGE75_I17@CHPSET_LIB.SKX_EXT_B(CHIPS)':
 'VSS'<514>: CDS_PINID='VSS(514)';
NODE_NAME     U2D1 CA70
 '@BASEBOARD_FAB2_LIB.BASEBOARD_FAB2(SCH_1):PAGE75_I17@CHPSET_LIB.SKX_EXT_B(CHIPS)':
 'VSS'<515>: CDS_PINID='VSS(515)';
NODE_NAME     U2D1 CA68
 '@BASEBOARD_FAB2_LIB.BASEBOARD_FAB2(SCH_1):PAGE75_I17@CHPSET_LIB.SKX_EXT_B(CHIPS)':
 'VSS'<516>: CDS_PINID='VSS(516)';
NODE_NAME     U2D1 CA66
 '@BASEBOARD_FAB2_LIB.BASEBOARD_FAB2(SCH_1):PAGE75_I17@CHPSET_LIB.SKX_EXT_B(CHIPS)':
 'VSS'<517>: CDS_PINID='VSS(517)';
NODE_NAME     U2D1 CA64
 '@BASEBOARD_FAB2_LIB.BASEBOARD_FAB2(SCH_1):PAGE75_I17@CHPSET_LIB.SKX_EXT_B(CHIPS)':
 'VSS'<518>: CDS_PINID='VSS(518)';
NODE_NAME     U2D1 CA26
 '@BASEBOARD_FAB2_LIB.BASEBOARD_FAB2(SCH_1):PAGE75_I17@CHPSET_LIB.SKX_EXT_B(CHIPS)':
 'VSS'<519>: CDS_PINID='VSS(519)';
NODE_NAME     U2D1 CA18
 '@BASEBOARD_FAB2_LIB.BASEBOARD_FAB2(SCH_1):PAGE75_I17@CHPSET_LIB.SKX_EXT_B(CHIPS)':
 'VSS'<520>: CDS_PINID='VSS(520)';
NODE_NAME     U2D1 CA14
 '@BASEBOARD_FAB2_LIB.BASEBOARD_FAB2(SCH_1):PAGE75_I17@CHPSET_LIB.SKX_EXT_B(CHIPS)':
 'VSS'<521>: CDS_PINID='VSS(521)';
NODE_NAME     U2D1 CA10
 '@BASEBOARD_FAB2_LIB.BASEBOARD_FAB2(SCH_1):PAGE75_I17@CHPSET_LIB.SKX_EXT_B(CHIPS)':
 'VSS'<522>: CDS_PINID='VSS(522)';
NODE_NAME     U2D1 CA8
 '@BASEBOARD_FAB2_LIB.BASEBOARD_FAB2(SCH_1):PAGE75_I17@CHPSET_LIB.SKX_EXT_B(CHIPS)':
 'VSS'<523>: CDS_PINID='VSS(523)';
NODE_NAME     U2D1 CA6
 '@BASEBOARD_FAB2_LIB.BASEBOARD_FAB2(SCH_1):PAGE75_I17@CHPSET_LIB.SKX_EXT_B(CHIPS)':
 'VSS'<524>: CDS_PINID='VSS(524)';
NODE_NAME     U2D1 CA2
 '@BASEBOARD_FAB2_LIB.BASEBOARD_FAB2(SCH_1):PAGE75_I17@CHPSET_LIB.SKX_EXT_B(CHIPS)':
 'VSS'<525>: CDS_PINID='VSS(525)';
NODE_NAME     U2D1 BY71
 '@BASEBOARD_FAB2_LIB.BASEBOARD_FAB2(SCH_1):PAGE75_I17@CHPSET_LIB.SKX_EXT_B(CHIPS)':
 'VSS'<526>: CDS_PINID='VSS(526)';
NODE_NAME     U2D1 BY69
 '@BASEBOARD_FAB2_LIB.BASEBOARD_FAB2(SCH_1):PAGE75_I17@CHPSET_LIB.SKX_EXT_B(CHIPS)':
 'VSS'<527>: CDS_PINID='VSS(527)';
NODE_NAME     U2D1 BY67
 '@BASEBOARD_FAB2_LIB.BASEBOARD_FAB2(SCH_1):PAGE75_I17@CHPSET_LIB.SKX_EXT_B(CHIPS)':
 'VSS'<528>: CDS_PINID='VSS(528)';
NODE_NAME     U2D1 BY65
 '@BASEBOARD_FAB2_LIB.BASEBOARD_FAB2(SCH_1):PAGE75_I17@CHPSET_LIB.SKX_EXT_B(CHIPS)':
 'VSS'<529>: CDS_PINID='VSS(529)';
NODE_NAME     U2D1 BY63
 '@BASEBOARD_FAB2_LIB.BASEBOARD_FAB2(SCH_1):PAGE75_I17@CHPSET_LIB.SKX_EXT_B(CHIPS)':
 'VSS'<530>: CDS_PINID='VSS(530)';
NODE_NAME     U2D1 BY23
 '@BASEBOARD_FAB2_LIB.BASEBOARD_FAB2(SCH_1):PAGE75_I17@CHPSET_LIB.SKX_EXT_B(CHIPS)':
 'VSS'<531>: CDS_PINID='VSS(531)';
NODE_NAME     U2D1 BY13
 '@BASEBOARD_FAB2_LIB.BASEBOARD_FAB2(SCH_1):PAGE75_I17@CHPSET_LIB.SKX_EXT_B(CHIPS)':
 'VSS'<532>: CDS_PINID='VSS(532)';
NODE_NAME     U2D1 BY11
 '@BASEBOARD_FAB2_LIB.BASEBOARD_FAB2(SCH_1):PAGE75_I17@CHPSET_LIB.SKX_EXT_B(CHIPS)':
 'VSS'<533>: CDS_PINID='VSS(533)';
NODE_NAME     U2D1 BW82
 '@BASEBOARD_FAB2_LIB.BASEBOARD_FAB2(SCH_1):PAGE75_I17@CHPSET_LIB.SKX_EXT_B(CHIPS)':
 'VSS'<534>: CDS_PINID='VSS(534)';
NODE_NAME     U2D1 BW80
 '@BASEBOARD_FAB2_LIB.BASEBOARD_FAB2(SCH_1):PAGE75_I17@CHPSET_LIB.SKX_EXT_B(CHIPS)':
 'VSS'<535>: CDS_PINID='VSS(535)';
NODE_NAME     U2D1 BW78
 '@BASEBOARD_FAB2_LIB.BASEBOARD_FAB2(SCH_1):PAGE75_I17@CHPSET_LIB.SKX_EXT_B(CHIPS)':
 'VSS'<536>: CDS_PINID='VSS(536)';
NODE_NAME     U2D1 BW76
 '@BASEBOARD_FAB2_LIB.BASEBOARD_FAB2(SCH_1):PAGE75_I17@CHPSET_LIB.SKX_EXT_B(CHIPS)':
 'VSS'<537>: CDS_PINID='VSS(537)';
NODE_NAME     U2D1 BW74
 '@BASEBOARD_FAB2_LIB.BASEBOARD_FAB2(SCH_1):PAGE75_I17@CHPSET_LIB.SKX_EXT_B(CHIPS)':
 'VSS'<538>: CDS_PINID='VSS(538)';
NODE_NAME     U2D1 BW72
 '@BASEBOARD_FAB2_LIB.BASEBOARD_FAB2(SCH_1):PAGE75_I17@CHPSET_LIB.SKX_EXT_B(CHIPS)':
 'VSS'<539>: CDS_PINID='VSS(539)';
NODE_NAME     U2D1 BW26
 '@BASEBOARD_FAB2_LIB.BASEBOARD_FAB2(SCH_1):PAGE75_I17@CHPSET_LIB.SKX_EXT_B(CHIPS)':
 'VSS'<540>: CDS_PINID='VSS(540)';
NODE_NAME     U2D1 BW18
 '@BASEBOARD_FAB2_LIB.BASEBOARD_FAB2(SCH_1):PAGE75_I17@CHPSET_LIB.SKX_EXT_B(CHIPS)':
 'VSS'<541>: CDS_PINID='VSS(541)';
NODE_NAME     U2D1 BW16
 '@BASEBOARD_FAB2_LIB.BASEBOARD_FAB2(SCH_1):PAGE75_I17@CHPSET_LIB.SKX_EXT_B(CHIPS)':
 'VSS'<542>: CDS_PINID='VSS(542)';
NODE_NAME     U2D1 BW14
 '@BASEBOARD_FAB2_LIB.BASEBOARD_FAB2(SCH_1):PAGE75_I17@CHPSET_LIB.SKX_EXT_B(CHIPS)':
 'VSS'<543>: CDS_PINID='VSS(543)';
NODE_NAME     U2D1 BW12
 '@BASEBOARD_FAB2_LIB.BASEBOARD_FAB2(SCH_1):PAGE75_I17@CHPSET_LIB.SKX_EXT_B(CHIPS)':
 'VSS'<544>: CDS_PINID='VSS(544)';
NODE_NAME     U2D1 P55
 '@BASEBOARD_FAB2_LIB.BASEBOARD_FAB2(SCH_1):PAGE75_I17@CHPSET_LIB.SKX_EXT_B(CHIPS)':
 'VSS'<545>: CDS_PINID='VSS(545)';
NODE_NAME     U2D1 BW6
 '@BASEBOARD_FAB2_LIB.BASEBOARD_FAB2(SCH_1):PAGE75_I17@CHPSET_LIB.SKX_EXT_B(CHIPS)':
 'VSS'<546>: CDS_PINID='VSS(546)';
NODE_NAME     U2D1 BV25
 '@BASEBOARD_FAB2_LIB.BASEBOARD_FAB2(SCH_1):PAGE75_I17@CHPSET_LIB.SKX_EXT_B(CHIPS)':
 'VSS'<547>: CDS_PINID='VSS(547)';
NODE_NAME     U2D1 BV17
 '@BASEBOARD_FAB2_LIB.BASEBOARD_FAB2(SCH_1):PAGE75_I17@CHPSET_LIB.SKX_EXT_B(CHIPS)':
 'VSS'<548>: CDS_PINID='VSS(548)';
NODE_NAME     U2D1 BU10
 '@BASEBOARD_FAB2_LIB.BASEBOARD_FAB2(SCH_1):PAGE75_I17@CHPSET_LIB.SKX_EXT_B(CHIPS)':
 'VSS'<549>: CDS_PINID='VSS(549)';
NODE_NAME     U2D1 BV5
 '@BASEBOARD_FAB2_LIB.BASEBOARD_FAB2(SCH_1):PAGE75_I17@CHPSET_LIB.SKX_EXT_B(CHIPS)':
 'VSS'<550>: CDS_PINID='VSS(550)';
NODE_NAME     U2D1 BU8
 '@BASEBOARD_FAB2_LIB.BASEBOARD_FAB2(SCH_1):PAGE75_I17@CHPSET_LIB.SKX_EXT_B(CHIPS)':
 'VSS'<551>: CDS_PINID='VSS(551)';
NODE_NAME     U2D1 BT25
 '@BASEBOARD_FAB2_LIB.BASEBOARD_FAB2(SCH_1):PAGE75_I17@CHPSET_LIB.SKX_EXT_B(CHIPS)':
 'VSS'<552>: CDS_PINID='VSS(552)';
NODE_NAME     U2D1 BT23
 '@BASEBOARD_FAB2_LIB.BASEBOARD_FAB2(SCH_1):PAGE75_I17@CHPSET_LIB.SKX_EXT_B(CHIPS)':
 'VSS'<553>: CDS_PINID='VSS(553)';
NODE_NAME     U2D1 BT21
 '@BASEBOARD_FAB2_LIB.BASEBOARD_FAB2(SCH_1):PAGE75_I17@CHPSET_LIB.SKX_EXT_B(CHIPS)':
 'VSS'<554>: CDS_PINID='VSS(554)';
NODE_NAME     U2D1 BT5
 '@BASEBOARD_FAB2_LIB.BASEBOARD_FAB2(SCH_1):PAGE75_I17@CHPSET_LIB.SKX_EXT_B(CHIPS)':
 'VSS'<555>: CDS_PINID='VSS(555)';
NODE_NAME     U2D1 BT3
 '@BASEBOARD_FAB2_LIB.BASEBOARD_FAB2(SCH_1):PAGE75_I17@CHPSET_LIB.SKX_EXT_B(CHIPS)':
 'VSS'<556>: CDS_PINID='VSS(556)';
NODE_NAME     U2D1 BR82
 '@BASEBOARD_FAB2_LIB.BASEBOARD_FAB2(SCH_1):PAGE75_I17@CHPSET_LIB.SKX_EXT_B(CHIPS)':
 'VSS'<557>: CDS_PINID='VSS(557)';
NODE_NAME     U2D1 BR80
 '@BASEBOARD_FAB2_LIB.BASEBOARD_FAB2(SCH_1):PAGE75_I17@CHPSET_LIB.SKX_EXT_B(CHIPS)':
 'VSS'<558>: CDS_PINID='VSS(558)';
NODE_NAME     U2D1 BR78
 '@BASEBOARD_FAB2_LIB.BASEBOARD_FAB2(SCH_1):PAGE75_I17@CHPSET_LIB.SKX_EXT_B(CHIPS)':
 'VSS'<559>: CDS_PINID='VSS(559)';
NODE_NAME     U2D1 BR76
 '@BASEBOARD_FAB2_LIB.BASEBOARD_FAB2(SCH_1):PAGE75_I17@CHPSET_LIB.SKX_EXT_B(CHIPS)':
 'VSS'<560>: CDS_PINID='VSS(560)';
NODE_NAME     U2D1 BR74
 '@BASEBOARD_FAB2_LIB.BASEBOARD_FAB2(SCH_1):PAGE75_I17@CHPSET_LIB.SKX_EXT_B(CHIPS)':
 'VSS'<561>: CDS_PINID='VSS(561)';
NODE_NAME     U2D1 BR72
 '@BASEBOARD_FAB2_LIB.BASEBOARD_FAB2(SCH_1):PAGE75_I17@CHPSET_LIB.SKX_EXT_B(CHIPS)':
 'VSS'<562>: CDS_PINID='VSS(562)';
NODE_NAME     U2D1 BR70
 '@BASEBOARD_FAB2_LIB.BASEBOARD_FAB2(SCH_1):PAGE75_I17@CHPSET_LIB.SKX_EXT_B(CHIPS)':
 'VSS'<563>: CDS_PINID='VSS(563)';
NODE_NAME     U2D1 BR68
 '@BASEBOARD_FAB2_LIB.BASEBOARD_FAB2(SCH_1):PAGE75_I17@CHPSET_LIB.SKX_EXT_B(CHIPS)':
 'VSS'<564>: CDS_PINID='VSS(564)';
NODE_NAME     U2D1 BR66
 '@BASEBOARD_FAB2_LIB.BASEBOARD_FAB2(SCH_1):PAGE75_I17@CHPSET_LIB.SKX_EXT_B(CHIPS)':
 'VSS'<565>: CDS_PINID='VSS(565)';
NODE_NAME     U2D1 BR64
 '@BASEBOARD_FAB2_LIB.BASEBOARD_FAB2(SCH_1):PAGE75_I17@CHPSET_LIB.SKX_EXT_B(CHIPS)':
 'VSS'<566>: CDS_PINID='VSS(566)';
NODE_NAME     U2D1 P57
 '@BASEBOARD_FAB2_LIB.BASEBOARD_FAB2(SCH_1):PAGE75_I17@CHPSET_LIB.SKX_EXT_B(CHIPS)':
 'VSS'<567>: CDS_PINID='VSS(567)';
NODE_NAME     U2D1 BR16
 '@BASEBOARD_FAB2_LIB.BASEBOARD_FAB2(SCH_1):PAGE75_I17@CHPSET_LIB.SKX_EXT_B(CHIPS)':
 'VSS'<568>: CDS_PINID='VSS(568)';
NODE_NAME     U2D1 BR10
 '@BASEBOARD_FAB2_LIB.BASEBOARD_FAB2(SCH_1):PAGE75_I17@CHPSET_LIB.SKX_EXT_B(CHIPS)':
 'VSS'<569>: CDS_PINID='VSS(569)';
NODE_NAME     U2D1 BR6
 '@BASEBOARD_FAB2_LIB.BASEBOARD_FAB2(SCH_1):PAGE75_I17@CHPSET_LIB.SKX_EXT_B(CHIPS)':
 'VSS'<570>: CDS_PINID='VSS(570)';
NODE_NAME     U2D1 BP27
 '@BASEBOARD_FAB2_LIB.BASEBOARD_FAB2(SCH_1):PAGE75_I17@CHPSET_LIB.SKX_EXT_B(CHIPS)':
 'VSS'<571>: CDS_PINID='VSS(571)';
NODE_NAME     U2D1 BP3
 '@BASEBOARD_FAB2_LIB.BASEBOARD_FAB2(SCH_1):PAGE75_I17@CHPSET_LIB.SKX_EXT_B(CHIPS)':
 'VSS'<572>: CDS_PINID='VSS(572)';
NODE_NAME     U2D1 BN26
 '@BASEBOARD_FAB2_LIB.BASEBOARD_FAB2(SCH_1):PAGE75_I17@CHPSET_LIB.SKX_EXT_B(CHIPS)':
 'VSS'<573>: CDS_PINID='VSS(573)';
NODE_NAME     U2D1 BN20
 '@BASEBOARD_FAB2_LIB.BASEBOARD_FAB2(SCH_1):PAGE75_I17@CHPSET_LIB.SKX_EXT_B(CHIPS)':
 'VSS'<574>: CDS_PINID='VSS(574)';
NODE_NAME     U2D1 BN10
 '@BASEBOARD_FAB2_LIB.BASEBOARD_FAB2(SCH_1):PAGE75_I17@CHPSET_LIB.SKX_EXT_B(CHIPS)':
 'VSS'<575>: CDS_PINID='VSS(575)';
NODE_NAME     U2D1 BN6
 '@BASEBOARD_FAB2_LIB.BASEBOARD_FAB2(SCH_1):PAGE75_I17@CHPSET_LIB.SKX_EXT_B(CHIPS)':
 'VSS'<576>: CDS_PINID='VSS(576)';
NODE_NAME     U2D1 BM25
 '@BASEBOARD_FAB2_LIB.BASEBOARD_FAB2(SCH_1):PAGE75_I17@CHPSET_LIB.SKX_EXT_B(CHIPS)':
 'VSS'<577>: CDS_PINID='VSS(577)';
NODE_NAME     U2D1 P59
 '@BASEBOARD_FAB2_LIB.BASEBOARD_FAB2(SCH_1):PAGE75_I17@CHPSET_LIB.SKX_EXT_B(CHIPS)':
 'VSS'<578>: CDS_PINID='VSS(578)';
NODE_NAME     U2D1 BM15
 '@BASEBOARD_FAB2_LIB.BASEBOARD_FAB2(SCH_1):PAGE75_I17@CHPSET_LIB.SKX_EXT_B(CHIPS)':
 'VSS'<579>: CDS_PINID='VSS(579)';
NODE_NAME     U2D1 BM13
 '@BASEBOARD_FAB2_LIB.BASEBOARD_FAB2(SCH_1):PAGE75_I17@CHPSET_LIB.SKX_EXT_B(CHIPS)':
 'VSS'<580>: CDS_PINID='VSS(580)';
NODE_NAME     U2D1 BM9
 '@BASEBOARD_FAB2_LIB.BASEBOARD_FAB2(SCH_1):PAGE75_I17@CHPSET_LIB.SKX_EXT_B(CHIPS)':
 'VSS'<581>: CDS_PINID='VSS(581)';
NODE_NAME     U2D1 BL82
 '@BASEBOARD_FAB2_LIB.BASEBOARD_FAB2(SCH_1):PAGE75_I17@CHPSET_LIB.SKX_EXT_B(CHIPS)':
 'VSS'<582>: CDS_PINID='VSS(582)';
NODE_NAME     U2D1 BL80
 '@BASEBOARD_FAB2_LIB.BASEBOARD_FAB2(SCH_1):PAGE75_I17@CHPSET_LIB.SKX_EXT_B(CHIPS)':
 'VSS'<583>: CDS_PINID='VSS(583)';
NODE_NAME     U2D1 BL78
 '@BASEBOARD_FAB2_LIB.BASEBOARD_FAB2(SCH_1):PAGE75_I17@CHPSET_LIB.SKX_EXT_B(CHIPS)':
 'VSS'<584>: CDS_PINID='VSS(584)';
NODE_NAME     U2D1 BL76
 '@BASEBOARD_FAB2_LIB.BASEBOARD_FAB2(SCH_1):PAGE75_I17@CHPSET_LIB.SKX_EXT_B(CHIPS)':
 'VSS'<585>: CDS_PINID='VSS(585)';
NODE_NAME     U2D1 BL74
 '@BASEBOARD_FAB2_LIB.BASEBOARD_FAB2(SCH_1):PAGE75_I17@CHPSET_LIB.SKX_EXT_B(CHIPS)':
 'VSS'<586>: CDS_PINID='VSS(586)';
NODE_NAME     U2D1 BL72
 '@BASEBOARD_FAB2_LIB.BASEBOARD_FAB2(SCH_1):PAGE75_I17@CHPSET_LIB.SKX_EXT_B(CHIPS)':
 'VSS'<587>: CDS_PINID='VSS(587)';
NODE_NAME     U2D1 BL70
 '@BASEBOARD_FAB2_LIB.BASEBOARD_FAB2(SCH_1):PAGE75_I17@CHPSET_LIB.SKX_EXT_B(CHIPS)':
 'VSS'<588>: CDS_PINID='VSS(588)';
NODE_NAME     U2D1 BL68
 '@BASEBOARD_FAB2_LIB.BASEBOARD_FAB2(SCH_1):PAGE75_I17@CHPSET_LIB.SKX_EXT_B(CHIPS)':
 'VSS'<589>: CDS_PINID='VSS(589)';
NODE_NAME     U2D1 BL66
 '@BASEBOARD_FAB2_LIB.BASEBOARD_FAB2(SCH_1):PAGE75_I17@CHPSET_LIB.SKX_EXT_B(CHIPS)':
 'VSS'<590>: CDS_PINID='VSS(590)';
NODE_NAME     U2D1 BL64
 '@BASEBOARD_FAB2_LIB.BASEBOARD_FAB2(SCH_1):PAGE75_I17@CHPSET_LIB.SKX_EXT_B(CHIPS)':
 'VSS'<591>: CDS_PINID='VSS(591)';
NODE_NAME     U2D1 BL24
 '@BASEBOARD_FAB2_LIB.BASEBOARD_FAB2(SCH_1):PAGE75_I17@CHPSET_LIB.SKX_EXT_B(CHIPS)':
 'VSS'<592>: CDS_PINID='VSS(592)';
NODE_NAME     U2D1 BL22
 '@BASEBOARD_FAB2_LIB.BASEBOARD_FAB2(SCH_1):PAGE75_I17@CHPSET_LIB.SKX_EXT_B(CHIPS)':
 'VSS'<593>: CDS_PINID='VSS(593)';
NODE_NAME     U2D1 P61
 '@BASEBOARD_FAB2_LIB.BASEBOARD_FAB2(SCH_1):PAGE75_I17@CHPSET_LIB.SKX_EXT_B(CHIPS)':
 'VSS'<594>: CDS_PINID='VSS(594)';
NODE_NAME     U2D1 BL12
 '@BASEBOARD_FAB2_LIB.BASEBOARD_FAB2(SCH_1):PAGE75_I17@CHPSET_LIB.SKX_EXT_B(CHIPS)':
 'VSS'<595>: CDS_PINID='VSS(595)';
NODE_NAME     U2D1 BL10
 '@BASEBOARD_FAB2_LIB.BASEBOARD_FAB2(SCH_1):PAGE75_I17@CHPSET_LIB.SKX_EXT_B(CHIPS)':
 'VSS'<596>: CDS_PINID='VSS(596)';
NODE_NAME     U2D1 BL6
 '@BASEBOARD_FAB2_LIB.BASEBOARD_FAB2(SCH_1):PAGE75_I17@CHPSET_LIB.SKX_EXT_B(CHIPS)':
 'VSS'<597>: CDS_PINID='VSS(597)';
NODE_NAME     U2D1 BK19
 '@BASEBOARD_FAB2_LIB.BASEBOARD_FAB2(SCH_1):PAGE75_I17@CHPSET_LIB.SKX_EXT_B(CHIPS)':
 'VSS'<598>: CDS_PINID='VSS(598)';
NODE_NAME     U2D1 BK11
 '@BASEBOARD_FAB2_LIB.BASEBOARD_FAB2(SCH_1):PAGE75_I17@CHPSET_LIB.SKX_EXT_B(CHIPS)':
 'VSS'<599>: CDS_PINID='VSS(599)';
NODE_NAME     U2D1 BK7
 '@BASEBOARD_FAB2_LIB.BASEBOARD_FAB2(SCH_1):PAGE75_I17@CHPSET_LIB.SKX_EXT_B(CHIPS)':
 'VSS'<600>: CDS_PINID='VSS(600)';
NODE_NAME     U2D1 BK3
 '@BASEBOARD_FAB2_LIB.BASEBOARD_FAB2(SCH_1):PAGE75_I17@CHPSET_LIB.SKX_EXT_B(CHIPS)':
 'VSS'<601>: CDS_PINID='VSS(601)';
NODE_NAME     U2D1 BJ6
 '@BASEBOARD_FAB2_LIB.BASEBOARD_FAB2(SCH_1):PAGE75_I17@CHPSET_LIB.SKX_EXT_B(CHIPS)':
 'VSS'<602>: CDS_PINID='VSS(602)';
NODE_NAME     U2D1 BJ4
 '@BASEBOARD_FAB2_LIB.BASEBOARD_FAB2(SCH_1):PAGE75_I17@CHPSET_LIB.SKX_EXT_B(CHIPS)':
 'VSS'<603>: CDS_PINID='VSS(603)';
NODE_NAME     U2D1 BH21
 '@BASEBOARD_FAB2_LIB.BASEBOARD_FAB2(SCH_1):PAGE75_I17@CHPSET_LIB.SKX_EXT_B(CHIPS)':
 'VSS'<604>: CDS_PINID='VSS(604)';
NODE_NAME     U2D1 BH15
 '@BASEBOARD_FAB2_LIB.BASEBOARD_FAB2(SCH_1):PAGE75_I17@CHPSET_LIB.SKX_EXT_B(CHIPS)':
 'VSS'<605>: CDS_PINID='VSS(605)';
NODE_NAME     U2D1 BH11
 '@BASEBOARD_FAB2_LIB.BASEBOARD_FAB2(SCH_1):PAGE75_I17@CHPSET_LIB.SKX_EXT_B(CHIPS)':
 'VSS'<606>: CDS_PINID='VSS(606)';
NODE_NAME     U2D1 BH9
 '@BASEBOARD_FAB2_LIB.BASEBOARD_FAB2(SCH_1):PAGE75_I17@CHPSET_LIB.SKX_EXT_B(CHIPS)':
 'VSS'<607>: CDS_PINID='VSS(607)';
NODE_NAME     U2D1 BH7
 '@BASEBOARD_FAB2_LIB.BASEBOARD_FAB2(SCH_1):PAGE75_I17@CHPSET_LIB.SKX_EXT_B(CHIPS)':
 'VSS'<608>: CDS_PINID='VSS(608)';
NODE_NAME     U2D1 BG82
 '@BASEBOARD_FAB2_LIB.BASEBOARD_FAB2(SCH_1):PAGE75_I17@CHPSET_LIB.SKX_EXT_B(CHIPS)':
 'VSS'<609>: CDS_PINID='VSS(609)';
NODE_NAME     U2D1 BG80
 '@BASEBOARD_FAB2_LIB.BASEBOARD_FAB2(SCH_1):PAGE75_I17@CHPSET_LIB.SKX_EXT_B(CHIPS)':
 'VSS'<610>: CDS_PINID='VSS(610)';
NODE_NAME     U2D1 BG78
 '@BASEBOARD_FAB2_LIB.BASEBOARD_FAB2(SCH_1):PAGE75_I17@CHPSET_LIB.SKX_EXT_B(CHIPS)':
 'VSS'<611>: CDS_PINID='VSS(611)';
NODE_NAME     U2D1 BG76
 '@BASEBOARD_FAB2_LIB.BASEBOARD_FAB2(SCH_1):PAGE75_I17@CHPSET_LIB.SKX_EXT_B(CHIPS)':
 'VSS'<612>: CDS_PINID='VSS(612)';
NODE_NAME     U2D1 BG74
 '@BASEBOARD_FAB2_LIB.BASEBOARD_FAB2(SCH_1):PAGE75_I17@CHPSET_LIB.SKX_EXT_B(CHIPS)':
 'VSS'<613>: CDS_PINID='VSS(613)';
NODE_NAME     U2D1 DA46
 '@BASEBOARD_FAB2_LIB.BASEBOARD_FAB2(SCH_1):PAGE75_I18@CHPSET_LIB.SKX_EXT_B(CHIPS)':
 'VSS'<294>: CDS_PINID='VSS(294)';
NODE_NAME     U2D1 DA44
 '@BASEBOARD_FAB2_LIB.BASEBOARD_FAB2(SCH_1):PAGE75_I18@CHPSET_LIB.SKX_EXT_B(CHIPS)':
 'VSS'<295>: CDS_PINID='VSS(295)';
NODE_NAME     U2D1 DA38
 '@BASEBOARD_FAB2_LIB.BASEBOARD_FAB2(SCH_1):PAGE75_I18@CHPSET_LIB.SKX_EXT_B(CHIPS)':
 'VSS'<296>: CDS_PINID='VSS(296)';
NODE_NAME     U2D1 DA36
 '@BASEBOARD_FAB2_LIB.BASEBOARD_FAB2(SCH_1):PAGE75_I18@CHPSET_LIB.SKX_EXT_B(CHIPS)':
 'VSS'<297>: CDS_PINID='VSS(297)';
NODE_NAME     U2D1 DA34
 '@BASEBOARD_FAB2_LIB.BASEBOARD_FAB2(SCH_1):PAGE75_I18@CHPSET_LIB.SKX_EXT_B(CHIPS)':
 'VSS'<298>: CDS_PINID='VSS(298)';
NODE_NAME     U2D1 DA32
 '@BASEBOARD_FAB2_LIB.BASEBOARD_FAB2(SCH_1):PAGE75_I18@CHPSET_LIB.SKX_EXT_B(CHIPS)':
 'VSS'<299>: CDS_PINID='VSS(299)';
NODE_NAME     U2D1 DA30
 '@BASEBOARD_FAB2_LIB.BASEBOARD_FAB2(SCH_1):PAGE75_I18@CHPSET_LIB.SKX_EXT_B(CHIPS)':
 'VSS'<300>: CDS_PINID='VSS(300)';
NODE_NAME     U2D1 DA28
 '@BASEBOARD_FAB2_LIB.BASEBOARD_FAB2(SCH_1):PAGE75_I18@CHPSET_LIB.SKX_EXT_B(CHIPS)':
 'VSS'<301>: CDS_PINID='VSS(301)';
NODE_NAME     U2D1 DA26
 '@BASEBOARD_FAB2_LIB.BASEBOARD_FAB2(SCH_1):PAGE75_I18@CHPSET_LIB.SKX_EXT_B(CHIPS)':
 'VSS'<302>: CDS_PINID='VSS(302)';
NODE_NAME     U2D1 DA18
 '@BASEBOARD_FAB2_LIB.BASEBOARD_FAB2(SCH_1):PAGE75_I18@CHPSET_LIB.SKX_EXT_B(CHIPS)':
 'VSS'<303>: CDS_PINID='VSS(303)';
NODE_NAME     U2D1 H53
 '@BASEBOARD_FAB2_LIB.BASEBOARD_FAB2(SCH_1):PAGE75_I18@CHPSET_LIB.SKX_EXT_B(CHIPS)':
 'VSS'<304>: CDS_PINID='VSS(304)';
NODE_NAME     U2D1 DA6
 '@BASEBOARD_FAB2_LIB.BASEBOARD_FAB2(SCH_1):PAGE75_I18@CHPSET_LIB.SKX_EXT_B(CHIPS)':
 'VSS'<305>: CDS_PINID='VSS(305)';
NODE_NAME     U2D1 CY85
 '@BASEBOARD_FAB2_LIB.BASEBOARD_FAB2(SCH_1):PAGE75_I18@CHPSET_LIB.SKX_EXT_B(CHIPS)':
 'VSS'<306>: CDS_PINID='VSS(306)';
NODE_NAME     U2D1 CY83
 '@BASEBOARD_FAB2_LIB.BASEBOARD_FAB2(SCH_1):PAGE75_I18@CHPSET_LIB.SKX_EXT_B(CHIPS)':
 'VSS'<307>: CDS_PINID='VSS(307)';
NODE_NAME     U2D1 CY77
 '@BASEBOARD_FAB2_LIB.BASEBOARD_FAB2(SCH_1):PAGE75_I18@CHPSET_LIB.SKX_EXT_B(CHIPS)':
 'VSS'<308>: CDS_PINID='VSS(308)';
NODE_NAME     U2D1 CY75
 '@BASEBOARD_FAB2_LIB.BASEBOARD_FAB2(SCH_1):PAGE75_I18@CHPSET_LIB.SKX_EXT_B(CHIPS)':
 'VSS'<309>: CDS_PINID='VSS(309)';
NODE_NAME     U2D1 CY69
 '@BASEBOARD_FAB2_LIB.BASEBOARD_FAB2(SCH_1):PAGE75_I18@CHPSET_LIB.SKX_EXT_B(CHIPS)':
 'VSS'<310>: CDS_PINID='VSS(310)';
NODE_NAME     U2D1 CY65
 '@BASEBOARD_FAB2_LIB.BASEBOARD_FAB2(SCH_1):PAGE75_I18@CHPSET_LIB.SKX_EXT_B(CHIPS)':
 'VSS'<311>: CDS_PINID='VSS(311)';
NODE_NAME     U2D1 CY61
 '@BASEBOARD_FAB2_LIB.BASEBOARD_FAB2(SCH_1):PAGE75_I18@CHPSET_LIB.SKX_EXT_B(CHIPS)':
 'VSS'<312>: CDS_PINID='VSS(312)';
NODE_NAME     U2D1 CY59
 '@BASEBOARD_FAB2_LIB.BASEBOARD_FAB2(SCH_1):PAGE75_I18@CHPSET_LIB.SKX_EXT_B(CHIPS)':
 'VSS'<313>: CDS_PINID='VSS(313)';
NODE_NAME     U2D1 CY51
 '@BASEBOARD_FAB2_LIB.BASEBOARD_FAB2(SCH_1):PAGE75_I18@CHPSET_LIB.SKX_EXT_B(CHIPS)':
 'VSS'<314>: CDS_PINID='VSS(314)';
NODE_NAME     U2D1 CY45
 '@BASEBOARD_FAB2_LIB.BASEBOARD_FAB2(SCH_1):PAGE75_I18@CHPSET_LIB.SKX_EXT_B(CHIPS)':
 'VSS'<315>: CDS_PINID='VSS(315)';
NODE_NAME     U2D1 CY41
 '@BASEBOARD_FAB2_LIB.BASEBOARD_FAB2(SCH_1):PAGE75_I18@CHPSET_LIB.SKX_EXT_B(CHIPS)':
 'VSS'<316>: CDS_PINID='VSS(316)';
NODE_NAME     U2D1 CY21
 '@BASEBOARD_FAB2_LIB.BASEBOARD_FAB2(SCH_1):PAGE75_I18@CHPSET_LIB.SKX_EXT_B(CHIPS)':
 'VSS'<317>: CDS_PINID='VSS(317)';
NODE_NAME     U2D1 CY15
 '@BASEBOARD_FAB2_LIB.BASEBOARD_FAB2(SCH_1):PAGE75_I18@CHPSET_LIB.SKX_EXT_B(CHIPS)':
 'VSS'<318>: CDS_PINID='VSS(318)';
NODE_NAME     U2D1 CY13
 '@BASEBOARD_FAB2_LIB.BASEBOARD_FAB2(SCH_1):PAGE75_I18@CHPSET_LIB.SKX_EXT_B(CHIPS)':
 'VSS'<319>: CDS_PINID='VSS(319)';
NODE_NAME     U2D1 CY9
 '@BASEBOARD_FAB2_LIB.BASEBOARD_FAB2(SCH_1):PAGE75_I18@CHPSET_LIB.SKX_EXT_B(CHIPS)':
 'VSS'<320>: CDS_PINID='VSS(320)';
NODE_NAME     U2D1 CY1
 '@BASEBOARD_FAB2_LIB.BASEBOARD_FAB2(SCH_1):PAGE75_I18@CHPSET_LIB.SKX_EXT_B(CHIPS)':
 'VSS'<321>: CDS_PINID='VSS(321)';
NODE_NAME     U2D1 CW82
 '@BASEBOARD_FAB2_LIB.BASEBOARD_FAB2(SCH_1):PAGE75_I18@CHPSET_LIB.SKX_EXT_B(CHIPS)':
 'VSS'<322>: CDS_PINID='VSS(322)';
NODE_NAME     U2D1 CW78
 '@BASEBOARD_FAB2_LIB.BASEBOARD_FAB2(SCH_1):PAGE75_I18@CHPSET_LIB.SKX_EXT_B(CHIPS)':
 'VSS'<323>: CDS_PINID='VSS(323)';
NODE_NAME     U2D1 CW74
 '@BASEBOARD_FAB2_LIB.BASEBOARD_FAB2(SCH_1):PAGE75_I18@CHPSET_LIB.SKX_EXT_B(CHIPS)':
 'VSS'<324>: CDS_PINID='VSS(324)';
NODE_NAME     U2D1 CW68
 '@BASEBOARD_FAB2_LIB.BASEBOARD_FAB2(SCH_1):PAGE75_I18@CHPSET_LIB.SKX_EXT_B(CHIPS)':
 'VSS'<325>: CDS_PINID='VSS(325)';
NODE_NAME     U2D1 CW66
 '@BASEBOARD_FAB2_LIB.BASEBOARD_FAB2(SCH_1):PAGE75_I18@CHPSET_LIB.SKX_EXT_B(CHIPS)':
 'VSS'<326>: CDS_PINID='VSS(326)';
NODE_NAME     U2D1 CW64
 '@BASEBOARD_FAB2_LIB.BASEBOARD_FAB2(SCH_1):PAGE75_I18@CHPSET_LIB.SKX_EXT_B(CHIPS)':
 'VSS'<327>: CDS_PINID='VSS(327)';
NODE_NAME     U2D1 CW54
 '@BASEBOARD_FAB2_LIB.BASEBOARD_FAB2(SCH_1):PAGE75_I18@CHPSET_LIB.SKX_EXT_B(CHIPS)':
 'VSS'<328>: CDS_PINID='VSS(328)';
NODE_NAME     U2D1 CW52
 '@BASEBOARD_FAB2_LIB.BASEBOARD_FAB2(SCH_1):PAGE75_I18@CHPSET_LIB.SKX_EXT_B(CHIPS)':
 'VSS'<329>: CDS_PINID='VSS(329)';
NODE_NAME     U2D1 CW42
 '@BASEBOARD_FAB2_LIB.BASEBOARD_FAB2(SCH_1):PAGE75_I18@CHPSET_LIB.SKX_EXT_B(CHIPS)':
 'VSS'<330>: CDS_PINID='VSS(330)';
NODE_NAME     U2D1 CW40
 '@BASEBOARD_FAB2_LIB.BASEBOARD_FAB2(SCH_1):PAGE75_I18@CHPSET_LIB.SKX_EXT_B(CHIPS)':
 'VSS'<331>: CDS_PINID='VSS(331)';
NODE_NAME     U2D1 CW38
 '@BASEBOARD_FAB2_LIB.BASEBOARD_FAB2(SCH_1):PAGE75_I18@CHPSET_LIB.SKX_EXT_B(CHIPS)':
 'VSS'<332>: CDS_PINID='VSS(332)';
NODE_NAME     U2D1 CW32
 '@BASEBOARD_FAB2_LIB.BASEBOARD_FAB2(SCH_1):PAGE75_I18@CHPSET_LIB.SKX_EXT_B(CHIPS)':
 'VSS'<333>: CDS_PINID='VSS(333)';
NODE_NAME     U2D1 CW26
 '@BASEBOARD_FAB2_LIB.BASEBOARD_FAB2(SCH_1):PAGE75_I18@CHPSET_LIB.SKX_EXT_B(CHIPS)':
 'VSS'<334>: CDS_PINID='VSS(334)';
NODE_NAME     U2D1 CW12
 '@BASEBOARD_FAB2_LIB.BASEBOARD_FAB2(SCH_1):PAGE75_I18@CHPSET_LIB.SKX_EXT_B(CHIPS)':
 'VSS'<335>: CDS_PINID='VSS(335)';
NODE_NAME     U2D1 CV83
 '@BASEBOARD_FAB2_LIB.BASEBOARD_FAB2(SCH_1):PAGE75_I18@CHPSET_LIB.SKX_EXT_B(CHIPS)':
 'VSS'<336>: CDS_PINID='VSS(336)';
NODE_NAME     U2D1 CV81
 '@BASEBOARD_FAB2_LIB.BASEBOARD_FAB2(SCH_1):PAGE75_I18@CHPSET_LIB.SKX_EXT_B(CHIPS)':
 'VSS'<337>: CDS_PINID='VSS(337)';
NODE_NAME     U2D1 CV79
 '@BASEBOARD_FAB2_LIB.BASEBOARD_FAB2(SCH_1):PAGE75_I18@CHPSET_LIB.SKX_EXT_B(CHIPS)':
 'VSS'<338>: CDS_PINID='VSS(338)';
NODE_NAME     U2D1 CV73
 '@BASEBOARD_FAB2_LIB.BASEBOARD_FAB2(SCH_1):PAGE75_I18@CHPSET_LIB.SKX_EXT_B(CHIPS)':
 'VSS'<339>: CDS_PINID='VSS(339)';
NODE_NAME     U2D1 CV67
 '@BASEBOARD_FAB2_LIB.BASEBOARD_FAB2(SCH_1):PAGE75_I18@CHPSET_LIB.SKX_EXT_B(CHIPS)':
 'VSS'<340>: CDS_PINID='VSS(340)';
NODE_NAME     U2D1 CV63
 '@BASEBOARD_FAB2_LIB.BASEBOARD_FAB2(SCH_1):PAGE75_I18@CHPSET_LIB.SKX_EXT_B(CHIPS)':
 'VSS'<341>: CDS_PINID='VSS(341)';
NODE_NAME     U2D1 CV55
 '@BASEBOARD_FAB2_LIB.BASEBOARD_FAB2(SCH_1):PAGE75_I18@CHPSET_LIB.SKX_EXT_B(CHIPS)':
 'VSS'<342>: CDS_PINID='VSS(342)';
NODE_NAME     U2D1 CV53
 '@BASEBOARD_FAB2_LIB.BASEBOARD_FAB2(SCH_1):PAGE75_I18@CHPSET_LIB.SKX_EXT_B(CHIPS)':
 'VSS'<343>: CDS_PINID='VSS(343)';
NODE_NAME     U2D1 CV41
 '@BASEBOARD_FAB2_LIB.BASEBOARD_FAB2(SCH_1):PAGE75_I18@CHPSET_LIB.SKX_EXT_B(CHIPS)':
 'VSS'<344>: CDS_PINID='VSS(344)';
NODE_NAME     U2D1 CV39
 '@BASEBOARD_FAB2_LIB.BASEBOARD_FAB2(SCH_1):PAGE75_I18@CHPSET_LIB.SKX_EXT_B(CHIPS)':
 'VSS'<345>: CDS_PINID='VSS(345)';
NODE_NAME     U2D1 CV37
 '@BASEBOARD_FAB2_LIB.BASEBOARD_FAB2(SCH_1):PAGE75_I18@CHPSET_LIB.SKX_EXT_B(CHIPS)':
 'VSS'<346>: CDS_PINID='VSS(346)';
NODE_NAME     U2D1 CV33
 '@BASEBOARD_FAB2_LIB.BASEBOARD_FAB2(SCH_1):PAGE75_I18@CHPSET_LIB.SKX_EXT_B(CHIPS)':
 'VSS'<347>: CDS_PINID='VSS(347)';
NODE_NAME     U2D1 CV31
 '@BASEBOARD_FAB2_LIB.BASEBOARD_FAB2(SCH_1):PAGE75_I18@CHPSET_LIB.SKX_EXT_B(CHIPS)':
 'VSS'<348>: CDS_PINID='VSS(348)';
NODE_NAME     U2D1 CV27
 '@BASEBOARD_FAB2_LIB.BASEBOARD_FAB2(SCH_1):PAGE75_I18@CHPSET_LIB.SKX_EXT_B(CHIPS)':
 'VSS'<349>: CDS_PINID='VSS(349)';
NODE_NAME     U2D1 CV25
 '@BASEBOARD_FAB2_LIB.BASEBOARD_FAB2(SCH_1):PAGE75_I18@CHPSET_LIB.SKX_EXT_B(CHIPS)':
 'VSS'<350>: CDS_PINID='VSS(350)';
NODE_NAME     U2D1 CV17
 '@BASEBOARD_FAB2_LIB.BASEBOARD_FAB2(SCH_1):PAGE75_I18@CHPSET_LIB.SKX_EXT_B(CHIPS)':
 'VSS'<351>: CDS_PINID='VSS(351)';
NODE_NAME     U2D1 H55
 '@BASEBOARD_FAB2_LIB.BASEBOARD_FAB2(SCH_1):PAGE75_I18@CHPSET_LIB.SKX_EXT_B(CHIPS)':
 'VSS'<352>: CDS_PINID='VSS(352)';
NODE_NAME     U2D1 CV1
 '@BASEBOARD_FAB2_LIB.BASEBOARD_FAB2(SCH_1):PAGE75_I18@CHPSET_LIB.SKX_EXT_B(CHIPS)':
 'VSS'<353>: CDS_PINID='VSS(353)';
NODE_NAME     U2D1 CU86
 '@BASEBOARD_FAB2_LIB.BASEBOARD_FAB2(SCH_1):PAGE75_I18@CHPSET_LIB.SKX_EXT_B(CHIPS)':
 'VSS'<354>: CDS_PINID='VSS(354)';
NODE_NAME     U2D1 CU82
 '@BASEBOARD_FAB2_LIB.BASEBOARD_FAB2(SCH_1):PAGE75_I18@CHPSET_LIB.SKX_EXT_B(CHIPS)':
 'VSS'<355>: CDS_PINID='VSS(355)';
NODE_NAME     U2D1 CU80
 '@BASEBOARD_FAB2_LIB.BASEBOARD_FAB2(SCH_1):PAGE75_I18@CHPSET_LIB.SKX_EXT_B(CHIPS)':
 'VSS'<356>: CDS_PINID='VSS(356)';
NODE_NAME     U2D1 CU78
 '@BASEBOARD_FAB2_LIB.BASEBOARD_FAB2(SCH_1):PAGE75_I18@CHPSET_LIB.SKX_EXT_B(CHIPS)':
 'VSS'<357>: CDS_PINID='VSS(357)';
NODE_NAME     U2D1 CU76
 '@BASEBOARD_FAB2_LIB.BASEBOARD_FAB2(SCH_1):PAGE75_I18@CHPSET_LIB.SKX_EXT_B(CHIPS)':
 'VSS'<358>: CDS_PINID='VSS(358)';
NODE_NAME     U2D1 CU68
 '@BASEBOARD_FAB2_LIB.BASEBOARD_FAB2(SCH_1):PAGE75_I18@CHPSET_LIB.SKX_EXT_B(CHIPS)':
 'VSS'<359>: CDS_PINID='VSS(359)';
NODE_NAME     U2D1 CU62
 '@BASEBOARD_FAB2_LIB.BASEBOARD_FAB2(SCH_1):PAGE75_I18@CHPSET_LIB.SKX_EXT_B(CHIPS)':
 'VSS'<360>: CDS_PINID='VSS(360)';
NODE_NAME     U2D1 CU56
 '@BASEBOARD_FAB2_LIB.BASEBOARD_FAB2(SCH_1):PAGE75_I18@CHPSET_LIB.SKX_EXT_B(CHIPS)':
 'VSS'<361>: CDS_PINID='VSS(361)';
NODE_NAME     U2D1 CU36
 '@BASEBOARD_FAB2_LIB.BASEBOARD_FAB2(SCH_1):PAGE75_I18@CHPSET_LIB.SKX_EXT_B(CHIPS)':
 'VSS'<362>: CDS_PINID='VSS(362)';
NODE_NAME     U2D1 CU34
 '@BASEBOARD_FAB2_LIB.BASEBOARD_FAB2(SCH_1):PAGE75_I18@CHPSET_LIB.SKX_EXT_B(CHIPS)':
 'VSS'<363>: CDS_PINID='VSS(363)';
NODE_NAME     U2D1 CU30
 '@BASEBOARD_FAB2_LIB.BASEBOARD_FAB2(SCH_1):PAGE75_I18@CHPSET_LIB.SKX_EXT_B(CHIPS)':
 'VSS'<364>: CDS_PINID='VSS(364)';
NODE_NAME     U2D1 CU28
 '@BASEBOARD_FAB2_LIB.BASEBOARD_FAB2(SCH_1):PAGE75_I18@CHPSET_LIB.SKX_EXT_B(CHIPS)':
 'VSS'<365>: CDS_PINID='VSS(365)';
NODE_NAME     U2D1 CU22
 '@BASEBOARD_FAB2_LIB.BASEBOARD_FAB2(SCH_1):PAGE75_I18@CHPSET_LIB.SKX_EXT_B(CHIPS)':
 'VSS'<366>: CDS_PINID='VSS(366)';
NODE_NAME     U2D1 CU4
 '@BASEBOARD_FAB2_LIB.BASEBOARD_FAB2(SCH_1):PAGE75_I18@CHPSET_LIB.SKX_EXT_B(CHIPS)':
 'VSS'<367>: CDS_PINID='VSS(367)';
NODE_NAME     U2D1 CT85
 '@BASEBOARD_FAB2_LIB.BASEBOARD_FAB2(SCH_1):PAGE75_I18@CHPSET_LIB.SKX_EXT_B(CHIPS)':
 'VSS'<368>: CDS_PINID='VSS(368)';
NODE_NAME     U2D1 CT83
 '@BASEBOARD_FAB2_LIB.BASEBOARD_FAB2(SCH_1):PAGE75_I18@CHPSET_LIB.SKX_EXT_B(CHIPS)':
 'VSS'<369>: CDS_PINID='VSS(369)';
NODE_NAME     U2D1 CT79
 '@BASEBOARD_FAB2_LIB.BASEBOARD_FAB2(SCH_1):PAGE75_I18@CHPSET_LIB.SKX_EXT_B(CHIPS)':
 'VSS'<370>: CDS_PINID='VSS(370)';
NODE_NAME     U2D1 CT73
 '@BASEBOARD_FAB2_LIB.BASEBOARD_FAB2(SCH_1):PAGE75_I18@CHPSET_LIB.SKX_EXT_B(CHIPS)':
 'VSS'<371>: CDS_PINID='VSS(371)';
NODE_NAME     U2D1 CT57
 '@BASEBOARD_FAB2_LIB.BASEBOARD_FAB2(SCH_1):PAGE75_I18@CHPSET_LIB.SKX_EXT_B(CHIPS)':
 'VSS'<372>: CDS_PINID='VSS(372)';
NODE_NAME     U2D1 CT35
 '@BASEBOARD_FAB2_LIB.BASEBOARD_FAB2(SCH_1):PAGE75_I18@CHPSET_LIB.SKX_EXT_B(CHIPS)':
 'VSS'<373>: CDS_PINID='VSS(373)';
NODE_NAME     U2D1 CT33
 '@BASEBOARD_FAB2_LIB.BASEBOARD_FAB2(SCH_1):PAGE75_I18@CHPSET_LIB.SKX_EXT_B(CHIPS)':
 'VSS'<374>: CDS_PINID='VSS(374)';
NODE_NAME     U2D1 CT29
 '@BASEBOARD_FAB2_LIB.BASEBOARD_FAB2(SCH_1):PAGE75_I18@CHPSET_LIB.SKX_EXT_B(CHIPS)':
 'VSS'<375>: CDS_PINID='VSS(375)';
NODE_NAME     U2D1 CT27
 '@BASEBOARD_FAB2_LIB.BASEBOARD_FAB2(SCH_1):PAGE75_I18@CHPSET_LIB.SKX_EXT_B(CHIPS)':
 'VSS'<376>: CDS_PINID='VSS(376)';
NODE_NAME     U2D1 CT19
 '@BASEBOARD_FAB2_LIB.BASEBOARD_FAB2(SCH_1):PAGE75_I18@CHPSET_LIB.SKX_EXT_B(CHIPS)':
 'VSS'<377>: CDS_PINID='VSS(377)';
NODE_NAME     U2D1 CT13
 '@BASEBOARD_FAB2_LIB.BASEBOARD_FAB2(SCH_1):PAGE75_I18@CHPSET_LIB.SKX_EXT_B(CHIPS)':
 'VSS'<378>: CDS_PINID='VSS(378)';
NODE_NAME     U2D1 H57
 '@BASEBOARD_FAB2_LIB.BASEBOARD_FAB2(SCH_1):PAGE75_I18@CHPSET_LIB.SKX_EXT_B(CHIPS)':
 'VSS'<379>: CDS_PINID='VSS(379)';
NODE_NAME     U2D1 CR86
 '@BASEBOARD_FAB2_LIB.BASEBOARD_FAB2(SCH_1):PAGE75_I18@CHPSET_LIB.SKX_EXT_B(CHIPS)':
 'VSS'<380>: CDS_PINID='VSS(380)';
NODE_NAME     U2D1 CR78
 '@BASEBOARD_FAB2_LIB.BASEBOARD_FAB2(SCH_1):PAGE75_I18@CHPSET_LIB.SKX_EXT_B(CHIPS)':
 'VSS'<381>: CDS_PINID='VSS(381)';
NODE_NAME     U2D1 CR68
 '@BASEBOARD_FAB2_LIB.BASEBOARD_FAB2(SCH_1):PAGE75_I18@CHPSET_LIB.SKX_EXT_B(CHIPS)':
 'VSS'<382>: CDS_PINID='VSS(382)';
NODE_NAME     U2D1 CR66
 '@BASEBOARD_FAB2_LIB.BASEBOARD_FAB2(SCH_1):PAGE75_I18@CHPSET_LIB.SKX_EXT_B(CHIPS)':
 'VSS'<383>: CDS_PINID='VSS(383)';
NODE_NAME     U2D1 CR64
 '@BASEBOARD_FAB2_LIB.BASEBOARD_FAB2(SCH_1):PAGE75_I18@CHPSET_LIB.SKX_EXT_B(CHIPS)':
 'VSS'<384>: CDS_PINID='VSS(384)';
NODE_NAME     U2D1 CR62
 '@BASEBOARD_FAB2_LIB.BASEBOARD_FAB2(SCH_1):PAGE75_I18@CHPSET_LIB.SKX_EXT_B(CHIPS)':
 'VSS'<385>: CDS_PINID='VSS(385)';
NODE_NAME     U2D1 CR58
 '@BASEBOARD_FAB2_LIB.BASEBOARD_FAB2(SCH_1):PAGE75_I18@CHPSET_LIB.SKX_EXT_B(CHIPS)':
 'VSS'<386>: CDS_PINID='VSS(386)';
NODE_NAME     U2D1 CR32
 '@BASEBOARD_FAB2_LIB.BASEBOARD_FAB2(SCH_1):PAGE75_I18@CHPSET_LIB.SKX_EXT_B(CHIPS)':
 'VSS'<387>: CDS_PINID='VSS(387)';
NODE_NAME     U2D1 CR24
 '@BASEBOARD_FAB2_LIB.BASEBOARD_FAB2(SCH_1):PAGE75_I18@CHPSET_LIB.SKX_EXT_B(CHIPS)':
 'VSS'<388>: CDS_PINID='VSS(388)';
NODE_NAME     U2D1 CR22
 '@BASEBOARD_FAB2_LIB.BASEBOARD_FAB2(SCH_1):PAGE75_I18@CHPSET_LIB.SKX_EXT_B(CHIPS)':
 'VSS'<389>: CDS_PINID='VSS(389)';
NODE_NAME     U2D1 CR10
 '@BASEBOARD_FAB2_LIB.BASEBOARD_FAB2(SCH_1):PAGE75_I18@CHPSET_LIB.SKX_EXT_B(CHIPS)':
 'VSS'<390>: CDS_PINID='VSS(390)';
NODE_NAME     U2D1 CR6
 '@BASEBOARD_FAB2_LIB.BASEBOARD_FAB2(SCH_1):PAGE75_I18@CHPSET_LIB.SKX_EXT_B(CHIPS)':
 'VSS'<391>: CDS_PINID='VSS(391)';
NODE_NAME     U2D1 CP83
 '@BASEBOARD_FAB2_LIB.BASEBOARD_FAB2(SCH_1):PAGE75_I18@CHPSET_LIB.SKX_EXT_B(CHIPS)':
 'VSS'<392>: CDS_PINID='VSS(392)';
NODE_NAME     U2D1 CP81
 '@BASEBOARD_FAB2_LIB.BASEBOARD_FAB2(SCH_1):PAGE75_I18@CHPSET_LIB.SKX_EXT_B(CHIPS)':
 'VSS'<393>: CDS_PINID='VSS(393)';
NODE_NAME     U2D1 CP75
 '@BASEBOARD_FAB2_LIB.BASEBOARD_FAB2(SCH_1):PAGE75_I18@CHPSET_LIB.SKX_EXT_B(CHIPS)':
 'VSS'<394>: CDS_PINID='VSS(394)';
NODE_NAME     U2D1 CP73
 '@BASEBOARD_FAB2_LIB.BASEBOARD_FAB2(SCH_1):PAGE75_I18@CHPSET_LIB.SKX_EXT_B(CHIPS)':
 'VSS'<395>: CDS_PINID='VSS(395)';
NODE_NAME     U2D1 CP69
 '@BASEBOARD_FAB2_LIB.BASEBOARD_FAB2(SCH_1):PAGE75_I18@CHPSET_LIB.SKX_EXT_B(CHIPS)':
 'VSS'<396>: CDS_PINID='VSS(396)';
NODE_NAME     U2D1 CP59
 '@BASEBOARD_FAB2_LIB.BASEBOARD_FAB2(SCH_1):PAGE75_I18@CHPSET_LIB.SKX_EXT_B(CHIPS)':
 'VSS'<397>: CDS_PINID='VSS(397)';
NODE_NAME     U2D1 CP25
 '@BASEBOARD_FAB2_LIB.BASEBOARD_FAB2(SCH_1):PAGE75_I18@CHPSET_LIB.SKX_EXT_B(CHIPS)':
 'VSS'<398>: CDS_PINID='VSS(398)';
NODE_NAME     U2D1 H59
 '@BASEBOARD_FAB2_LIB.BASEBOARD_FAB2(SCH_1):PAGE75_I18@CHPSET_LIB.SKX_EXT_B(CHIPS)':
 'VSS'<399>: CDS_PINID='VSS(399)';
NODE_NAME     U2D1 CP1
 '@BASEBOARD_FAB2_LIB.BASEBOARD_FAB2(SCH_1):PAGE75_I18@CHPSET_LIB.SKX_EXT_B(CHIPS)':
 'VSS'<400>: CDS_PINID='VSS(400)';
NODE_NAME     U2D1 CN78
 '@BASEBOARD_FAB2_LIB.BASEBOARD_FAB2(SCH_1):PAGE75_I18@CHPSET_LIB.SKX_EXT_B(CHIPS)':
 'VSS'<401>: CDS_PINID='VSS(401)';
NODE_NAME     U2D1 CN68
 '@BASEBOARD_FAB2_LIB.BASEBOARD_FAB2(SCH_1):PAGE75_I18@CHPSET_LIB.SKX_EXT_B(CHIPS)':
 'VSS'<402>: CDS_PINID='VSS(402)';
NODE_NAME     U2D1 CN62
 '@BASEBOARD_FAB2_LIB.BASEBOARD_FAB2(SCH_1):PAGE75_I18@CHPSET_LIB.SKX_EXT_B(CHIPS)':
 'VSS'<403>: CDS_PINID='VSS(403)';
NODE_NAME     U2D1 CN60
 '@BASEBOARD_FAB2_LIB.BASEBOARD_FAB2(SCH_1):PAGE75_I18@CHPSET_LIB.SKX_EXT_B(CHIPS)':
 'VSS'<404>: CDS_PINID='VSS(404)';
NODE_NAME     U2D1 CN32
 '@BASEBOARD_FAB2_LIB.BASEBOARD_FAB2(SCH_1):PAGE75_I18@CHPSET_LIB.SKX_EXT_B(CHIPS)':
 'VSS'<405>: CDS_PINID='VSS(405)';
NODE_NAME     U2D1 CN26
 '@BASEBOARD_FAB2_LIB.BASEBOARD_FAB2(SCH_1):PAGE75_I18@CHPSET_LIB.SKX_EXT_B(CHIPS)':
 'VSS'<406>: CDS_PINID='VSS(406)';
NODE_NAME     U2D1 H61
 '@BASEBOARD_FAB2_LIB.BASEBOARD_FAB2(SCH_1):PAGE75_I18@CHPSET_LIB.SKX_EXT_B(CHIPS)':
 'VSS'<407>: CDS_PINID='VSS(407)';
NODE_NAME     U2D1 CN12
 '@BASEBOARD_FAB2_LIB.BASEBOARD_FAB2(SCH_1):PAGE75_I18@CHPSET_LIB.SKX_EXT_B(CHIPS)':
 'VSS'<408>: CDS_PINID='VSS(408)';
NODE_NAME     U2D1 CN2
 '@BASEBOARD_FAB2_LIB.BASEBOARD_FAB2(SCH_1):PAGE75_I18@CHPSET_LIB.SKX_EXT_B(CHIPS)':
 'VSS'<409>: CDS_PINID='VSS(409)';
NODE_NAME     U2D1 CM85
 '@BASEBOARD_FAB2_LIB.BASEBOARD_FAB2(SCH_1):PAGE75_I18@CHPSET_LIB.SKX_EXT_B(CHIPS)':
 'VSS'<410>: CDS_PINID='VSS(410)';
NODE_NAME     U2D1 CM83
 '@BASEBOARD_FAB2_LIB.BASEBOARD_FAB2(SCH_1):PAGE75_I18@CHPSET_LIB.SKX_EXT_B(CHIPS)':
 'VSS'<411>: CDS_PINID='VSS(411)';
NODE_NAME     U2D1 CM77
 '@BASEBOARD_FAB2_LIB.BASEBOARD_FAB2(SCH_1):PAGE75_I18@CHPSET_LIB.SKX_EXT_B(CHIPS)':
 'VSS'<412>: CDS_PINID='VSS(412)';
NODE_NAME     U2D1 CM73
 '@BASEBOARD_FAB2_LIB.BASEBOARD_FAB2(SCH_1):PAGE75_I18@CHPSET_LIB.SKX_EXT_B(CHIPS)':
 'VSS'<413>: CDS_PINID='VSS(413)';
NODE_NAME     U2D1 CM67
 '@BASEBOARD_FAB2_LIB.BASEBOARD_FAB2(SCH_1):PAGE75_I18@CHPSET_LIB.SKX_EXT_B(CHIPS)':
 'VSS'<414>: CDS_PINID='VSS(414)';
NODE_NAME     U2D1 CM63
 '@BASEBOARD_FAB2_LIB.BASEBOARD_FAB2(SCH_1):PAGE75_I18@CHPSET_LIB.SKX_EXT_B(CHIPS)':
 'VSS'<415>: CDS_PINID='VSS(415)';
NODE_NAME     U2D1 CM61
 '@BASEBOARD_FAB2_LIB.BASEBOARD_FAB2(SCH_1):PAGE75_I18@CHPSET_LIB.SKX_EXT_B(CHIPS)':
 'VSS'<416>: CDS_PINID='VSS(416)';
NODE_NAME     U2D1 CM31
 '@BASEBOARD_FAB2_LIB.BASEBOARD_FAB2(SCH_1):PAGE75_I18@CHPSET_LIB.SKX_EXT_B(CHIPS)':
 'VSS'<417>: CDS_PINID='VSS(417)';
NODE_NAME     U2D1 CM5
 '@BASEBOARD_FAB2_LIB.BASEBOARD_FAB2(SCH_1):PAGE75_I18@CHPSET_LIB.SKX_EXT_B(CHIPS)':
 'VSS'<418>: CDS_PINID='VSS(418)';
NODE_NAME     U2D1 CM29
 '@BASEBOARD_FAB2_LIB.BASEBOARD_FAB2(SCH_1):PAGE75_I18@CHPSET_LIB.SKX_EXT_B(CHIPS)':
 'VSS'<419>: CDS_PINID='VSS(419)';
NODE_NAME     U2D1 CM19
 '@BASEBOARD_FAB2_LIB.BASEBOARD_FAB2(SCH_1):PAGE75_I18@CHPSET_LIB.SKX_EXT_B(CHIPS)':
 'VSS'<420>: CDS_PINID='VSS(420)';
NODE_NAME     U2D1 CL80
 '@BASEBOARD_FAB2_LIB.BASEBOARD_FAB2(SCH_1):PAGE75_I18@CHPSET_LIB.SKX_EXT_B(CHIPS)':
 'VSS'<421>: CDS_PINID='VSS(421)';
NODE_NAME     U2D1 CL78
 '@BASEBOARD_FAB2_LIB.BASEBOARD_FAB2(SCH_1):PAGE75_I18@CHPSET_LIB.SKX_EXT_B(CHIPS)':
 'VSS'<422>: CDS_PINID='VSS(422)';
NODE_NAME     U2D1 CL76
 '@BASEBOARD_FAB2_LIB.BASEBOARD_FAB2(SCH_1):PAGE75_I18@CHPSET_LIB.SKX_EXT_B(CHIPS)':
 'VSS'<423>: CDS_PINID='VSS(423)';
NODE_NAME     U2D1 CL74
 '@BASEBOARD_FAB2_LIB.BASEBOARD_FAB2(SCH_1):PAGE75_I18@CHPSET_LIB.SKX_EXT_B(CHIPS)':
 'VSS'<424>: CDS_PINID='VSS(424)';
NODE_NAME     U2D1 CL66
 '@BASEBOARD_FAB2_LIB.BASEBOARD_FAB2(SCH_1):PAGE75_I18@CHPSET_LIB.SKX_EXT_B(CHIPS)':
 'VSS'<425>: CDS_PINID='VSS(425)';
NODE_NAME     U2D1 CL64
 '@BASEBOARD_FAB2_LIB.BASEBOARD_FAB2(SCH_1):PAGE75_I18@CHPSET_LIB.SKX_EXT_B(CHIPS)':
 'VSS'<426>: CDS_PINID='VSS(426)';
NODE_NAME     U2D1 CL62
 '@BASEBOARD_FAB2_LIB.BASEBOARD_FAB2(SCH_1):PAGE75_I18@CHPSET_LIB.SKX_EXT_B(CHIPS)':
 'VSS'<427>: CDS_PINID='VSS(427)';
NODE_NAME     U2D1 H63
 '@BASEBOARD_FAB2_LIB.BASEBOARD_FAB2(SCH_1):PAGE75_I18@CHPSET_LIB.SKX_EXT_B(CHIPS)':
 'VSS'<428>: CDS_PINID='VSS(428)';
NODE_NAME     U2D1 P45
 '@BASEBOARD_FAB2_LIB.BASEBOARD_FAB2(SCH_1):PAGE75_I18@CHPSET_LIB.SKX_EXT_B(CHIPS)':
 'VSS'<429>: CDS_PINID='VSS(429)';
NODE_NAME     U2D1 CL18
 '@BASEBOARD_FAB2_LIB.BASEBOARD_FAB2(SCH_1):PAGE75_I18@CHPSET_LIB.SKX_EXT_B(CHIPS)':
 'VSS'<430>: CDS_PINID='VSS(430)';
NODE_NAME     U2D1 CL14
 '@BASEBOARD_FAB2_LIB.BASEBOARD_FAB2(SCH_1):PAGE75_I18@CHPSET_LIB.SKX_EXT_B(CHIPS)':
 'VSS'<431>: CDS_PINID='VSS(431)';
NODE_NAME     U2D1 CL8
 '@BASEBOARD_FAB2_LIB.BASEBOARD_FAB2(SCH_1):PAGE75_I18@CHPSET_LIB.SKX_EXT_B(CHIPS)':
 'VSS'<432>: CDS_PINID='VSS(432)';
NODE_NAME     U2D1 CK85
 '@BASEBOARD_FAB2_LIB.BASEBOARD_FAB2(SCH_1):PAGE75_I18@CHPSET_LIB.SKX_EXT_B(CHIPS)':
 'VSS'<433>: CDS_PINID='VSS(433)';
NODE_NAME     U2D1 CK83
 '@BASEBOARD_FAB2_LIB.BASEBOARD_FAB2(SCH_1):PAGE75_I18@CHPSET_LIB.SKX_EXT_B(CHIPS)':
 'VSS'<434>: CDS_PINID='VSS(434)';
NODE_NAME     U2D1 CK75
 '@BASEBOARD_FAB2_LIB.BASEBOARD_FAB2(SCH_1):PAGE75_I18@CHPSET_LIB.SKX_EXT_B(CHIPS)':
 'VSS'<435>: CDS_PINID='VSS(435)';
NODE_NAME     U2D1 CK73
 '@BASEBOARD_FAB2_LIB.BASEBOARD_FAB2(SCH_1):PAGE75_I18@CHPSET_LIB.SKX_EXT_B(CHIPS)':
 'VSS'<436>: CDS_PINID='VSS(436)';
NODE_NAME     U2D1 CK71
 '@BASEBOARD_FAB2_LIB.BASEBOARD_FAB2(SCH_1):PAGE75_I18@CHPSET_LIB.SKX_EXT_B(CHIPS)':
 'VSS'<437>: CDS_PINID='VSS(437)';
NODE_NAME     U2D1 CK69
 '@BASEBOARD_FAB2_LIB.BASEBOARD_FAB2(SCH_1):PAGE75_I18@CHPSET_LIB.SKX_EXT_B(CHIPS)':
 'VSS'<438>: CDS_PINID='VSS(438)';
NODE_NAME     U2D1 CK67
 '@BASEBOARD_FAB2_LIB.BASEBOARD_FAB2(SCH_1):PAGE75_I18@CHPSET_LIB.SKX_EXT_B(CHIPS)':
 'VSS'<439>: CDS_PINID='VSS(439)';
NODE_NAME     U2D1 CK65
 '@BASEBOARD_FAB2_LIB.BASEBOARD_FAB2(SCH_1):PAGE75_I18@CHPSET_LIB.SKX_EXT_B(CHIPS)':
 'VSS'<440>: CDS_PINID='VSS(440)';
NODE_NAME     U2D1 CK63
 '@BASEBOARD_FAB2_LIB.BASEBOARD_FAB2(SCH_1):PAGE75_I18@CHPSET_LIB.SKX_EXT_B(CHIPS)':
 'VSS'<441>: CDS_PINID='VSS(441)';
NODE_NAME     U2D1 CK27
 '@BASEBOARD_FAB2_LIB.BASEBOARD_FAB2(SCH_1):PAGE75_I18@CHPSET_LIB.SKX_EXT_B(CHIPS)':
 'VSS'<442>: CDS_PINID='VSS(442)';
NODE_NAME     U2D1 CK21
 '@BASEBOARD_FAB2_LIB.BASEBOARD_FAB2(SCH_1):PAGE75_I18@CHPSET_LIB.SKX_EXT_B(CHIPS)':
 'VSS'<443>: CDS_PINID='VSS(443)';
NODE_NAME     U2D1 CK15
 '@BASEBOARD_FAB2_LIB.BASEBOARD_FAB2(SCH_1):PAGE75_I18@CHPSET_LIB.SKX_EXT_B(CHIPS)':
 'VSS'<444>: CDS_PINID='VSS(444)';
NODE_NAME     U2D1 CK11
 '@BASEBOARD_FAB2_LIB.BASEBOARD_FAB2(SCH_1):PAGE75_I18@CHPSET_LIB.SKX_EXT_B(CHIPS)':
 'VSS'<445>: CDS_PINID='VSS(445)';
NODE_NAME     U2D1 CJ86
 '@BASEBOARD_FAB2_LIB.BASEBOARD_FAB2(SCH_1):PAGE75_I18@CHPSET_LIB.SKX_EXT_B(CHIPS)':
 'VSS'<446>: CDS_PINID='VSS(446)';
NODE_NAME     U2D1 CJ84
 '@BASEBOARD_FAB2_LIB.BASEBOARD_FAB2(SCH_1):PAGE75_I18@CHPSET_LIB.SKX_EXT_B(CHIPS)':
 'VSS'<447>: CDS_PINID='VSS(447)';
NODE_NAME     U2D1 CJ82
 '@BASEBOARD_FAB2_LIB.BASEBOARD_FAB2(SCH_1):PAGE75_I18@CHPSET_LIB.SKX_EXT_B(CHIPS)':
 'VSS'<448>: CDS_PINID='VSS(448)';
NODE_NAME     U2D1 CJ78
 '@BASEBOARD_FAB2_LIB.BASEBOARD_FAB2(SCH_1):PAGE75_I18@CHPSET_LIB.SKX_EXT_B(CHIPS)':
 'VSS'<449>: CDS_PINID='VSS(449)';
NODE_NAME     U2D1 CJ76
 '@BASEBOARD_FAB2_LIB.BASEBOARD_FAB2(SCH_1):PAGE75_I18@CHPSET_LIB.SKX_EXT_B(CHIPS)':
 'VSS'<450>: CDS_PINID='VSS(450)';
NODE_NAME     U2D1 CJ74
 '@BASEBOARD_FAB2_LIB.BASEBOARD_FAB2(SCH_1):PAGE75_I18@CHPSET_LIB.SKX_EXT_B(CHIPS)':
 'VSS'<451>: CDS_PINID='VSS(451)';
NODE_NAME     U2D1 CJ62
 '@BASEBOARD_FAB2_LIB.BASEBOARD_FAB2(SCH_1):PAGE75_I18@CHPSET_LIB.SKX_EXT_B(CHIPS)':
 'VSS'<452>: CDS_PINID='VSS(452)';
NODE_NAME     U2D1 P47
 '@BASEBOARD_FAB2_LIB.BASEBOARD_FAB2(SCH_1):PAGE75_I18@CHPSET_LIB.SKX_EXT_B(CHIPS)':
 'VSS'<453>: CDS_PINID='VSS(453)';
NODE_NAME     U2D1 DN72
 '@BASEBOARD_FAB2_LIB.BASEBOARD_FAB2(SCH_1):PAGE75_I19@CHPSET_LIB.SKX_EXT_B(CHIPS)':
 'VSS'<134>: CDS_PINID='VSS(134)';
NODE_NAME     U2D1 DN68
 '@BASEBOARD_FAB2_LIB.BASEBOARD_FAB2(SCH_1):PAGE75_I19@CHPSET_LIB.SKX_EXT_B(CHIPS)':
 'VSS'<135>: CDS_PINID='VSS(135)';
NODE_NAME     U2D1 DN38
 '@BASEBOARD_FAB2_LIB.BASEBOARD_FAB2(SCH_1):PAGE75_I19@CHPSET_LIB.SKX_EXT_B(CHIPS)':
 'VSS'<136>: CDS_PINID='VSS(136)';
NODE_NAME     U2D1 DN32
 '@BASEBOARD_FAB2_LIB.BASEBOARD_FAB2(SCH_1):PAGE75_I19@CHPSET_LIB.SKX_EXT_B(CHIPS)':
 'VSS'<137>: CDS_PINID='VSS(137)';
NODE_NAME     U2D1 DN26
 '@BASEBOARD_FAB2_LIB.BASEBOARD_FAB2(SCH_1):PAGE75_I19@CHPSET_LIB.SKX_EXT_B(CHIPS)':
 'VSS'<138>: CDS_PINID='VSS(138)';
NODE_NAME     U2D1 DN22
 '@BASEBOARD_FAB2_LIB.BASEBOARD_FAB2(SCH_1):PAGE75_I19@CHPSET_LIB.SKX_EXT_B(CHIPS)':
 'VSS'<139>: CDS_PINID='VSS(139)';
NODE_NAME     U2D1 DN12
 '@BASEBOARD_FAB2_LIB.BASEBOARD_FAB2(SCH_1):PAGE75_I19@CHPSET_LIB.SKX_EXT_B(CHIPS)':
 'VSS'<140>: CDS_PINID='VSS(140)';
NODE_NAME     U2D1 BH17
 '@BASEBOARD_FAB2_LIB.BASEBOARD_FAB2(SCH_1):PAGE75_I19@CHPSET_LIB.SKX_EXT_B(CHIPS)':
 'VSS'<141>: CDS_PINID='VSS(141)';
NODE_NAME     U2D1 DN2
 '@BASEBOARD_FAB2_LIB.BASEBOARD_FAB2(SCH_1):PAGE75_I19@CHPSET_LIB.SKX_EXT_B(CHIPS)':
 'VSS'<142>: CDS_PINID='VSS(142)';
NODE_NAME     U2D1 DM83
 '@BASEBOARD_FAB2_LIB.BASEBOARD_FAB2(SCH_1):PAGE75_I19@CHPSET_LIB.SKX_EXT_B(CHIPS)':
 'VSS'<143>: CDS_PINID='VSS(143)';
NODE_NAME     U2D1 DM77
 '@BASEBOARD_FAB2_LIB.BASEBOARD_FAB2(SCH_1):PAGE75_I19@CHPSET_LIB.SKX_EXT_B(CHIPS)':
 'VSS'<144>: CDS_PINID='VSS(144)';
NODE_NAME     U2D1 DM73
 '@BASEBOARD_FAB2_LIB.BASEBOARD_FAB2(SCH_1):PAGE75_I19@CHPSET_LIB.SKX_EXT_B(CHIPS)':
 'VSS'<145>: CDS_PINID='VSS(145)';
NODE_NAME     U2D1 DM65
 '@BASEBOARD_FAB2_LIB.BASEBOARD_FAB2(SCH_1):PAGE75_I19@CHPSET_LIB.SKX_EXT_B(CHIPS)':
 'VSS'<146>: CDS_PINID='VSS(146)';
NODE_NAME     U2D1 DM39
 '@BASEBOARD_FAB2_LIB.BASEBOARD_FAB2(SCH_1):PAGE75_I19@CHPSET_LIB.SKX_EXT_B(CHIPS)':
 'VSS'<147>: CDS_PINID='VSS(147)';
NODE_NAME     U2D1 DM37
 '@BASEBOARD_FAB2_LIB.BASEBOARD_FAB2(SCH_1):PAGE75_I19@CHPSET_LIB.SKX_EXT_B(CHIPS)':
 'VSS'<148>: CDS_PINID='VSS(148)';
NODE_NAME     U2D1 DM33
 '@BASEBOARD_FAB2_LIB.BASEBOARD_FAB2(SCH_1):PAGE75_I19@CHPSET_LIB.SKX_EXT_B(CHIPS)':
 'VSS'<149>: CDS_PINID='VSS(149)';
NODE_NAME     U2D1 DM31
 '@BASEBOARD_FAB2_LIB.BASEBOARD_FAB2(SCH_1):PAGE75_I19@CHPSET_LIB.SKX_EXT_B(CHIPS)':
 'VSS'<150>: CDS_PINID='VSS(150)';
NODE_NAME     U2D1 DM27
 '@BASEBOARD_FAB2_LIB.BASEBOARD_FAB2(SCH_1):PAGE75_I19@CHPSET_LIB.SKX_EXT_B(CHIPS)':
 'VSS'<151>: CDS_PINID='VSS(151)';
NODE_NAME     U2D1 DM25
 '@BASEBOARD_FAB2_LIB.BASEBOARD_FAB2(SCH_1):PAGE75_I19@CHPSET_LIB.SKX_EXT_B(CHIPS)':
 'VSS'<152>: CDS_PINID='VSS(152)';
NODE_NAME     U2D1 H45
 '@BASEBOARD_FAB2_LIB.BASEBOARD_FAB2(SCH_1):PAGE75_I19@CHPSET_LIB.SKX_EXT_B(CHIPS)':
 'VSS'<153>: CDS_PINID='VSS(153)';
NODE_NAME     U2D1 DM15
 '@BASEBOARD_FAB2_LIB.BASEBOARD_FAB2(SCH_1):PAGE75_I19@CHPSET_LIB.SKX_EXT_B(CHIPS)':
 'VSS'<154>: CDS_PINID='VSS(154)';
NODE_NAME     U2D1 DL80
 '@BASEBOARD_FAB2_LIB.BASEBOARD_FAB2(SCH_1):PAGE75_I19@CHPSET_LIB.SKX_EXT_B(CHIPS)':
 'VSS'<155>: CDS_PINID='VSS(155)';
NODE_NAME     U2D1 DL78
 '@BASEBOARD_FAB2_LIB.BASEBOARD_FAB2(SCH_1):PAGE75_I19@CHPSET_LIB.SKX_EXT_B(CHIPS)':
 'VSS'<156>: CDS_PINID='VSS(156)';
NODE_NAME     U2D1 DL76
 '@BASEBOARD_FAB2_LIB.BASEBOARD_FAB2(SCH_1):PAGE75_I19@CHPSET_LIB.SKX_EXT_B(CHIPS)':
 'VSS'<157>: CDS_PINID='VSS(157)';
NODE_NAME     U2D1 DL74
 '@BASEBOARD_FAB2_LIB.BASEBOARD_FAB2(SCH_1):PAGE75_I19@CHPSET_LIB.SKX_EXT_B(CHIPS)':
 'VSS'<158>: CDS_PINID='VSS(158)';
NODE_NAME     U2D1 DL70
 '@BASEBOARD_FAB2_LIB.BASEBOARD_FAB2(SCH_1):PAGE75_I19@CHPSET_LIB.SKX_EXT_B(CHIPS)':
 'VSS'<159>: CDS_PINID='VSS(159)';
NODE_NAME     U2D1 DL68
 '@BASEBOARD_FAB2_LIB.BASEBOARD_FAB2(SCH_1):PAGE75_I19@CHPSET_LIB.SKX_EXT_B(CHIPS)':
 'VSS'<160>: CDS_PINID='VSS(160)';
NODE_NAME     U2D1 DL40
 '@BASEBOARD_FAB2_LIB.BASEBOARD_FAB2(SCH_1):PAGE75_I19@CHPSET_LIB.SKX_EXT_B(CHIPS)':
 'VSS'<161>: CDS_PINID='VSS(161)';
NODE_NAME     U2D1 DL36
 '@BASEBOARD_FAB2_LIB.BASEBOARD_FAB2(SCH_1):PAGE75_I19@CHPSET_LIB.SKX_EXT_B(CHIPS)':
 'VSS'<162>: CDS_PINID='VSS(162)';
NODE_NAME     U2D1 DL34
 '@BASEBOARD_FAB2_LIB.BASEBOARD_FAB2(SCH_1):PAGE75_I19@CHPSET_LIB.SKX_EXT_B(CHIPS)':
 'VSS'<163>: CDS_PINID='VSS(163)';
NODE_NAME     U2D1 DL30
 '@BASEBOARD_FAB2_LIB.BASEBOARD_FAB2(SCH_1):PAGE75_I19@CHPSET_LIB.SKX_EXT_B(CHIPS)':
 'VSS'<164>: CDS_PINID='VSS(164)';
NODE_NAME     U2D1 DL28
 '@BASEBOARD_FAB2_LIB.BASEBOARD_FAB2(SCH_1):PAGE75_I19@CHPSET_LIB.SKX_EXT_B(CHIPS)':
 'VSS'<165>: CDS_PINID='VSS(165)';
NODE_NAME     U2D1 DL24
 '@BASEBOARD_FAB2_LIB.BASEBOARD_FAB2(SCH_1):PAGE75_I19@CHPSET_LIB.SKX_EXT_B(CHIPS)':
 'VSS'<166>: CDS_PINID='VSS(166)';
NODE_NAME     U2D1 DL22
 '@BASEBOARD_FAB2_LIB.BASEBOARD_FAB2(SCH_1):PAGE75_I19@CHPSET_LIB.SKX_EXT_B(CHIPS)':
 'VSS'<167>: CDS_PINID='VSS(167)';
NODE_NAME     U2D1 DL4
 '@BASEBOARD_FAB2_LIB.BASEBOARD_FAB2(SCH_1):PAGE75_I19@CHPSET_LIB.SKX_EXT_B(CHIPS)':
 'VSS'<168>: CDS_PINID='VSS(168)';
NODE_NAME     U2D1 DL18
 '@BASEBOARD_FAB2_LIB.BASEBOARD_FAB2(SCH_1):PAGE75_I19@CHPSET_LIB.SKX_EXT_B(CHIPS)':
 'VSS'<169>: CDS_PINID='VSS(169)';
NODE_NAME     U2D1 DL16
 '@BASEBOARD_FAB2_LIB.BASEBOARD_FAB2(SCH_1):PAGE75_I19@CHPSET_LIB.SKX_EXT_B(CHIPS)':
 'VSS'<170>: CDS_PINID='VSS(170)';
NODE_NAME     U2D1 DK85
 '@BASEBOARD_FAB2_LIB.BASEBOARD_FAB2(SCH_1):PAGE75_I19@CHPSET_LIB.SKX_EXT_B(CHIPS)':
 'VSS'<171>: CDS_PINID='VSS(171)';
NODE_NAME     U2D1 DK83
 '@BASEBOARD_FAB2_LIB.BASEBOARD_FAB2(SCH_1):PAGE75_I19@CHPSET_LIB.SKX_EXT_B(CHIPS)':
 'VSS'<172>: CDS_PINID='VSS(172)';
NODE_NAME     U2D1 DK77
 '@BASEBOARD_FAB2_LIB.BASEBOARD_FAB2(SCH_1):PAGE75_I19@CHPSET_LIB.SKX_EXT_B(CHIPS)':
 'VSS'<173>: CDS_PINID='VSS(173)';
NODE_NAME     U2D1 DK75
 '@BASEBOARD_FAB2_LIB.BASEBOARD_FAB2(SCH_1):PAGE75_I19@CHPSET_LIB.SKX_EXT_B(CHIPS)':
 'VSS'<174>: CDS_PINID='VSS(174)';
NODE_NAME     U2D1 DK73
 '@BASEBOARD_FAB2_LIB.BASEBOARD_FAB2(SCH_1):PAGE75_I19@CHPSET_LIB.SKX_EXT_B(CHIPS)':
 'VSS'<175>: CDS_PINID='VSS(175)';
NODE_NAME     U2D1 DK41
 '@BASEBOARD_FAB2_LIB.BASEBOARD_FAB2(SCH_1):PAGE75_I19@CHPSET_LIB.SKX_EXT_B(CHIPS)':
 'VSS'<176>: CDS_PINID='VSS(176)';
NODE_NAME     U2D1 DK39
 '@BASEBOARD_FAB2_LIB.BASEBOARD_FAB2(SCH_1):PAGE75_I19@CHPSET_LIB.SKX_EXT_B(CHIPS)':
 'VSS'<177>: CDS_PINID='VSS(177)';
NODE_NAME     U2D1 DK35
 '@BASEBOARD_FAB2_LIB.BASEBOARD_FAB2(SCH_1):PAGE75_I19@CHPSET_LIB.SKX_EXT_B(CHIPS)':
 'VSS'<178>: CDS_PINID='VSS(178)';
NODE_NAME     U2D1 DK29
 '@BASEBOARD_FAB2_LIB.BASEBOARD_FAB2(SCH_1):PAGE75_I19@CHPSET_LIB.SKX_EXT_B(CHIPS)':
 'VSS'<179>: CDS_PINID='VSS(179)';
NODE_NAME     U2D1 DK23
 '@BASEBOARD_FAB2_LIB.BASEBOARD_FAB2(SCH_1):PAGE75_I19@CHPSET_LIB.SKX_EXT_B(CHIPS)':
 'VSS'<180>: CDS_PINID='VSS(180)';
NODE_NAME     U2D1 DK7
 '@BASEBOARD_FAB2_LIB.BASEBOARD_FAB2(SCH_1):PAGE75_I19@CHPSET_LIB.SKX_EXT_B(CHIPS)':
 'VSS'<181>: CDS_PINID='VSS(181)';
NODE_NAME     U2D1 DJ84
 '@BASEBOARD_FAB2_LIB.BASEBOARD_FAB2(SCH_1):PAGE75_I19@CHPSET_LIB.SKX_EXT_B(CHIPS)':
 'VSS'<182>: CDS_PINID='VSS(182)';
NODE_NAME     U2D1 DJ82
 '@BASEBOARD_FAB2_LIB.BASEBOARD_FAB2(SCH_1):PAGE75_I19@CHPSET_LIB.SKX_EXT_B(CHIPS)':
 'VSS'<183>: CDS_PINID='VSS(183)';
NODE_NAME     U2D1 DJ78
 '@BASEBOARD_FAB2_LIB.BASEBOARD_FAB2(SCH_1):PAGE75_I19@CHPSET_LIB.SKX_EXT_B(CHIPS)':
 'VSS'<184>: CDS_PINID='VSS(184)';
NODE_NAME     U2D1 DJ74
 '@BASEBOARD_FAB2_LIB.BASEBOARD_FAB2(SCH_1):PAGE75_I19@CHPSET_LIB.SKX_EXT_B(CHIPS)':
 'VSS'<185>: CDS_PINID='VSS(185)';
NODE_NAME     U2D1 DJ68
 '@BASEBOARD_FAB2_LIB.BASEBOARD_FAB2(SCH_1):PAGE75_I19@CHPSET_LIB.SKX_EXT_B(CHIPS)':
 'VSS'<186>: CDS_PINID='VSS(186)';
NODE_NAME     U2D1 DJ42
 '@BASEBOARD_FAB2_LIB.BASEBOARD_FAB2(SCH_1):PAGE75_I19@CHPSET_LIB.SKX_EXT_B(CHIPS)':
 'VSS'<187>: CDS_PINID='VSS(187)';
NODE_NAME     U2D1 DJ38
 '@BASEBOARD_FAB2_LIB.BASEBOARD_FAB2(SCH_1):PAGE75_I19@CHPSET_LIB.SKX_EXT_B(CHIPS)':
 'VSS'<188>: CDS_PINID='VSS(188)';
NODE_NAME     U2D1 DJ22
 '@BASEBOARD_FAB2_LIB.BASEBOARD_FAB2(SCH_1):PAGE75_I19@CHPSET_LIB.SKX_EXT_B(CHIPS)':
 'VSS'<189>: CDS_PINID='VSS(189)';
NODE_NAME     U2D1 H47
 '@BASEBOARD_FAB2_LIB.BASEBOARD_FAB2(SCH_1):PAGE75_I19@CHPSET_LIB.SKX_EXT_B(CHIPS)':
 'VSS'<190>: CDS_PINID='VSS(190)';
NODE_NAME     U2D1 DJ10
 '@BASEBOARD_FAB2_LIB.BASEBOARD_FAB2(SCH_1):PAGE75_I19@CHPSET_LIB.SKX_EXT_B(CHIPS)':
 'VSS'<191>: CDS_PINID='VSS(191)';
NODE_NAME     U2D1 DJ2
 '@BASEBOARD_FAB2_LIB.BASEBOARD_FAB2(SCH_1):PAGE75_I19@CHPSET_LIB.SKX_EXT_B(CHIPS)':
 'VSS'<192>: CDS_PINID='VSS(192)';
NODE_NAME     U2D1 DH83
 '@BASEBOARD_FAB2_LIB.BASEBOARD_FAB2(SCH_1):PAGE75_I19@CHPSET_LIB.SKX_EXT_B(CHIPS)':
 'VSS'<193>: CDS_PINID='VSS(193)';
NODE_NAME     U2D1 DH81
 '@BASEBOARD_FAB2_LIB.BASEBOARD_FAB2(SCH_1):PAGE75_I19@CHPSET_LIB.SKX_EXT_B(CHIPS)':
 'VSS'<194>: CDS_PINID='VSS(194)';
NODE_NAME     U2D1 DH79
 '@BASEBOARD_FAB2_LIB.BASEBOARD_FAB2(SCH_1):PAGE75_I19@CHPSET_LIB.SKX_EXT_B(CHIPS)':
 'VSS'<195>: CDS_PINID='VSS(195)';
NODE_NAME     U2D1 DH73
 '@BASEBOARD_FAB2_LIB.BASEBOARD_FAB2(SCH_1):PAGE75_I19@CHPSET_LIB.SKX_EXT_B(CHIPS)':
 'VSS'<196>: CDS_PINID='VSS(196)';
NODE_NAME     U2D1 DH71
 '@BASEBOARD_FAB2_LIB.BASEBOARD_FAB2(SCH_1):PAGE75_I19@CHPSET_LIB.SKX_EXT_B(CHIPS)':
 'VSS'<197>: CDS_PINID='VSS(197)';
NODE_NAME     U2D1 DH67
 '@BASEBOARD_FAB2_LIB.BASEBOARD_FAB2(SCH_1):PAGE75_I19@CHPSET_LIB.SKX_EXT_B(CHIPS)':
 'VSS'<198>: CDS_PINID='VSS(198)';
NODE_NAME     U2D1 DH41
 '@BASEBOARD_FAB2_LIB.BASEBOARD_FAB2(SCH_1):PAGE75_I19@CHPSET_LIB.SKX_EXT_B(CHIPS)':
 'VSS'<199>: CDS_PINID='VSS(199)';
NODE_NAME     U2D1 DH37
 '@BASEBOARD_FAB2_LIB.BASEBOARD_FAB2(SCH_1):PAGE75_I19@CHPSET_LIB.SKX_EXT_B(CHIPS)':
 'VSS'<200>: CDS_PINID='VSS(200)';
NODE_NAME     U2D1 DH35
 '@BASEBOARD_FAB2_LIB.BASEBOARD_FAB2(SCH_1):PAGE75_I19@CHPSET_LIB.SKX_EXT_B(CHIPS)':
 'VSS'<201>: CDS_PINID='VSS(201)';
NODE_NAME     U2D1 DH33
 '@BASEBOARD_FAB2_LIB.BASEBOARD_FAB2(SCH_1):PAGE75_I19@CHPSET_LIB.SKX_EXT_B(CHIPS)':
 'VSS'<202>: CDS_PINID='VSS(202)';
NODE_NAME     U2D1 DH31
 '@BASEBOARD_FAB2_LIB.BASEBOARD_FAB2(SCH_1):PAGE75_I19@CHPSET_LIB.SKX_EXT_B(CHIPS)':
 'VSS'<203>: CDS_PINID='VSS(203)';
NODE_NAME     U2D1 DH29
 '@BASEBOARD_FAB2_LIB.BASEBOARD_FAB2(SCH_1):PAGE75_I19@CHPSET_LIB.SKX_EXT_B(CHIPS)':
 'VSS'<204>: CDS_PINID='VSS(204)';
NODE_NAME     U2D1 DH27
 '@BASEBOARD_FAB2_LIB.BASEBOARD_FAB2(SCH_1):PAGE75_I19@CHPSET_LIB.SKX_EXT_B(CHIPS)':
 'VSS'<205>: CDS_PINID='VSS(205)';
NODE_NAME     U2D1 DH25
 '@BASEBOARD_FAB2_LIB.BASEBOARD_FAB2(SCH_1):PAGE75_I19@CHPSET_LIB.SKX_EXT_B(CHIPS)':
 'VSS'<206>: CDS_PINID='VSS(206)';
NODE_NAME     U2D1 DH23
 '@BASEBOARD_FAB2_LIB.BASEBOARD_FAB2(SCH_1):PAGE75_I19@CHPSET_LIB.SKX_EXT_B(CHIPS)':
 'VSS'<207>: CDS_PINID='VSS(207)';
NODE_NAME     U2D1 DH15
 '@BASEBOARD_FAB2_LIB.BASEBOARD_FAB2(SCH_1):PAGE75_I19@CHPSET_LIB.SKX_EXT_B(CHIPS)':
 'VSS'<208>: CDS_PINID='VSS(208)';
NODE_NAME     U2D1 DH13
 '@BASEBOARD_FAB2_LIB.BASEBOARD_FAB2(SCH_1):PAGE75_I19@CHPSET_LIB.SKX_EXT_B(CHIPS)':
 'VSS'<209>: CDS_PINID='VSS(209)';
NODE_NAME     U2D1 DG82
 '@BASEBOARD_FAB2_LIB.BASEBOARD_FAB2(SCH_1):PAGE75_I19@CHPSET_LIB.SKX_EXT_B(CHIPS)':
 'VSS'<210>: CDS_PINID='VSS(210)';
NODE_NAME     U2D1 DG80
 '@BASEBOARD_FAB2_LIB.BASEBOARD_FAB2(SCH_1):PAGE75_I19@CHPSET_LIB.SKX_EXT_B(CHIPS)':
 'VSS'<211>: CDS_PINID='VSS(211)';
NODE_NAME     U2D1 DG78
 '@BASEBOARD_FAB2_LIB.BASEBOARD_FAB2(SCH_1):PAGE75_I19@CHPSET_LIB.SKX_EXT_B(CHIPS)':
 'VSS'<212>: CDS_PINID='VSS(212)';
NODE_NAME     U2D1 DG76
 '@BASEBOARD_FAB2_LIB.BASEBOARD_FAB2(SCH_1):PAGE75_I19@CHPSET_LIB.SKX_EXT_B(CHIPS)':
 'VSS'<213>: CDS_PINID='VSS(213)';
NODE_NAME     U2D1 DG68
 '@BASEBOARD_FAB2_LIB.BASEBOARD_FAB2(SCH_1):PAGE75_I19@CHPSET_LIB.SKX_EXT_B(CHIPS)':
 'VSS'<214>: CDS_PINID='VSS(214)';
NODE_NAME     U2D1 DG66
 '@BASEBOARD_FAB2_LIB.BASEBOARD_FAB2(SCH_1):PAGE75_I19@CHPSET_LIB.SKX_EXT_B(CHIPS)':
 'VSS'<215>: CDS_PINID='VSS(215)';
NODE_NAME     U2D1 DG24
 '@BASEBOARD_FAB2_LIB.BASEBOARD_FAB2(SCH_1):PAGE75_I19@CHPSET_LIB.SKX_EXT_B(CHIPS)':
 'VSS'<216>: CDS_PINID='VSS(216)';
NODE_NAME     U2D1 DG16
 '@BASEBOARD_FAB2_LIB.BASEBOARD_FAB2(SCH_1):PAGE75_I19@CHPSET_LIB.SKX_EXT_B(CHIPS)':
 'VSS'<217>: CDS_PINID='VSS(217)';
NODE_NAME     U2D1 DG14
 '@BASEBOARD_FAB2_LIB.BASEBOARD_FAB2(SCH_1):PAGE75_I19@CHPSET_LIB.SKX_EXT_B(CHIPS)':
 'VSS'<218>: CDS_PINID='VSS(218)';
NODE_NAME     U2D1 H49
 '@BASEBOARD_FAB2_LIB.BASEBOARD_FAB2(SCH_1):PAGE75_I19@CHPSET_LIB.SKX_EXT_B(CHIPS)':
 'VSS'<219>: CDS_PINID='VSS(219)';
NODE_NAME     U2D1 DG2
 '@BASEBOARD_FAB2_LIB.BASEBOARD_FAB2(SCH_1):PAGE75_I19@CHPSET_LIB.SKX_EXT_B(CHIPS)':
 'VSS'<220>: CDS_PINID='VSS(220)';
NODE_NAME     U2D1 DF85
 '@BASEBOARD_FAB2_LIB.BASEBOARD_FAB2(SCH_1):PAGE75_I19@CHPSET_LIB.SKX_EXT_B(CHIPS)':
 'VSS'<221>: CDS_PINID='VSS(221)';
NODE_NAME     U2D1 DF83
 '@BASEBOARD_FAB2_LIB.BASEBOARD_FAB2(SCH_1):PAGE75_I19@CHPSET_LIB.SKX_EXT_B(CHIPS)':
 'VSS'<222>: CDS_PINID='VSS(222)';
NODE_NAME     U2D1 DF79
 '@BASEBOARD_FAB2_LIB.BASEBOARD_FAB2(SCH_1):PAGE75_I19@CHPSET_LIB.SKX_EXT_B(CHIPS)':
 'VSS'<223>: CDS_PINID='VSS(223)';
NODE_NAME     U2D1 DF73
 '@BASEBOARD_FAB2_LIB.BASEBOARD_FAB2(SCH_1):PAGE75_I19@CHPSET_LIB.SKX_EXT_B(CHIPS)':
 'VSS'<224>: CDS_PINID='VSS(224)';
NODE_NAME     U2D1 DF69
 '@BASEBOARD_FAB2_LIB.BASEBOARD_FAB2(SCH_1):PAGE75_I19@CHPSET_LIB.SKX_EXT_B(CHIPS)':
 'VSS'<225>: CDS_PINID='VSS(225)';
NODE_NAME     U2D1 DF65
 '@BASEBOARD_FAB2_LIB.BASEBOARD_FAB2(SCH_1):PAGE75_I19@CHPSET_LIB.SKX_EXT_B(CHIPS)':
 'VSS'<226>: CDS_PINID='VSS(226)';
NODE_NAME     U2D1 DF41
 '@BASEBOARD_FAB2_LIB.BASEBOARD_FAB2(SCH_1):PAGE75_I19@CHPSET_LIB.SKX_EXT_B(CHIPS)':
 'VSS'<227>: CDS_PINID='VSS(227)';
NODE_NAME     U2D1 DF39
 '@BASEBOARD_FAB2_LIB.BASEBOARD_FAB2(SCH_1):PAGE75_I19@CHPSET_LIB.SKX_EXT_B(CHIPS)':
 'VSS'<228>: CDS_PINID='VSS(228)';
NODE_NAME     U2D1 DF37
 '@BASEBOARD_FAB2_LIB.BASEBOARD_FAB2(SCH_1):PAGE75_I19@CHPSET_LIB.SKX_EXT_B(CHIPS)':
 'VSS'<229>: CDS_PINID='VSS(229)';
NODE_NAME     U2D1 DF35
 '@BASEBOARD_FAB2_LIB.BASEBOARD_FAB2(SCH_1):PAGE75_I19@CHPSET_LIB.SKX_EXT_B(CHIPS)':
 'VSS'<230>: CDS_PINID='VSS(230)';
NODE_NAME     U2D1 DF29
 '@BASEBOARD_FAB2_LIB.BASEBOARD_FAB2(SCH_1):PAGE75_I19@CHPSET_LIB.SKX_EXT_B(CHIPS)':
 'VSS'<231>: CDS_PINID='VSS(231)';
NODE_NAME     U2D1 DF19
 '@BASEBOARD_FAB2_LIB.BASEBOARD_FAB2(SCH_1):PAGE75_I19@CHPSET_LIB.SKX_EXT_B(CHIPS)':
 'VSS'<232>: CDS_PINID='VSS(232)';
NODE_NAME     U2D1 H51
 '@BASEBOARD_FAB2_LIB.BASEBOARD_FAB2(SCH_1):PAGE75_I19@CHPSET_LIB.SKX_EXT_B(CHIPS)':
 'VSS'<233>: CDS_PINID='VSS(233)';
NODE_NAME     U2D1 DF7
 '@BASEBOARD_FAB2_LIB.BASEBOARD_FAB2(SCH_1):PAGE75_I19@CHPSET_LIB.SKX_EXT_B(CHIPS)':
 'VSS'<234>: CDS_PINID='VSS(234)';
NODE_NAME     U2D1 DF5
 '@BASEBOARD_FAB2_LIB.BASEBOARD_FAB2(SCH_1):PAGE75_I19@CHPSET_LIB.SKX_EXT_B(CHIPS)':
 'VSS'<235>: CDS_PINID='VSS(235)';
NODE_NAME     U2D1 DE78
 '@BASEBOARD_FAB2_LIB.BASEBOARD_FAB2(SCH_1):PAGE75_I19@CHPSET_LIB.SKX_EXT_B(CHIPS)':
 'VSS'<236>: CDS_PINID='VSS(236)';
NODE_NAME     U2D1 DE72
 '@BASEBOARD_FAB2_LIB.BASEBOARD_FAB2(SCH_1):PAGE75_I19@CHPSET_LIB.SKX_EXT_B(CHIPS)':
 'VSS'<237>: CDS_PINID='VSS(237)';
NODE_NAME     U2D1 DE70
 '@BASEBOARD_FAB2_LIB.BASEBOARD_FAB2(SCH_1):PAGE75_I19@CHPSET_LIB.SKX_EXT_B(CHIPS)':
 'VSS'<238>: CDS_PINID='VSS(238)';
NODE_NAME     U2D1 DE64
 '@BASEBOARD_FAB2_LIB.BASEBOARD_FAB2(SCH_1):PAGE75_I19@CHPSET_LIB.SKX_EXT_B(CHIPS)':
 'VSS'<239>: CDS_PINID='VSS(239)';
NODE_NAME     U2D1 DE36
 '@BASEBOARD_FAB2_LIB.BASEBOARD_FAB2(SCH_1):PAGE75_I19@CHPSET_LIB.SKX_EXT_B(CHIPS)':
 'VSS'<240>: CDS_PINID='VSS(240)';
NODE_NAME     U2D1 DE34
 '@BASEBOARD_FAB2_LIB.BASEBOARD_FAB2(SCH_1):PAGE75_I19@CHPSET_LIB.SKX_EXT_B(CHIPS)':
 'VSS'<241>: CDS_PINID='VSS(241)';
NODE_NAME     U2D1 DE30
 '@BASEBOARD_FAB2_LIB.BASEBOARD_FAB2(SCH_1):PAGE75_I19@CHPSET_LIB.SKX_EXT_B(CHIPS)':
 'VSS'<242>: CDS_PINID='VSS(242)';
NODE_NAME     U2D1 DE28
 '@BASEBOARD_FAB2_LIB.BASEBOARD_FAB2(SCH_1):PAGE75_I19@CHPSET_LIB.SKX_EXT_B(CHIPS)':
 'VSS'<243>: CDS_PINID='VSS(243)';
NODE_NAME     U2D1 DE24
 '@BASEBOARD_FAB2_LIB.BASEBOARD_FAB2(SCH_1):PAGE75_I19@CHPSET_LIB.SKX_EXT_B(CHIPS)':
 'VSS'<244>: CDS_PINID='VSS(244)';
NODE_NAME     U2D1 DE20
 '@BASEBOARD_FAB2_LIB.BASEBOARD_FAB2(SCH_1):PAGE75_I19@CHPSET_LIB.SKX_EXT_B(CHIPS)':
 'VSS'<245>: CDS_PINID='VSS(245)';
NODE_NAME     U2D1 DE18
 '@BASEBOARD_FAB2_LIB.BASEBOARD_FAB2(SCH_1):PAGE75_I19@CHPSET_LIB.SKX_EXT_B(CHIPS)':
 'VSS'<246>: CDS_PINID='VSS(246)';
NODE_NAME     U2D1 DE8
 '@BASEBOARD_FAB2_LIB.BASEBOARD_FAB2(SCH_1):PAGE75_I19@CHPSET_LIB.SKX_EXT_B(CHIPS)':
 'VSS'<247>: CDS_PINID='VSS(247)';
NODE_NAME     U2D1 DE6
 '@BASEBOARD_FAB2_LIB.BASEBOARD_FAB2(SCH_1):PAGE75_I19@CHPSET_LIB.SKX_EXT_B(CHIPS)':
 'VSS'<248>: CDS_PINID='VSS(248)';
NODE_NAME     U2D1 DD83
 '@BASEBOARD_FAB2_LIB.BASEBOARD_FAB2(SCH_1):PAGE75_I19@CHPSET_LIB.SKX_EXT_B(CHIPS)':
 'VSS'<249>: CDS_PINID='VSS(249)';
NODE_NAME     U2D1 DD81
 '@BASEBOARD_FAB2_LIB.BASEBOARD_FAB2(SCH_1):PAGE75_I19@CHPSET_LIB.SKX_EXT_B(CHIPS)':
 'VSS'<250>: CDS_PINID='VSS(250)';
NODE_NAME     U2D1 DD75
 '@BASEBOARD_FAB2_LIB.BASEBOARD_FAB2(SCH_1):PAGE75_I19@CHPSET_LIB.SKX_EXT_B(CHIPS)':
 'VSS'<251>: CDS_PINID='VSS(251)';
NODE_NAME     U2D1 DD73
 '@BASEBOARD_FAB2_LIB.BASEBOARD_FAB2(SCH_1):PAGE75_I19@CHPSET_LIB.SKX_EXT_B(CHIPS)':
 'VSS'<252>: CDS_PINID='VSS(252)';
NODE_NAME     U2D1 DD71
 '@BASEBOARD_FAB2_LIB.BASEBOARD_FAB2(SCH_1):PAGE75_I19@CHPSET_LIB.SKX_EXT_B(CHIPS)':
 'VSS'<253>: CDS_PINID='VSS(253)';
NODE_NAME     U2D1 DD37
 '@BASEBOARD_FAB2_LIB.BASEBOARD_FAB2(SCH_1):PAGE75_I19@CHPSET_LIB.SKX_EXT_B(CHIPS)':
 'VSS'<254>: CDS_PINID='VSS(254)';
NODE_NAME     U2D1 DD33
 '@BASEBOARD_FAB2_LIB.BASEBOARD_FAB2(SCH_1):PAGE75_I19@CHPSET_LIB.SKX_EXT_B(CHIPS)':
 'VSS'<255>: CDS_PINID='VSS(255)';
NODE_NAME     U2D1 DD31
 '@BASEBOARD_FAB2_LIB.BASEBOARD_FAB2(SCH_1):PAGE75_I19@CHPSET_LIB.SKX_EXT_B(CHIPS)':
 'VSS'<256>: CDS_PINID='VSS(256)';
NODE_NAME     U2D1 DD27
 '@BASEBOARD_FAB2_LIB.BASEBOARD_FAB2(SCH_1):PAGE75_I19@CHPSET_LIB.SKX_EXT_B(CHIPS)':
 'VSS'<257>: CDS_PINID='VSS(257)';
NODE_NAME     U2D1 DD23
 '@BASEBOARD_FAB2_LIB.BASEBOARD_FAB2(SCH_1):PAGE75_I19@CHPSET_LIB.SKX_EXT_B(CHIPS)':
 'VSS'<258>: CDS_PINID='VSS(258)';
NODE_NAME     U2D1 DD11
 '@BASEBOARD_FAB2_LIB.BASEBOARD_FAB2(SCH_1):PAGE75_I19@CHPSET_LIB.SKX_EXT_B(CHIPS)':
 'VSS'<259>: CDS_PINID='VSS(259)';
NODE_NAME     U2D1 DC86
 '@BASEBOARD_FAB2_LIB.BASEBOARD_FAB2(SCH_1):PAGE75_I19@CHPSET_LIB.SKX_EXT_B(CHIPS)':
 'VSS'<260>: CDS_PINID='VSS(260)';
NODE_NAME     U2D1 DC84
 '@BASEBOARD_FAB2_LIB.BASEBOARD_FAB2(SCH_1):PAGE75_I19@CHPSET_LIB.SKX_EXT_B(CHIPS)':
 'VSS'<261>: CDS_PINID='VSS(261)';
NODE_NAME     U2D1 DC78
 '@BASEBOARD_FAB2_LIB.BASEBOARD_FAB2(SCH_1):PAGE75_I19@CHPSET_LIB.SKX_EXT_B(CHIPS)':
 'VSS'<262>: CDS_PINID='VSS(262)';
NODE_NAME     U2D1 DC70
 '@BASEBOARD_FAB2_LIB.BASEBOARD_FAB2(SCH_1):PAGE75_I19@CHPSET_LIB.SKX_EXT_B(CHIPS)':
 'VSS'<263>: CDS_PINID='VSS(263)';
NODE_NAME     U2D1 DC68
 '@BASEBOARD_FAB2_LIB.BASEBOARD_FAB2(SCH_1):PAGE75_I19@CHPSET_LIB.SKX_EXT_B(CHIPS)':
 'VSS'<264>: CDS_PINID='VSS(264)';
NODE_NAME     U2D1 DC66
 '@BASEBOARD_FAB2_LIB.BASEBOARD_FAB2(SCH_1):PAGE75_I19@CHPSET_LIB.SKX_EXT_B(CHIPS)':
 'VSS'<265>: CDS_PINID='VSS(265)';
NODE_NAME     U2D1 DC64
 '@BASEBOARD_FAB2_LIB.BASEBOARD_FAB2(SCH_1):PAGE75_I19@CHPSET_LIB.SKX_EXT_B(CHIPS)':
 'VSS'<266>: CDS_PINID='VSS(266)';
NODE_NAME     U2D1 DC42
 '@BASEBOARD_FAB2_LIB.BASEBOARD_FAB2(SCH_1):PAGE75_I19@CHPSET_LIB.SKX_EXT_B(CHIPS)':
 'VSS'<267>: CDS_PINID='VSS(267)';
NODE_NAME     U2D1 DC38
 '@BASEBOARD_FAB2_LIB.BASEBOARD_FAB2(SCH_1):PAGE75_I19@CHPSET_LIB.SKX_EXT_B(CHIPS)':
 'VSS'<268>: CDS_PINID='VSS(268)';
NODE_NAME     U2D1 DC32
 '@BASEBOARD_FAB2_LIB.BASEBOARD_FAB2(SCH_1):PAGE75_I19@CHPSET_LIB.SKX_EXT_B(CHIPS)':
 'VSS'<269>: CDS_PINID='VSS(269)';
NODE_NAME     U2D1 DC26
 '@BASEBOARD_FAB2_LIB.BASEBOARD_FAB2(SCH_1):PAGE75_I19@CHPSET_LIB.SKX_EXT_B(CHIPS)':
 'VSS'<270>: CDS_PINID='VSS(270)';
NODE_NAME     U2D1 DC24
 '@BASEBOARD_FAB2_LIB.BASEBOARD_FAB2(SCH_1):PAGE75_I19@CHPSET_LIB.SKX_EXT_B(CHIPS)':
 'VSS'<271>: CDS_PINID='VSS(271)';
NODE_NAME     U2D1 DC14
 '@BASEBOARD_FAB2_LIB.BASEBOARD_FAB2(SCH_1):PAGE75_I19@CHPSET_LIB.SKX_EXT_B(CHIPS)':
 'VSS'<272>: CDS_PINID='VSS(272)';
NODE_NAME     U2D1 DB85
 '@BASEBOARD_FAB2_LIB.BASEBOARD_FAB2(SCH_1):PAGE75_I19@CHPSET_LIB.SKX_EXT_B(CHIPS)':
 'VSS'<273>: CDS_PINID='VSS(273)';
NODE_NAME     U2D1 DB83
 '@BASEBOARD_FAB2_LIB.BASEBOARD_FAB2(SCH_1):PAGE75_I19@CHPSET_LIB.SKX_EXT_B(CHIPS)':
 'VSS'<274>: CDS_PINID='VSS(274)';
NODE_NAME     U2D1 DB77
 '@BASEBOARD_FAB2_LIB.BASEBOARD_FAB2(SCH_1):PAGE75_I19@CHPSET_LIB.SKX_EXT_B(CHIPS)':
 'VSS'<275>: CDS_PINID='VSS(275)';
NODE_NAME     U2D1 DB73
 '@BASEBOARD_FAB2_LIB.BASEBOARD_FAB2(SCH_1):PAGE75_I19@CHPSET_LIB.SKX_EXT_B(CHIPS)':
 'VSS'<276>: CDS_PINID='VSS(276)';
NODE_NAME     U2D1 DB49
 '@BASEBOARD_FAB2_LIB.BASEBOARD_FAB2(SCH_1):PAGE75_I19@CHPSET_LIB.SKX_EXT_B(CHIPS)':
 'VSS'<277>: CDS_PINID='VSS(277)';
NODE_NAME     U2D1 DB47
 '@BASEBOARD_FAB2_LIB.BASEBOARD_FAB2(SCH_1):PAGE75_I19@CHPSET_LIB.SKX_EXT_B(CHIPS)':
 'VSS'<278>: CDS_PINID='VSS(278)';
NODE_NAME     U2D1 DB41
 '@BASEBOARD_FAB2_LIB.BASEBOARD_FAB2(SCH_1):PAGE75_I19@CHPSET_LIB.SKX_EXT_B(CHIPS)':
 'VSS'<279>: CDS_PINID='VSS(279)';
NODE_NAME     U2D1 DB39
 '@BASEBOARD_FAB2_LIB.BASEBOARD_FAB2(SCH_1):PAGE75_I19@CHPSET_LIB.SKX_EXT_B(CHIPS)':
 'VSS'<280>: CDS_PINID='VSS(280)';
NODE_NAME     U2D1 DB25
 '@BASEBOARD_FAB2_LIB.BASEBOARD_FAB2(SCH_1):PAGE75_I19@CHPSET_LIB.SKX_EXT_B(CHIPS)':
 'VSS'<281>: CDS_PINID='VSS(281)';
NODE_NAME     U2D1 DB23
 '@BASEBOARD_FAB2_LIB.BASEBOARD_FAB2(SCH_1):PAGE75_I19@CHPSET_LIB.SKX_EXT_B(CHIPS)':
 'VSS'<282>: CDS_PINID='VSS(282)';
NODE_NAME     U2D1 DB17
 '@BASEBOARD_FAB2_LIB.BASEBOARD_FAB2(SCH_1):PAGE75_I19@CHPSET_LIB.SKX_EXT_B(CHIPS)':
 'VSS'<283>: CDS_PINID='VSS(283)';
NODE_NAME     U2D1 DB13
 '@BASEBOARD_FAB2_LIB.BASEBOARD_FAB2(SCH_1):PAGE75_I19@CHPSET_LIB.SKX_EXT_B(CHIPS)':
 'VSS'<284>: CDS_PINID='VSS(284)';
NODE_NAME     U2D1 DB3
 '@BASEBOARD_FAB2_LIB.BASEBOARD_FAB2(SCH_1):PAGE75_I19@CHPSET_LIB.SKX_EXT_B(CHIPS)':
 'VSS'<285>: CDS_PINID='VSS(285)';
NODE_NAME     U2D1 DA80
 '@BASEBOARD_FAB2_LIB.BASEBOARD_FAB2(SCH_1):PAGE75_I19@CHPSET_LIB.SKX_EXT_B(CHIPS)':
 'VSS'<286>: CDS_PINID='VSS(286)';
NODE_NAME     U2D1 DA78
 '@BASEBOARD_FAB2_LIB.BASEBOARD_FAB2(SCH_1):PAGE75_I19@CHPSET_LIB.SKX_EXT_B(CHIPS)':
 'VSS'<287>: CDS_PINID='VSS(287)';
NODE_NAME     U2D1 DA76
 '@BASEBOARD_FAB2_LIB.BASEBOARD_FAB2(SCH_1):PAGE75_I19@CHPSET_LIB.SKX_EXT_B(CHIPS)':
 'VSS'<288>: CDS_PINID='VSS(288)';
NODE_NAME     U2D1 DA74
 '@BASEBOARD_FAB2_LIB.BASEBOARD_FAB2(SCH_1):PAGE75_I19@CHPSET_LIB.SKX_EXT_B(CHIPS)':
 'VSS'<289>: CDS_PINID='VSS(289)';
NODE_NAME     U2D1 DA70
 '@BASEBOARD_FAB2_LIB.BASEBOARD_FAB2(SCH_1):PAGE75_I19@CHPSET_LIB.SKX_EXT_B(CHIPS)':
 'VSS'<290>: CDS_PINID='VSS(290)';
NODE_NAME     U2D1 DA64
 '@BASEBOARD_FAB2_LIB.BASEBOARD_FAB2(SCH_1):PAGE75_I19@CHPSET_LIB.SKX_EXT_B(CHIPS)':
 'VSS'<291>: CDS_PINID='VSS(291)';
NODE_NAME     U2D1 DA50
 '@BASEBOARD_FAB2_LIB.BASEBOARD_FAB2(SCH_1):PAGE75_I19@CHPSET_LIB.SKX_EXT_B(CHIPS)':
 'VSS'<292>: CDS_PINID='VSS(292)';
NODE_NAME     U2D1 DA48
 '@BASEBOARD_FAB2_LIB.BASEBOARD_FAB2(SCH_1):PAGE75_I19@CHPSET_LIB.SKX_EXT_B(CHIPS)':
 'VSS'<293>: CDS_PINID='VSS(293)';
NODE_NAME     U2D1 EF79
 '@BASEBOARD_FAB2_LIB.BASEBOARD_FAB2(SCH_1):PAGE75_I20@CHPSET_LIB.SKX_EXT_B(CHIPS)':
 'VSS'<0>: CDS_PINID='VSS(0)';
NODE_NAME     U2D1 EF75
 '@BASEBOARD_FAB2_LIB.BASEBOARD_FAB2(SCH_1):PAGE75_I20@CHPSET_LIB.SKX_EXT_B(CHIPS)':
 'VSS'<1>: CDS_PINID='VSS(1)';
NODE_NAME     U2D1 EF71
 '@BASEBOARD_FAB2_LIB.BASEBOARD_FAB2(SCH_1):PAGE75_I20@CHPSET_LIB.SKX_EXT_B(CHIPS)':
 'VSS'<2>: CDS_PINID='VSS(2)';
NODE_NAME     U2D1 EE78
 '@BASEBOARD_FAB2_LIB.BASEBOARD_FAB2(SCH_1):PAGE75_I20@CHPSET_LIB.SKX_EXT_B(CHIPS)':
 'VSS'<3>: CDS_PINID='VSS(3)';
NODE_NAME     U2D1 EE76
 '@BASEBOARD_FAB2_LIB.BASEBOARD_FAB2(SCH_1):PAGE75_I20@CHPSET_LIB.SKX_EXT_B(CHIPS)':
 'VSS'<4>: CDS_PINID='VSS(4)';
NODE_NAME     U2D1 EE70
 '@BASEBOARD_FAB2_LIB.BASEBOARD_FAB2(SCH_1):PAGE75_I20@CHPSET_LIB.SKX_EXT_B(CHIPS)':
 'VSS'<5>: CDS_PINID='VSS(5)';
NODE_NAME     U2D1 EE36
 '@BASEBOARD_FAB2_LIB.BASEBOARD_FAB2(SCH_1):PAGE75_I20@CHPSET_LIB.SKX_EXT_B(CHIPS)':
 'VSS'<6>: CDS_PINID='VSS(6)';
NODE_NAME     U2D1 EE34
 '@BASEBOARD_FAB2_LIB.BASEBOARD_FAB2(SCH_1):PAGE75_I20@CHPSET_LIB.SKX_EXT_B(CHIPS)':
 'VSS'<7>: CDS_PINID='VSS(7)';
NODE_NAME     U2D1 EE30
 '@BASEBOARD_FAB2_LIB.BASEBOARD_FAB2(SCH_1):PAGE75_I20@CHPSET_LIB.SKX_EXT_B(CHIPS)':
 'VSS'<8>: CDS_PINID='VSS(8)';
NODE_NAME     U2D1 EE28
 '@BASEBOARD_FAB2_LIB.BASEBOARD_FAB2(SCH_1):PAGE75_I20@CHPSET_LIB.SKX_EXT_B(CHIPS)':
 'VSS'<9>: CDS_PINID='VSS(9)';
NODE_NAME     U2D1 EE24
 '@BASEBOARD_FAB2_LIB.BASEBOARD_FAB2(SCH_1):PAGE75_I20@CHPSET_LIB.SKX_EXT_B(CHIPS)':
 'VSS'<10>: CDS_PINID='VSS(10)';
NODE_NAME     U2D1 ED77
 '@BASEBOARD_FAB2_LIB.BASEBOARD_FAB2(SCH_1):PAGE75_I20@CHPSET_LIB.SKX_EXT_B(CHIPS)':
 'VSS'<11>: CDS_PINID='VSS(11)';
NODE_NAME     U2D1 ED35
 '@BASEBOARD_FAB2_LIB.BASEBOARD_FAB2(SCH_1):PAGE75_I20@CHPSET_LIB.SKX_EXT_B(CHIPS)':
 'VSS'<12>: CDS_PINID='VSS(12)';
NODE_NAME     U2D1 ED29
 '@BASEBOARD_FAB2_LIB.BASEBOARD_FAB2(SCH_1):PAGE75_I20@CHPSET_LIB.SKX_EXT_B(CHIPS)':
 'VSS'<13>: CDS_PINID='VSS(13)';
NODE_NAME     U2D1 ED23
 '@BASEBOARD_FAB2_LIB.BASEBOARD_FAB2(SCH_1):PAGE75_I20@CHPSET_LIB.SKX_EXT_B(CHIPS)':
 'VSS'<14>: CDS_PINID='VSS(14)';
NODE_NAME     U2D1 ED15
 '@BASEBOARD_FAB2_LIB.BASEBOARD_FAB2(SCH_1):PAGE75_I20@CHPSET_LIB.SKX_EXT_B(CHIPS)':
 'VSS'<15>: CDS_PINID='VSS(15)';
NODE_NAME     U2D1 ED11
 '@BASEBOARD_FAB2_LIB.BASEBOARD_FAB2(SCH_1):PAGE75_I20@CHPSET_LIB.SKX_EXT_B(CHIPS)':
 'VSS'<16>: CDS_PINID='VSS(16)';
NODE_NAME     U2D1 EC76
 '@BASEBOARD_FAB2_LIB.BASEBOARD_FAB2(SCH_1):PAGE75_I20@CHPSET_LIB.SKX_EXT_B(CHIPS)':
 'VSS'<17>: CDS_PINID='VSS(17)';
NODE_NAME     U2D1 EC74
 '@BASEBOARD_FAB2_LIB.BASEBOARD_FAB2(SCH_1):PAGE75_I20@CHPSET_LIB.SKX_EXT_B(CHIPS)':
 'VSS'<18>: CDS_PINID='VSS(18)';
NODE_NAME     U2D1 EC72
 '@BASEBOARD_FAB2_LIB.BASEBOARD_FAB2(SCH_1):PAGE75_I20@CHPSET_LIB.SKX_EXT_B(CHIPS)':
 'VSS'<19>: CDS_PINID='VSS(19)';
NODE_NAME     U2D1 EC70
 '@BASEBOARD_FAB2_LIB.BASEBOARD_FAB2(SCH_1):PAGE75_I20@CHPSET_LIB.SKX_EXT_B(CHIPS)':
 'VSS'<20>: CDS_PINID='VSS(20)';
NODE_NAME     U2D1 EC10
 '@BASEBOARD_FAB2_LIB.BASEBOARD_FAB2(SCH_1):PAGE75_I20@CHPSET_LIB.SKX_EXT_B(CHIPS)':
 'VSS'<21>: CDS_PINID='VSS(21)';
NODE_NAME     U2D1 EB69
 '@BASEBOARD_FAB2_LIB.BASEBOARD_FAB2(SCH_1):PAGE75_I20@CHPSET_LIB.SKX_EXT_B(CHIPS)':
 'VSS'<22>: CDS_PINID='VSS(22)';
NODE_NAME     U2D1 EB65
 '@BASEBOARD_FAB2_LIB.BASEBOARD_FAB2(SCH_1):PAGE75_I20@CHPSET_LIB.SKX_EXT_B(CHIPS)':
 'VSS'<23>: CDS_PINID='VSS(23)';
NODE_NAME     U2D1 EB41
 '@BASEBOARD_FAB2_LIB.BASEBOARD_FAB2(SCH_1):PAGE75_I20@CHPSET_LIB.SKX_EXT_B(CHIPS)':
 'VSS'<24>: CDS_PINID='VSS(24)';
NODE_NAME     U2D1 EB39
 '@BASEBOARD_FAB2_LIB.BASEBOARD_FAB2(SCH_1):PAGE75_I20@CHPSET_LIB.SKX_EXT_B(CHIPS)':
 'VSS'<25>: CDS_PINID='VSS(25)';
NODE_NAME     U2D1 EB37
 '@BASEBOARD_FAB2_LIB.BASEBOARD_FAB2(SCH_1):PAGE75_I20@CHPSET_LIB.SKX_EXT_B(CHIPS)':
 'VSS'<26>: CDS_PINID='VSS(26)';
NODE_NAME     U2D1 EB35
 '@BASEBOARD_FAB2_LIB.BASEBOARD_FAB2(SCH_1):PAGE75_I20@CHPSET_LIB.SKX_EXT_B(CHIPS)':
 'VSS'<27>: CDS_PINID='VSS(27)';
NODE_NAME     U2D1 EB33
 '@BASEBOARD_FAB2_LIB.BASEBOARD_FAB2(SCH_1):PAGE75_I20@CHPSET_LIB.SKX_EXT_B(CHIPS)':
 'VSS'<28>: CDS_PINID='VSS(28)';
NODE_NAME     U2D1 EB31
 '@BASEBOARD_FAB2_LIB.BASEBOARD_FAB2(SCH_1):PAGE75_I20@CHPSET_LIB.SKX_EXT_B(CHIPS)':
 'VSS'<29>: CDS_PINID='VSS(29)';
NODE_NAME     U2D1 EB29
 '@BASEBOARD_FAB2_LIB.BASEBOARD_FAB2(SCH_1):PAGE75_I20@CHPSET_LIB.SKX_EXT_B(CHIPS)':
 'VSS'<30>: CDS_PINID='VSS(30)';
NODE_NAME     U2D1 EB27
 '@BASEBOARD_FAB2_LIB.BASEBOARD_FAB2(SCH_1):PAGE75_I20@CHPSET_LIB.SKX_EXT_B(CHIPS)':
 'VSS'<31>: CDS_PINID='VSS(31)';
NODE_NAME     U2D1 EB25
 '@BASEBOARD_FAB2_LIB.BASEBOARD_FAB2(SCH_1):PAGE75_I20@CHPSET_LIB.SKX_EXT_B(CHIPS)':
 'VSS'<32>: CDS_PINID='VSS(32)';
NODE_NAME     U2D1 EB23
 '@BASEBOARD_FAB2_LIB.BASEBOARD_FAB2(SCH_1):PAGE75_I20@CHPSET_LIB.SKX_EXT_B(CHIPS)':
 'VSS'<33>: CDS_PINID='VSS(33)';
NODE_NAME     U2D1 BR18
 '@BASEBOARD_FAB2_LIB.BASEBOARD_FAB2(SCH_1):PAGE75_I20@CHPSET_LIB.SKX_EXT_B(CHIPS)':
 'VSS'<34>: CDS_PINID='VSS(34)';
NODE_NAME     U2D1 EB13
 '@BASEBOARD_FAB2_LIB.BASEBOARD_FAB2(SCH_1):PAGE75_I20@CHPSET_LIB.SKX_EXT_B(CHIPS)':
 'VSS'<35>: CDS_PINID='VSS(35)';
NODE_NAME     U2D1 EA82
 '@BASEBOARD_FAB2_LIB.BASEBOARD_FAB2(SCH_1):PAGE75_I20@CHPSET_LIB.SKX_EXT_B(CHIPS)':
 'VSS'<36>: CDS_PINID='VSS(36)';
NODE_NAME     U2D1 EA80
 '@BASEBOARD_FAB2_LIB.BASEBOARD_FAB2(SCH_1):PAGE75_I20@CHPSET_LIB.SKX_EXT_B(CHIPS)':
 'VSS'<37>: CDS_PINID='VSS(37)';
NODE_NAME     U2D1 EA78
 '@BASEBOARD_FAB2_LIB.BASEBOARD_FAB2(SCH_1):PAGE75_I20@CHPSET_LIB.SKX_EXT_B(CHIPS)':
 'VSS'<38>: CDS_PINID='VSS(38)';
NODE_NAME     U2D1 EA76
 '@BASEBOARD_FAB2_LIB.BASEBOARD_FAB2(SCH_1):PAGE75_I20@CHPSET_LIB.SKX_EXT_B(CHIPS)':
 'VSS'<39>: CDS_PINID='VSS(39)';
NODE_NAME     U2D1 EA70
 '@BASEBOARD_FAB2_LIB.BASEBOARD_FAB2(SCH_1):PAGE75_I20@CHPSET_LIB.SKX_EXT_B(CHIPS)':
 'VSS'<40>: CDS_PINID='VSS(40)';
NODE_NAME     U2D1 EA64
 '@BASEBOARD_FAB2_LIB.BASEBOARD_FAB2(SCH_1):PAGE75_I20@CHPSET_LIB.SKX_EXT_B(CHIPS)':
 'VSS'<41>: CDS_PINID='VSS(41)';
NODE_NAME     U2D1 EA42
 '@BASEBOARD_FAB2_LIB.BASEBOARD_FAB2(SCH_1):PAGE75_I20@CHPSET_LIB.SKX_EXT_B(CHIPS)':
 'VSS'<42>: CDS_PINID='VSS(42)';
NODE_NAME     U2D1 EA22
 '@BASEBOARD_FAB2_LIB.BASEBOARD_FAB2(SCH_1):PAGE75_I20@CHPSET_LIB.SKX_EXT_B(CHIPS)':
 'VSS'<43>: CDS_PINID='VSS(43)';
NODE_NAME     U2D1 EA20
 '@BASEBOARD_FAB2_LIB.BASEBOARD_FAB2(SCH_1):PAGE75_I20@CHPSET_LIB.SKX_EXT_B(CHIPS)':
 'VSS'<44>: CDS_PINID='VSS(44)';
NODE_NAME     U2D1 EA16
 '@BASEBOARD_FAB2_LIB.BASEBOARD_FAB2(SCH_1):PAGE75_I20@CHPSET_LIB.SKX_EXT_B(CHIPS)':
 'VSS'<45>: CDS_PINID='VSS(45)';
NODE_NAME     U2D1 J16
 '@BASEBOARD_FAB2_LIB.BASEBOARD_FAB2(SCH_1):PAGE75_I20@CHPSET_LIB.SKX_EXT_B(CHIPS)':
 'VSS'<46>: CDS_PINID='VSS(46)';
NODE_NAME     U2D1 EA6
 '@BASEBOARD_FAB2_LIB.BASEBOARD_FAB2(SCH_1):PAGE75_I20@CHPSET_LIB.SKX_EXT_B(CHIPS)':
 'VSS'<47>: CDS_PINID='VSS(47)';
NODE_NAME     U2D1 DY75
 '@BASEBOARD_FAB2_LIB.BASEBOARD_FAB2(SCH_1):PAGE75_I20@CHPSET_LIB.SKX_EXT_B(CHIPS)':
 'VSS'<48>: CDS_PINID='VSS(48)';
NODE_NAME     U2D1 DY71
 '@BASEBOARD_FAB2_LIB.BASEBOARD_FAB2(SCH_1):PAGE75_I20@CHPSET_LIB.SKX_EXT_B(CHIPS)':
 'VSS'<49>: CDS_PINID='VSS(49)';
NODE_NAME     U2D1 DY41
 '@BASEBOARD_FAB2_LIB.BASEBOARD_FAB2(SCH_1):PAGE75_I20@CHPSET_LIB.SKX_EXT_B(CHIPS)':
 'VSS'<50>: CDS_PINID='VSS(50)';
NODE_NAME     U2D1 DY35
 '@BASEBOARD_FAB2_LIB.BASEBOARD_FAB2(SCH_1):PAGE75_I20@CHPSET_LIB.SKX_EXT_B(CHIPS)':
 'VSS'<51>: CDS_PINID='VSS(51)';
NODE_NAME     U2D1 DY29
 '@BASEBOARD_FAB2_LIB.BASEBOARD_FAB2(SCH_1):PAGE75_I20@CHPSET_LIB.SKX_EXT_B(CHIPS)':
 'VSS'<52>: CDS_PINID='VSS(52)';
NODE_NAME     U2D1 DY23
 '@BASEBOARD_FAB2_LIB.BASEBOARD_FAB2(SCH_1):PAGE75_I20@CHPSET_LIB.SKX_EXT_B(CHIPS)':
 'VSS'<53>: CDS_PINID='VSS(53)';
NODE_NAME     U2D1 DY19
 '@BASEBOARD_FAB2_LIB.BASEBOARD_FAB2(SCH_1):PAGE75_I20@CHPSET_LIB.SKX_EXT_B(CHIPS)':
 'VSS'<54>: CDS_PINID='VSS(54)';
NODE_NAME     U2D1 DY5
 '@BASEBOARD_FAB2_LIB.BASEBOARD_FAB2(SCH_1):PAGE75_I20@CHPSET_LIB.SKX_EXT_B(CHIPS)':
 'VSS'<55>: CDS_PINID='VSS(55)';
NODE_NAME     U2D1 DW84
 '@BASEBOARD_FAB2_LIB.BASEBOARD_FAB2(SCH_1):PAGE75_I20@CHPSET_LIB.SKX_EXT_B(CHIPS)':
 'VSS'<56>: CDS_PINID='VSS(56)';
NODE_NAME     U2D1 DW82
 '@BASEBOARD_FAB2_LIB.BASEBOARD_FAB2(SCH_1):PAGE75_I20@CHPSET_LIB.SKX_EXT_B(CHIPS)':
 'VSS'<57>: CDS_PINID='VSS(57)';
NODE_NAME     U2D1 DW8
 '@BASEBOARD_FAB2_LIB.BASEBOARD_FAB2(SCH_1):PAGE75_I20@CHPSET_LIB.SKX_EXT_B(CHIPS)':
 'VSS'<58>: CDS_PINID='VSS(58)';
NODE_NAME     U2D1 DW76
 '@BASEBOARD_FAB2_LIB.BASEBOARD_FAB2(SCH_1):PAGE75_I20@CHPSET_LIB.SKX_EXT_B(CHIPS)':
 'VSS'<59>: CDS_PINID='VSS(59)';
NODE_NAME     U2D1 DW74
 '@BASEBOARD_FAB2_LIB.BASEBOARD_FAB2(SCH_1):PAGE75_I20@CHPSET_LIB.SKX_EXT_B(CHIPS)':
 'VSS'<60>: CDS_PINID='VSS(60)';
NODE_NAME     U2D1 DW72
 '@BASEBOARD_FAB2_LIB.BASEBOARD_FAB2(SCH_1):PAGE75_I20@CHPSET_LIB.SKX_EXT_B(CHIPS)':
 'VSS'<61>: CDS_PINID='VSS(61)';
NODE_NAME     U2D1 DW70
 '@BASEBOARD_FAB2_LIB.BASEBOARD_FAB2(SCH_1):PAGE75_I20@CHPSET_LIB.SKX_EXT_B(CHIPS)':
 'VSS'<62>: CDS_PINID='VSS(62)';
NODE_NAME     U2D1 DW68
 '@BASEBOARD_FAB2_LIB.BASEBOARD_FAB2(SCH_1):PAGE75_I20@CHPSET_LIB.SKX_EXT_B(CHIPS)':
 'VSS'<63>: CDS_PINID='VSS(63)';
NODE_NAME     U2D1 DW66
 '@BASEBOARD_FAB2_LIB.BASEBOARD_FAB2(SCH_1):PAGE75_I20@CHPSET_LIB.SKX_EXT_B(CHIPS)':
 'VSS'<64>: CDS_PINID='VSS(64)';
NODE_NAME     U2D1 DW64
 '@BASEBOARD_FAB2_LIB.BASEBOARD_FAB2(SCH_1):PAGE75_I20@CHPSET_LIB.SKX_EXT_B(CHIPS)':
 'VSS'<65>: CDS_PINID='VSS(65)';
NODE_NAME     U2D1 DW40
 '@BASEBOARD_FAB2_LIB.BASEBOARD_FAB2(SCH_1):PAGE75_I20@CHPSET_LIB.SKX_EXT_B(CHIPS)':
 'VSS'<66>: CDS_PINID='VSS(66)';
NODE_NAME     U2D1 DW36
 '@BASEBOARD_FAB2_LIB.BASEBOARD_FAB2(SCH_1):PAGE75_I20@CHPSET_LIB.SKX_EXT_B(CHIPS)':
 'VSS'<67>: CDS_PINID='VSS(67)';
NODE_NAME     U2D1 DW34
 '@BASEBOARD_FAB2_LIB.BASEBOARD_FAB2(SCH_1):PAGE75_I20@CHPSET_LIB.SKX_EXT_B(CHIPS)':
 'VSS'<68>: CDS_PINID='VSS(68)';
NODE_NAME     U2D1 DW30
 '@BASEBOARD_FAB2_LIB.BASEBOARD_FAB2(SCH_1):PAGE75_I20@CHPSET_LIB.SKX_EXT_B(CHIPS)':
 'VSS'<69>: CDS_PINID='VSS(69)';
NODE_NAME     U2D1 DW28
 '@BASEBOARD_FAB2_LIB.BASEBOARD_FAB2(SCH_1):PAGE75_I20@CHPSET_LIB.SKX_EXT_B(CHIPS)':
 'VSS'<70>: CDS_PINID='VSS(70)';
NODE_NAME     U2D1 DW24
 '@BASEBOARD_FAB2_LIB.BASEBOARD_FAB2(SCH_1):PAGE75_I20@CHPSET_LIB.SKX_EXT_B(CHIPS)':
 'VSS'<71>: CDS_PINID='VSS(71)';
NODE_NAME     U2D1 DW20
 '@BASEBOARD_FAB2_LIB.BASEBOARD_FAB2(SCH_1):PAGE75_I20@CHPSET_LIB.SKX_EXT_B(CHIPS)':
 'VSS'<72>: CDS_PINID='VSS(72)';
NODE_NAME     U2D1 DW12
 '@BASEBOARD_FAB2_LIB.BASEBOARD_FAB2(SCH_1):PAGE75_I20@CHPSET_LIB.SKX_EXT_B(CHIPS)':
 'VSS'<73>: CDS_PINID='VSS(73)';
NODE_NAME     U2D1 DV81
 '@BASEBOARD_FAB2_LIB.BASEBOARD_FAB2(SCH_1):PAGE75_I20@CHPSET_LIB.SKX_EXT_B(CHIPS)':
 'VSS'<74>: CDS_PINID='VSS(74)';
NODE_NAME     U2D1 DV77
 '@BASEBOARD_FAB2_LIB.BASEBOARD_FAB2(SCH_1):PAGE75_I20@CHPSET_LIB.SKX_EXT_B(CHIPS)':
 'VSS'<75>: CDS_PINID='VSS(75)';
NODE_NAME     U2D1 DV73
 '@BASEBOARD_FAB2_LIB.BASEBOARD_FAB2(SCH_1):PAGE75_I20@CHPSET_LIB.SKX_EXT_B(CHIPS)':
 'VSS'<76>: CDS_PINID='VSS(76)';
NODE_NAME     U2D1 DV39
 '@BASEBOARD_FAB2_LIB.BASEBOARD_FAB2(SCH_1):PAGE75_I20@CHPSET_LIB.SKX_EXT_B(CHIPS)':
 'VSS'<77>: CDS_PINID='VSS(77)';
NODE_NAME     U2D1 DV37
 '@BASEBOARD_FAB2_LIB.BASEBOARD_FAB2(SCH_1):PAGE75_I20@CHPSET_LIB.SKX_EXT_B(CHIPS)':
 'VSS'<78>: CDS_PINID='VSS(78)';
NODE_NAME     U2D1 DV33
 '@BASEBOARD_FAB2_LIB.BASEBOARD_FAB2(SCH_1):PAGE75_I20@CHPSET_LIB.SKX_EXT_B(CHIPS)':
 'VSS'<79>: CDS_PINID='VSS(79)';
NODE_NAME     U2D1 DV31
 '@BASEBOARD_FAB2_LIB.BASEBOARD_FAB2(SCH_1):PAGE75_I20@CHPSET_LIB.SKX_EXT_B(CHIPS)':
 'VSS'<80>: CDS_PINID='VSS(80)';
NODE_NAME     U2D1 DV27
 '@BASEBOARD_FAB2_LIB.BASEBOARD_FAB2(SCH_1):PAGE75_I20@CHPSET_LIB.SKX_EXT_B(CHIPS)':
 'VSS'<81>: CDS_PINID='VSS(81)';
NODE_NAME     U2D1 DV25
 '@BASEBOARD_FAB2_LIB.BASEBOARD_FAB2(SCH_1):PAGE75_I20@CHPSET_LIB.SKX_EXT_B(CHIPS)':
 'VSS'<82>: CDS_PINID='VSS(82)';
NODE_NAME     U2D1 DV21
 '@BASEBOARD_FAB2_LIB.BASEBOARD_FAB2(SCH_1):PAGE75_I20@CHPSET_LIB.SKX_EXT_B(CHIPS)':
 'VSS'<83>: CDS_PINID='VSS(83)';
NODE_NAME     U2D1 DU84
 '@BASEBOARD_FAB2_LIB.BASEBOARD_FAB2(SCH_1):PAGE75_I20@CHPSET_LIB.SKX_EXT_B(CHIPS)':
 'VSS'<84>: CDS_PINID='VSS(84)';
NODE_NAME     U2D1 DU82
 '@BASEBOARD_FAB2_LIB.BASEBOARD_FAB2(SCH_1):PAGE75_I20@CHPSET_LIB.SKX_EXT_B(CHIPS)':
 'VSS'<85>: CDS_PINID='VSS(85)';
NODE_NAME     U2D1 DU80
 '@BASEBOARD_FAB2_LIB.BASEBOARD_FAB2(SCH_1):PAGE75_I20@CHPSET_LIB.SKX_EXT_B(CHIPS)':
 'VSS'<86>: CDS_PINID='VSS(86)';
NODE_NAME     U2D1 DU78
 '@BASEBOARD_FAB2_LIB.BASEBOARD_FAB2(SCH_1):PAGE75_I20@CHPSET_LIB.SKX_EXT_B(CHIPS)':
 'VSS'<87>: CDS_PINID='VSS(87)';
NODE_NAME     U2D1 DU72
 '@BASEBOARD_FAB2_LIB.BASEBOARD_FAB2(SCH_1):PAGE75_I20@CHPSET_LIB.SKX_EXT_B(CHIPS)':
 'VSS'<88>: CDS_PINID='VSS(88)';
NODE_NAME     U2D1 DU70
 '@BASEBOARD_FAB2_LIB.BASEBOARD_FAB2(SCH_1):PAGE75_I20@CHPSET_LIB.SKX_EXT_B(CHIPS)':
 'VSS'<89>: CDS_PINID='VSS(89)';
NODE_NAME     U2D1 DU38
 '@BASEBOARD_FAB2_LIB.BASEBOARD_FAB2(SCH_1):PAGE75_I20@CHPSET_LIB.SKX_EXT_B(CHIPS)':
 'VSS'<90>: CDS_PINID='VSS(90)';
NODE_NAME     U2D1 DU32
 '@BASEBOARD_FAB2_LIB.BASEBOARD_FAB2(SCH_1):PAGE75_I20@CHPSET_LIB.SKX_EXT_B(CHIPS)':
 'VSS'<91>: CDS_PINID='VSS(91)';
NODE_NAME     U2D1 DU26
 '@BASEBOARD_FAB2_LIB.BASEBOARD_FAB2(SCH_1):PAGE75_I20@CHPSET_LIB.SKX_EXT_B(CHIPS)':
 'VSS'<92>: CDS_PINID='VSS(92)';
NODE_NAME     U2D1 DU22
 '@BASEBOARD_FAB2_LIB.BASEBOARD_FAB2(SCH_1):PAGE75_I20@CHPSET_LIB.SKX_EXT_B(CHIPS)':
 'VSS'<93>: CDS_PINID='VSS(93)';
NODE_NAME     U2D1 CN14
 '@BASEBOARD_FAB2_LIB.BASEBOARD_FAB2(SCH_1):PAGE75_I20@CHPSET_LIB.SKX_EXT_B(CHIPS)':
 'VSS'<94>: CDS_PINID='VSS(94)';
NODE_NAME     U2D1 DU14
 '@BASEBOARD_FAB2_LIB.BASEBOARD_FAB2(SCH_1):PAGE75_I20@CHPSET_LIB.SKX_EXT_B(CHIPS)':
 'VSS'<95>: CDS_PINID='VSS(95)';
NODE_NAME     U2D1 DU10
 '@BASEBOARD_FAB2_LIB.BASEBOARD_FAB2(SCH_1):PAGE75_I20@CHPSET_LIB.SKX_EXT_B(CHIPS)':
 'VSS'<96>: CDS_PINID='VSS(96)';
NODE_NAME     U2D1 DT85
 '@BASEBOARD_FAB2_LIB.BASEBOARD_FAB2(SCH_1):PAGE75_I20@CHPSET_LIB.SKX_EXT_B(CHIPS)':
 'VSS'<97>: CDS_PINID='VSS(97)';
NODE_NAME     U2D1 DT83
 '@BASEBOARD_FAB2_LIB.BASEBOARD_FAB2(SCH_1):PAGE75_I20@CHPSET_LIB.SKX_EXT_B(CHIPS)':
 'VSS'<98>: CDS_PINID='VSS(98)';
NODE_NAME     U2D1 DT79
 '@BASEBOARD_FAB2_LIB.BASEBOARD_FAB2(SCH_1):PAGE75_I20@CHPSET_LIB.SKX_EXT_B(CHIPS)':
 'VSS'<99>: CDS_PINID='VSS(99)';
NODE_NAME     U2D1 DT69
 '@BASEBOARD_FAB2_LIB.BASEBOARD_FAB2(SCH_1):PAGE75_I20@CHPSET_LIB.SKX_EXT_B(CHIPS)':
 'VSS'<100>: CDS_PINID='VSS(100)';
NODE_NAME     U2D1 DT65
 '@BASEBOARD_FAB2_LIB.BASEBOARD_FAB2(SCH_1):PAGE75_I20@CHPSET_LIB.SKX_EXT_B(CHIPS)':
 'VSS'<101>: CDS_PINID='VSS(101)';
NODE_NAME     U2D1 DH21
 '@BASEBOARD_FAB2_LIB.BASEBOARD_FAB2(SCH_1):PAGE75_I20@CHPSET_LIB.SKX_EXT_B(CHIPS)':
 'VSS'<102>: CDS_PINID='VSS(102)';
NODE_NAME     U2D1 DT17
 '@BASEBOARD_FAB2_LIB.BASEBOARD_FAB2(SCH_1):PAGE75_I20@CHPSET_LIB.SKX_EXT_B(CHIPS)':
 'VSS'<103>: CDS_PINID='VSS(103)';
NODE_NAME     U2D1 DT3
 '@BASEBOARD_FAB2_LIB.BASEBOARD_FAB2(SCH_1):PAGE75_I20@CHPSET_LIB.SKX_EXT_B(CHIPS)':
 'VSS'<104>: CDS_PINID='VSS(104)';
NODE_NAME     U2D1 DR78
 '@BASEBOARD_FAB2_LIB.BASEBOARD_FAB2(SCH_1):PAGE75_I20@CHPSET_LIB.SKX_EXT_B(CHIPS)':
 'VSS'<105>: CDS_PINID='VSS(105)';
NODE_NAME     U2D1 DR76
 '@BASEBOARD_FAB2_LIB.BASEBOARD_FAB2(SCH_1):PAGE75_I20@CHPSET_LIB.SKX_EXT_B(CHIPS)':
 'VSS'<106>: CDS_PINID='VSS(106)';
NODE_NAME     U2D1 DR74
 '@BASEBOARD_FAB2_LIB.BASEBOARD_FAB2(SCH_1):PAGE75_I20@CHPSET_LIB.SKX_EXT_B(CHIPS)':
 'VSS'<107>: CDS_PINID='VSS(107)';
NODE_NAME     U2D1 DR72
 '@BASEBOARD_FAB2_LIB.BASEBOARD_FAB2(SCH_1):PAGE75_I20@CHPSET_LIB.SKX_EXT_B(CHIPS)':
 'VSS'<108>: CDS_PINID='VSS(108)';
NODE_NAME     U2D1 DR70
 '@BASEBOARD_FAB2_LIB.BASEBOARD_FAB2(SCH_1):PAGE75_I20@CHPSET_LIB.SKX_EXT_B(CHIPS)':
 'VSS'<109>: CDS_PINID='VSS(109)';
NODE_NAME     U2D1 DR68
 '@BASEBOARD_FAB2_LIB.BASEBOARD_FAB2(SCH_1):PAGE75_I20@CHPSET_LIB.SKX_EXT_B(CHIPS)':
 'VSS'<110>: CDS_PINID='VSS(110)';
NODE_NAME     U2D1 DR66
 '@BASEBOARD_FAB2_LIB.BASEBOARD_FAB2(SCH_1):PAGE75_I20@CHPSET_LIB.SKX_EXT_B(CHIPS)':
 'VSS'<111>: CDS_PINID='VSS(111)';
NODE_NAME     U2D1 DR42
 '@BASEBOARD_FAB2_LIB.BASEBOARD_FAB2(SCH_1):PAGE75_I20@CHPSET_LIB.SKX_EXT_B(CHIPS)':
 'VSS'<112>: CDS_PINID='VSS(112)';
NODE_NAME     U2D1 DR40
 '@BASEBOARD_FAB2_LIB.BASEBOARD_FAB2(SCH_1):PAGE75_I20@CHPSET_LIB.SKX_EXT_B(CHIPS)':
 'VSS'<113>: CDS_PINID='VSS(113)';
NODE_NAME     U2D1 DR38
 '@BASEBOARD_FAB2_LIB.BASEBOARD_FAB2(SCH_1):PAGE75_I20@CHPSET_LIB.SKX_EXT_B(CHIPS)':
 'VSS'<114>: CDS_PINID='VSS(114)';
NODE_NAME     U2D1 DR36
 '@BASEBOARD_FAB2_LIB.BASEBOARD_FAB2(SCH_1):PAGE75_I20@CHPSET_LIB.SKX_EXT_B(CHIPS)':
 'VSS'<115>: CDS_PINID='VSS(115)';
NODE_NAME     U2D1 DR34
 '@BASEBOARD_FAB2_LIB.BASEBOARD_FAB2(SCH_1):PAGE75_I20@CHPSET_LIB.SKX_EXT_B(CHIPS)':
 'VSS'<116>: CDS_PINID='VSS(116)';
NODE_NAME     U2D1 DR32
 '@BASEBOARD_FAB2_LIB.BASEBOARD_FAB2(SCH_1):PAGE75_I20@CHPSET_LIB.SKX_EXT_B(CHIPS)':
 'VSS'<117>: CDS_PINID='VSS(117)';
NODE_NAME     U2D1 DR30
 '@BASEBOARD_FAB2_LIB.BASEBOARD_FAB2(SCH_1):PAGE75_I20@CHPSET_LIB.SKX_EXT_B(CHIPS)':
 'VSS'<118>: CDS_PINID='VSS(118)';
NODE_NAME     U2D1 DR28
 '@BASEBOARD_FAB2_LIB.BASEBOARD_FAB2(SCH_1):PAGE75_I20@CHPSET_LIB.SKX_EXT_B(CHIPS)':
 'VSS'<119>: CDS_PINID='VSS(119)';
NODE_NAME     U2D1 DR26
 '@BASEBOARD_FAB2_LIB.BASEBOARD_FAB2(SCH_1):PAGE75_I20@CHPSET_LIB.SKX_EXT_B(CHIPS)':
 'VSS'<120>: CDS_PINID='VSS(120)';
NODE_NAME     U2D1 DR24
 '@BASEBOARD_FAB2_LIB.BASEBOARD_FAB2(SCH_1):PAGE75_I20@CHPSET_LIB.SKX_EXT_B(CHIPS)':
 'VSS'<121>: CDS_PINID='VSS(121)';
NODE_NAME     U2D1 DR22
 '@BASEBOARD_FAB2_LIB.BASEBOARD_FAB2(SCH_1):PAGE75_I20@CHPSET_LIB.SKX_EXT_B(CHIPS)':
 'VSS'<122>: CDS_PINID='VSS(122)';
NODE_NAME     U2D1 DR20
 '@BASEBOARD_FAB2_LIB.BASEBOARD_FAB2(SCH_1):PAGE75_I20@CHPSET_LIB.SKX_EXT_B(CHIPS)':
 'VSS'<123>: CDS_PINID='VSS(123)';
NODE_NAME     U2D1 CL22
 '@BASEBOARD_FAB2_LIB.BASEBOARD_FAB2(SCH_1):PAGE75_I20@CHPSET_LIB.SKX_EXT_B(CHIPS)':
 'VSS'<124>: CDS_PINID='VSS(124)';
NODE_NAME     U2D1 CA20
 '@BASEBOARD_FAB2_LIB.BASEBOARD_FAB2(SCH_1):PAGE75_I20@CHPSET_LIB.SKX_EXT_B(CHIPS)':
 'VSS'<125>: CDS_PINID='VSS(125)';
NODE_NAME     U2D1 DR6
 '@BASEBOARD_FAB2_LIB.BASEBOARD_FAB2(SCH_1):PAGE75_I20@CHPSET_LIB.SKX_EXT_B(CHIPS)':
 'VSS'<126>: CDS_PINID='VSS(126)';
NODE_NAME     U2D1 BR26
 '@BASEBOARD_FAB2_LIB.BASEBOARD_FAB2(SCH_1):PAGE75_I20@CHPSET_LIB.SKX_EXT_B(CHIPS)':
 'VSS'<127>: CDS_PINID='VSS(127)';
NODE_NAME     U2D1 DP83
 '@BASEBOARD_FAB2_LIB.BASEBOARD_FAB2(SCH_1):PAGE75_I20@CHPSET_LIB.SKX_EXT_B(CHIPS)':
 'VSS'<128>: CDS_PINID='VSS(128)';
NODE_NAME     U2D1 DP81
 '@BASEBOARD_FAB2_LIB.BASEBOARD_FAB2(SCH_1):PAGE75_I20@CHPSET_LIB.SKX_EXT_B(CHIPS)':
 'VSS'<129>: CDS_PINID='VSS(129)';
NODE_NAME     U2D1 DP71
 '@BASEBOARD_FAB2_LIB.BASEBOARD_FAB2(SCH_1):PAGE75_I20@CHPSET_LIB.SKX_EXT_B(CHIPS)':
 'VSS'<130>: CDS_PINID='VSS(130)';
NODE_NAME     U2D1 DP69
 '@BASEBOARD_FAB2_LIB.BASEBOARD_FAB2(SCH_1):PAGE75_I20@CHPSET_LIB.SKX_EXT_B(CHIPS)':
 'VSS'<131>: CDS_PINID='VSS(131)';
NODE_NAME     U2D1 DP67
 '@BASEBOARD_FAB2_LIB.BASEBOARD_FAB2(SCH_1):PAGE75_I20@CHPSET_LIB.SKX_EXT_B(CHIPS)':
 'VSS'<132>: CDS_PINID='VSS(132)';
NODE_NAME     U2D1 DN78
 '@BASEBOARD_FAB2_LIB.BASEBOARD_FAB2(SCH_1):PAGE75_I20@CHPSET_LIB.SKX_EXT_B(CHIPS)':
 'VSS'<133>: CDS_PINID='VSS(133)';
NODE_NAME     C3D21 2
 '@BASEBOARD_FAB2_LIB.BASEBOARD_FAB2(SCH_1):PAGE76_I1@DEV_DISCRETE.CAP_A(CHIPS)':
 'B': CDS_PINID='B';
NODE_NAME     C3D5 2
 '@BASEBOARD_FAB2_LIB.BASEBOARD_FAB2(SCH_1):PAGE76_I3@DEV_DISCRETE.CAP_A(CHIPS)':
 'B': CDS_PINID='B';
NODE_NAME     C3D12 2
 '@BASEBOARD_FAB2_LIB.BASEBOARD_FAB2(SCH_1):PAGE76_I4@DEV_DISCRETE.CAP_A(CHIPS)':
 'B': CDS_PINID='B';
NODE_NAME     C3D4 2
 '@BASEBOARD_FAB2_LIB.BASEBOARD_FAB2(SCH_1):PAGE76_I5@DEV_DISCRETE.CAP_A(CHIPS)':
 'B': CDS_PINID='B';
NODE_NAME     C3D11 2
 '@BASEBOARD_FAB2_LIB.BASEBOARD_FAB2(SCH_1):PAGE76_I7@DEV_DISCRETE.CAP_A(CHIPS)':
 'B': CDS_PINID='B';
NODE_NAME     C3D13 2
 '@BASEBOARD_FAB2_LIB.BASEBOARD_FAB2(SCH_1):PAGE76_I8@DEV_DISCRETE.CAP_A(CHIPS)':
 'B': CDS_PINID='B';
NODE_NAME     C2D40 2
 '@BASEBOARD_FAB2_LIB.BASEBOARD_FAB2(SCH_1):PAGE76_I10@DEV_DISCRETE.CAP_A(CHIPS)':
 'B': CDS_PINID='B';
NODE_NAME     C3D9 2
 '@BASEBOARD_FAB2_LIB.BASEBOARD_FAB2(SCH_1):PAGE76_I15@DEV_DISCRETE.CAP_A(CHIPS)':
 'B': CDS_PINID='B';
NODE_NAME     C3D8 2
 '@BASEBOARD_FAB2_LIB.BASEBOARD_FAB2(SCH_1):PAGE76_I18@DEV_DISCRETE.CAP_A(CHIPS)':
 'B': CDS_PINID='B';
NODE_NAME     C7P17 2
 '@BASEBOARD_FAB2_LIB.BASEBOARD_FAB2(SCH_1):PAGE76_I29@MSTR_DISCRETE.CAP(CHIPS)':
 'B': CDS_PINID='B';
NODE_NAME     C2D8 2
 '@BASEBOARD_FAB2_LIB.BASEBOARD_FAB2(SCH_1):PAGE76_I33@MSTR_DISCRETE.CAP(CHIPS)':
 'B': CDS_PINID='B';
NODE_NAME     C2D10 2
 '@BASEBOARD_FAB2_LIB.BASEBOARD_FAB2(SCH_1):PAGE76_I37@MSTR_DISCRETE.CAP(CHIPS)':
 'B': CDS_PINID='B';
NODE_NAME     C2D11 2
 '@BASEBOARD_FAB2_LIB.BASEBOARD_FAB2(SCH_1):PAGE76_I42@MSTR_DISCRETE.CAP(CHIPS)':
 'B': CDS_PINID='B';
NODE_NAME     C2D9 2
 '@BASEBOARD_FAB2_LIB.BASEBOARD_FAB2(SCH_1):PAGE76_I43@MSTR_DISCRETE.CAP(CHIPS)':
 'B': CDS_PINID='B';
NODE_NAME     C7P18 2
 '@BASEBOARD_FAB2_LIB.BASEBOARD_FAB2(SCH_1):PAGE76_I51@MSTR_DISCRETE.CAP(CHIPS)':
 'B': CDS_PINID='B';
NODE_NAME     C7P3 2
 '@BASEBOARD_FAB2_LIB.BASEBOARD_FAB2(SCH_1):PAGE76_I52@MSTR_DISCRETE.CAP(CHIPS)':
 'B': CDS_PINID='B';
NODE_NAME     C2D12 2
 '@BASEBOARD_FAB2_LIB.BASEBOARD_FAB2(SCH_1):PAGE76_I59@DEV_DISCRETE.CAP_A(CHIPS)':
 'B': CDS_PINID='B';
NODE_NAME     C2D22 2
 '@BASEBOARD_FAB2_LIB.BASEBOARD_FAB2(SCH_1):PAGE76_I61@DEV_DISCRETE.CAP_A(CHIPS)':
 'B': CDS_PINID='B';
NODE_NAME     C2D31 2
 '@BASEBOARD_FAB2_LIB.BASEBOARD_FAB2(SCH_1):PAGE76_I63@DEV_DISCRETE.CAP_A(CHIPS)':
 'B': CDS_PINID='B';
NODE_NAME     C2D21 2
 '@BASEBOARD_FAB2_LIB.BASEBOARD_FAB2(SCH_1):PAGE76_I65@DEV_DISCRETE.CAP_A(CHIPS)':
 'B': CDS_PINID='B';
NODE_NAME     C2D27 2
 '@BASEBOARD_FAB2_LIB.BASEBOARD_FAB2(SCH_1):PAGE76_I66@DEV_DISCRETE.CAP_A(CHIPS)':
 'B': CDS_PINID='B';
NODE_NAME     C3D2 2
 '@BASEBOARD_FAB2_LIB.BASEBOARD_FAB2(SCH_1):PAGE76_I69@DEV_DISCRETE.CAP_A(CHIPS)':
 'B': CDS_PINID='B';
NODE_NAME     C2D36 2
 '@BASEBOARD_FAB2_LIB.BASEBOARD_FAB2(SCH_1):PAGE76_I70@DEV_DISCRETE.CAP_A(CHIPS)':
 'B': CDS_PINID='B';
NODE_NAME     C2D13 2
 '@BASEBOARD_FAB2_LIB.BASEBOARD_FAB2(SCH_1):PAGE76_I73@DEV_DISCRETE.CAP_A(CHIPS)':
 'B': CDS_PINID='B';
NODE_NAME     C2D19 2
 '@BASEBOARD_FAB2_LIB.BASEBOARD_FAB2(SCH_1):PAGE76_I75@DEV_DISCRETE.CAP_A(CHIPS)':
 'B': CDS_PINID='B';
NODE_NAME     C2D14 2
 '@BASEBOARD_FAB2_LIB.BASEBOARD_FAB2(SCH_1):PAGE76_I76@DEV_DISCRETE.CAP_A(CHIPS)':
 'B': CDS_PINID='B';
NODE_NAME     C2D20 2
 '@BASEBOARD_FAB2_LIB.BASEBOARD_FAB2(SCH_1):PAGE76_I79@DEV_DISCRETE.CAP_A(CHIPS)':
 'B': CDS_PINID='B';
NODE_NAME     C2D24 2
 '@BASEBOARD_FAB2_LIB.BASEBOARD_FAB2(SCH_1):PAGE76_I80@DEV_DISCRETE.CAP_A(CHIPS)':
 'B': CDS_PINID='B';
NODE_NAME     C2D25 2
 '@BASEBOARD_FAB2_LIB.BASEBOARD_FAB2(SCH_1):PAGE76_I82@DEV_DISCRETE.CAP_A(CHIPS)':
 'B': CDS_PINID='B';
NODE_NAME     C2D30 2
 '@BASEBOARD_FAB2_LIB.BASEBOARD_FAB2(SCH_1):PAGE76_I83@DEV_DISCRETE.CAP_A(CHIPS)':
 'B': CDS_PINID='B';
NODE_NAME     C2D33 2
 '@BASEBOARD_FAB2_LIB.BASEBOARD_FAB2(SCH_1):PAGE76_I85@DEV_DISCRETE.CAP_A(CHIPS)':
 'B': CDS_PINID='B';
NODE_NAME     C8P20 2
 '@BASEBOARD_FAB2_LIB.BASEBOARD_FAB2(SCH_1):PAGE76_I89@MSTR_DISCRETE.CAP(CHIPS)':
 'B': CDS_PINID='B';
NODE_NAME     C2D32 2
 '@BASEBOARD_FAB2_LIB.BASEBOARD_FAB2(SCH_1):PAGE76_I90@DEV_DISCRETE.CAP_A(CHIPS)':
 'B': CDS_PINID='B';
NODE_NAME     C8P18 2
 '@BASEBOARD_FAB2_LIB.BASEBOARD_FAB2(SCH_1):PAGE76_I92@MSTR_DISCRETE.CAP(CHIPS)':
 'B': CDS_PINID='B';
NODE_NAME     C8P19 2
 '@BASEBOARD_FAB2_LIB.BASEBOARD_FAB2(SCH_1):PAGE76_I103@MSTR_DISCRETE.CAP(CHIPS)':
 'B': CDS_PINID='B';
NODE_NAME     C8P12 2
 '@BASEBOARD_FAB2_LIB.BASEBOARD_FAB2(SCH_1):PAGE76_I107@MSTR_DISCRETE.CAP(CHIPS)':
 'B': CDS_PINID='B';
NODE_NAME     C2D26 2
 '@BASEBOARD_FAB2_LIB.BASEBOARD_FAB2(SCH_1):PAGE76_I108@DEV_DISCRETE.CAP_A(CHIPS)':
 'B': CDS_PINID='B';
NODE_NAME     C2D23 2
 '@BASEBOARD_FAB2_LIB.BASEBOARD_FAB2(SCH_1):PAGE76_I112@DEV_DISCRETE.CAP_A(CHIPS)':
 'B': CDS_PINID='B';
NODE_NAME     C2D17 2
 '@BASEBOARD_FAB2_LIB.BASEBOARD_FAB2(SCH_1):PAGE76_I114@DEV_DISCRETE.CAP_A(CHIPS)':
 'B': CDS_PINID='B';
NODE_NAME     C8P26 2
 '@BASEBOARD_FAB2_LIB.BASEBOARD_FAB2(SCH_1):PAGE76_I118@MSTR_DISCRETE.CAP(CHIPS)':
 'B': CDS_PINID='B';
NODE_NAME     C2D37 2
 '@BASEBOARD_FAB2_LIB.BASEBOARD_FAB2(SCH_1):PAGE76_I119@DEV_DISCRETE.CAP_A(CHIPS)':
 'B': CDS_PINID='B';
NODE_NAME     C2D34 2
 '@BASEBOARD_FAB2_LIB.BASEBOARD_FAB2(SCH_1):PAGE76_I122@DEV_DISCRETE.CAP_A(CHIPS)':
 'B': CDS_PINID='B';
NODE_NAME     C2D16 2
 '@BASEBOARD_FAB2_LIB.BASEBOARD_FAB2(SCH_1):PAGE76_I124@DEV_DISCRETE.CAP_A(CHIPS)':
 'B': CDS_PINID='B';
NODE_NAME     C8P29 2
 '@BASEBOARD_FAB2_LIB.BASEBOARD_FAB2(SCH_1):PAGE76_I125@MSTR_DISCRETE.CAP(CHIPS)':
 'B': CDS_PINID='B';
NODE_NAME     C8P10 2
 '@BASEBOARD_FAB2_LIB.BASEBOARD_FAB2(SCH_1):PAGE76_I127@MSTR_DISCRETE.CAP(CHIPS)':
 'B': CDS_PINID='B';
NODE_NAME     C8P16 2
 '@BASEBOARD_FAB2_LIB.BASEBOARD_FAB2(SCH_1):PAGE76_I129@MSTR_DISCRETE.CAP(CHIPS)':
 'B': CDS_PINID='B';
NODE_NAME     C8P13 2
 '@BASEBOARD_FAB2_LIB.BASEBOARD_FAB2(SCH_1):PAGE76_I132@MSTR_DISCRETE.CAP(CHIPS)':
 'B': CDS_PINID='B';
NODE_NAME     C8P28 2
 '@BASEBOARD_FAB2_LIB.BASEBOARD_FAB2(SCH_1):PAGE76_I137@MSTR_DISCRETE.CAP(CHIPS)':
 'B': CDS_PINID='B';
NODE_NAME     C8P11 2
 '@BASEBOARD_FAB2_LIB.BASEBOARD_FAB2(SCH_1):PAGE76_I139@MSTR_DISCRETE.CAP(CHIPS)':
 'B': CDS_PINID='B';
NODE_NAME     C2D15 2
 '@BASEBOARD_FAB2_LIB.BASEBOARD_FAB2(SCH_1):PAGE76_I159@DEV_DISCRETE.CAP_A(CHIPS)':
 'B': CDS_PINID='B';
NODE_NAME     C2D38 2
 '@BASEBOARD_FAB2_LIB.BASEBOARD_FAB2(SCH_1):PAGE76_I160@DEV_DISCRETE.CAP_A(CHIPS)':
 'B': CDS_PINID='B';
NODE_NAME     C2D35 2
 '@BASEBOARD_FAB2_LIB.BASEBOARD_FAB2(SCH_1):PAGE76_I161@DEV_DISCRETE.CAP_A(CHIPS)':
 'B': CDS_PINID='B';
NODE_NAME     C3D7 2
 '@BASEBOARD_FAB2_LIB.BASEBOARD_FAB2(SCH_1):PAGE76_I164@DEV_DISCRETE.CAP_A(CHIPS)':
 'B': CDS_PINID='B';
NODE_NAME     C2D39 2
 '@BASEBOARD_FAB2_LIB.BASEBOARD_FAB2(SCH_1):PAGE76_I165@DEV_DISCRETE.CAP_A(CHIPS)':
 'B': CDS_PINID='B';
NODE_NAME     C3D17 2
 '@BASEBOARD_FAB2_LIB.BASEBOARD_FAB2(SCH_1):PAGE76_I166@DEV_DISCRETE.CAP_A(CHIPS)':
 'B': CDS_PINID='B';
NODE_NAME     C3D18 2
 '@BASEBOARD_FAB2_LIB.BASEBOARD_FAB2(SCH_1):PAGE76_I169@DEV_DISCRETE.CAP_A(CHIPS)':
 'B': CDS_PINID='B';
NODE_NAME     C3D6 2
 '@BASEBOARD_FAB2_LIB.BASEBOARD_FAB2(SCH_1):PAGE76_I170@DEV_DISCRETE.CAP_A(CHIPS)':
 'B': CDS_PINID='B';
NODE_NAME     C3D14 2
 '@BASEBOARD_FAB2_LIB.BASEBOARD_FAB2(SCH_1):PAGE76_I171@DEV_DISCRETE.CAP_A(CHIPS)':
 'B': CDS_PINID='B';
NODE_NAME     C3D23 2
 '@BASEBOARD_FAB2_LIB.BASEBOARD_FAB2(SCH_1):PAGE76_I172@DEV_DISCRETE.CAP_A(CHIPS)':
 'B': CDS_PINID='B';
NODE_NAME     C3D15 2
 '@BASEBOARD_FAB2_LIB.BASEBOARD_FAB2(SCH_1):PAGE76_I174@DEV_DISCRETE.CAP_A(CHIPS)':
 'B': CDS_PINID='B';
NODE_NAME     C3D24 2
 '@BASEBOARD_FAB2_LIB.BASEBOARD_FAB2(SCH_1):PAGE76_I175@DEV_DISCRETE.CAP_A(CHIPS)':
 'B': CDS_PINID='B';
NODE_NAME     C3D16 2
 '@BASEBOARD_FAB2_LIB.BASEBOARD_FAB2(SCH_1):PAGE76_I176@DEV_DISCRETE.CAP_A(CHIPS)':
 'B': CDS_PINID='B';
NODE_NAME     C7P12 2
 '@BASEBOARD_FAB2_LIB.BASEBOARD_FAB2(SCH_1):PAGE76_I179@DEV_DISCRETE.CAP_A(CHIPS)':
 'B': CDS_PINID='B';
NODE_NAME     C3D10 2
 '@BASEBOARD_FAB2_LIB.BASEBOARD_FAB2(SCH_1):PAGE76_I196@DEV_DISCRETE.CAP_A(CHIPS)':
 'B': CDS_PINID='B';
NODE_NAME     C2D18 2
 '@BASEBOARD_FAB2_LIB.BASEBOARD_FAB2(SCH_1):PAGE76_I197@DEV_DISCRETE.CAP_A(CHIPS)':
 'B': CDS_PINID='B';
NODE_NAME     C2D28 2
 '@BASEBOARD_FAB2_LIB.BASEBOARD_FAB2(SCH_1):PAGE76_I198@DEV_DISCRETE.CAP_A(CHIPS)':
 'B': CDS_PINID='B';
NODE_NAME     C2D29 2
 '@BASEBOARD_FAB2_LIB.BASEBOARD_FAB2(SCH_1):PAGE76_I199@DEV_DISCRETE.CAP_A(CHIPS)':
 'B': CDS_PINID='B';
NODE_NAME     C7P16 2
 '@BASEBOARD_FAB2_LIB.BASEBOARD_FAB2(SCH_1):PAGE76_I206@DEV_DISCRETE.CAP_A(CHIPS)':
 'B': CDS_PINID='B';
NODE_NAME     C3D20 2
 '@BASEBOARD_FAB2_LIB.BASEBOARD_FAB2(SCH_1):PAGE76_I207@DEV_DISCRETE.CAP_A(CHIPS)':
 'B': CDS_PINID='B';
NODE_NAME     C3D19 2
 '@BASEBOARD_FAB2_LIB.BASEBOARD_FAB2(SCH_1):PAGE76_I208@DEV_DISCRETE.CAP_A(CHIPS)':
 'B': CDS_PINID='B';
NODE_NAME     C7P19 2
 '@BASEBOARD_FAB2_LIB.BASEBOARD_FAB2(SCH_1):PAGE76_I215@MSTR_DISCRETE.CAP(CHIPS)':
 'B': CDS_PINID='B';
NODE_NAME     C8P24 2
 '@BASEBOARD_FAB2_LIB.BASEBOARD_FAB2(SCH_1):PAGE76_I217@MSTR_DISCRETE.CAP(CHIPS)':
 'B': CDS_PINID='B';
NODE_NAME     J1G1 283
 '@BASEBOARD_FAB2_LIB.BASEBOARD_FAB2(SCH_1):PAGE77_I43@MSTR_SCONN.SCONN288_H44441004(CHIPS)':
 'VSS'<0>: CDS_PINID='VSS(0)';
NODE_NAME     J1G1 281
 '@BASEBOARD_FAB2_LIB.BASEBOARD_FAB2(SCH_1):PAGE77_I43@MSTR_SCONN.SCONN288_H44441004(CHIPS)':
 'VSS'<1>: CDS_PINID='VSS(1)';
NODE_NAME     J1G1 279
 '@BASEBOARD_FAB2_LIB.BASEBOARD_FAB2(SCH_1):PAGE77_I43@MSTR_SCONN.SCONN288_H44441004(CHIPS)':
 'VSS'<2>: CDS_PINID='VSS(2)';
NODE_NAME     J1G1 276
 '@BASEBOARD_FAB2_LIB.BASEBOARD_FAB2(SCH_1):PAGE77_I43@MSTR_SCONN.SCONN288_H44441004(CHIPS)':
 'VSS'<3>: CDS_PINID='VSS(3)';
NODE_NAME     J1G1 274
 '@BASEBOARD_FAB2_LIB.BASEBOARD_FAB2(SCH_1):PAGE77_I43@MSTR_SCONN.SCONN288_H44441004(CHIPS)':
 'VSS'<4>: CDS_PINID='VSS(4)';
NODE_NAME     J1G1 272
 '@BASEBOARD_FAB2_LIB.BASEBOARD_FAB2(SCH_1):PAGE77_I43@MSTR_SCONN.SCONN288_H44441004(CHIPS)':
 'VSS'<5>: CDS_PINID='VSS(5)';
NODE_NAME     J1G1 270
 '@BASEBOARD_FAB2_LIB.BASEBOARD_FAB2(SCH_1):PAGE77_I43@MSTR_SCONN.SCONN288_H44441004(CHIPS)':
 'VSS'<6>: CDS_PINID='VSS(6)';
NODE_NAME     J1G1 268
 '@BASEBOARD_FAB2_LIB.BASEBOARD_FAB2(SCH_1):PAGE77_I43@MSTR_SCONN.SCONN288_H44441004(CHIPS)':
 'VSS'<7>: CDS_PINID='VSS(7)';
NODE_NAME     J1G1 265
 '@BASEBOARD_FAB2_LIB.BASEBOARD_FAB2(SCH_1):PAGE77_I43@MSTR_SCONN.SCONN288_H44441004(CHIPS)':
 'VSS'<8>: CDS_PINID='VSS(8)';
NODE_NAME     J1G1 263
 '@BASEBOARD_FAB2_LIB.BASEBOARD_FAB2(SCH_1):PAGE77_I43@MSTR_SCONN.SCONN288_H44441004(CHIPS)':
 'VSS'<9>: CDS_PINID='VSS(9)';
NODE_NAME     J1G1 261
 '@BASEBOARD_FAB2_LIB.BASEBOARD_FAB2(SCH_1):PAGE77_I43@MSTR_SCONN.SCONN288_H44441004(CHIPS)':
 'VSS'<10>: CDS_PINID='VSS(10)';
NODE_NAME     J1G1 259
 '@BASEBOARD_FAB2_LIB.BASEBOARD_FAB2(SCH_1):PAGE77_I43@MSTR_SCONN.SCONN288_H44441004(CHIPS)':
 'VSS'<11>: CDS_PINID='VSS(11)';
NODE_NAME     J1G1 257
 '@BASEBOARD_FAB2_LIB.BASEBOARD_FAB2(SCH_1):PAGE77_I43@MSTR_SCONN.SCONN288_H44441004(CHIPS)':
 'VSS'<12>: CDS_PINID='VSS(12)';
NODE_NAME     J1G1 254
 '@BASEBOARD_FAB2_LIB.BASEBOARD_FAB2(SCH_1):PAGE77_I43@MSTR_SCONN.SCONN288_H44441004(CHIPS)':
 'VSS'<13>: CDS_PINID='VSS(13)';
NODE_NAME     J1G1 252
 '@BASEBOARD_FAB2_LIB.BASEBOARD_FAB2(SCH_1):PAGE77_I43@MSTR_SCONN.SCONN288_H44441004(CHIPS)':
 'VSS'<14>: CDS_PINID='VSS(14)';
NODE_NAME     J1G1 250
 '@BASEBOARD_FAB2_LIB.BASEBOARD_FAB2(SCH_1):PAGE77_I43@MSTR_SCONN.SCONN288_H44441004(CHIPS)':
 'VSS'<15>: CDS_PINID='VSS(15)';
NODE_NAME     J1G1 248
 '@BASEBOARD_FAB2_LIB.BASEBOARD_FAB2(SCH_1):PAGE77_I43@MSTR_SCONN.SCONN288_H44441004(CHIPS)':
 'VSS'<16>: CDS_PINID='VSS(16)';
NODE_NAME     J1G1 246
 '@BASEBOARD_FAB2_LIB.BASEBOARD_FAB2(SCH_1):PAGE77_I43@MSTR_SCONN.SCONN288_H44441004(CHIPS)':
 'VSS'<17>: CDS_PINID='VSS(17)';
NODE_NAME     J1G1 243
 '@BASEBOARD_FAB2_LIB.BASEBOARD_FAB2(SCH_1):PAGE77_I43@MSTR_SCONN.SCONN288_H44441004(CHIPS)':
 'VSS'<18>: CDS_PINID='VSS(18)';
NODE_NAME     J1G1 241
 '@BASEBOARD_FAB2_LIB.BASEBOARD_FAB2(SCH_1):PAGE77_I43@MSTR_SCONN.SCONN288_H44441004(CHIPS)':
 'VSS'<19>: CDS_PINID='VSS(19)';
NODE_NAME     J1G1 239
 '@BASEBOARD_FAB2_LIB.BASEBOARD_FAB2(SCH_1):PAGE77_I43@MSTR_SCONN.SCONN288_H44441004(CHIPS)':
 'VSS'<20>: CDS_PINID='VSS(20)';
NODE_NAME     J1G1 202
 '@BASEBOARD_FAB2_LIB.BASEBOARD_FAB2(SCH_1):PAGE77_I43@MSTR_SCONN.SCONN288_H44441004(CHIPS)':
 'VSS'<21>: CDS_PINID='VSS(21)';
NODE_NAME     J1G1 200
 '@BASEBOARD_FAB2_LIB.BASEBOARD_FAB2(SCH_1):PAGE77_I43@MSTR_SCONN.SCONN288_H44441004(CHIPS)':
 'VSS'<22>: CDS_PINID='VSS(22)';
NODE_NAME     J1G1 198
 '@BASEBOARD_FAB2_LIB.BASEBOARD_FAB2(SCH_1):PAGE77_I43@MSTR_SCONN.SCONN288_H44441004(CHIPS)':
 'VSS'<23>: CDS_PINID='VSS(23)';
NODE_NAME     J1G1 195
 '@BASEBOARD_FAB2_LIB.BASEBOARD_FAB2(SCH_1):PAGE77_I43@MSTR_SCONN.SCONN288_H44441004(CHIPS)':
 'VSS'<24>: CDS_PINID='VSS(24)';
NODE_NAME     J1G1 193
 '@BASEBOARD_FAB2_LIB.BASEBOARD_FAB2(SCH_1):PAGE77_I43@MSTR_SCONN.SCONN288_H44441004(CHIPS)':
 'VSS'<25>: CDS_PINID='VSS(25)';
NODE_NAME     J1G1 191
 '@BASEBOARD_FAB2_LIB.BASEBOARD_FAB2(SCH_1):PAGE77_I43@MSTR_SCONN.SCONN288_H44441004(CHIPS)':
 'VSS'<26>: CDS_PINID='VSS(26)';
NODE_NAME     J1G1 189
 '@BASEBOARD_FAB2_LIB.BASEBOARD_FAB2(SCH_1):PAGE77_I43@MSTR_SCONN.SCONN288_H44441004(CHIPS)':
 'VSS'<27>: CDS_PINID='VSS(27)';
NODE_NAME     J1G1 187
 '@BASEBOARD_FAB2_LIB.BASEBOARD_FAB2(SCH_1):PAGE77_I43@MSTR_SCONN.SCONN288_H44441004(CHIPS)':
 'VSS'<28>: CDS_PINID='VSS(28)';
NODE_NAME     J1G1 184
 '@BASEBOARD_FAB2_LIB.BASEBOARD_FAB2(SCH_1):PAGE77_I43@MSTR_SCONN.SCONN288_H44441004(CHIPS)':
 'VSS'<29>: CDS_PINID='VSS(29)';
NODE_NAME     J1G1 182
 '@BASEBOARD_FAB2_LIB.BASEBOARD_FAB2(SCH_1):PAGE77_I43@MSTR_SCONN.SCONN288_H44441004(CHIPS)':
 'VSS'<30>: CDS_PINID='VSS(30)';
NODE_NAME     J1G1 180
 '@BASEBOARD_FAB2_LIB.BASEBOARD_FAB2(SCH_1):PAGE77_I43@MSTR_SCONN.SCONN288_H44441004(CHIPS)':
 'VSS'<31>: CDS_PINID='VSS(31)';
NODE_NAME     J1G1 178
 '@BASEBOARD_FAB2_LIB.BASEBOARD_FAB2(SCH_1):PAGE77_I43@MSTR_SCONN.SCONN288_H44441004(CHIPS)':
 'VSS'<32>: CDS_PINID='VSS(32)';
NODE_NAME     J1G1 176
 '@BASEBOARD_FAB2_LIB.BASEBOARD_FAB2(SCH_1):PAGE77_I43@MSTR_SCONN.SCONN288_H44441004(CHIPS)':
 'VSS'<33>: CDS_PINID='VSS(33)';
NODE_NAME     J1G1 173
 '@BASEBOARD_FAB2_LIB.BASEBOARD_FAB2(SCH_1):PAGE77_I43@MSTR_SCONN.SCONN288_H44441004(CHIPS)':
 'VSS'<34>: CDS_PINID='VSS(34)';
NODE_NAME     J1G1 171
 '@BASEBOARD_FAB2_LIB.BASEBOARD_FAB2(SCH_1):PAGE77_I43@MSTR_SCONN.SCONN288_H44441004(CHIPS)':
 'VSS'<35>: CDS_PINID='VSS(35)';
NODE_NAME     J1G1 169
 '@BASEBOARD_FAB2_LIB.BASEBOARD_FAB2(SCH_1):PAGE77_I43@MSTR_SCONN.SCONN288_H44441004(CHIPS)':
 'VSS'<36>: CDS_PINID='VSS(36)';
NODE_NAME     J1G1 167
 '@BASEBOARD_FAB2_LIB.BASEBOARD_FAB2(SCH_1):PAGE77_I43@MSTR_SCONN.SCONN288_H44441004(CHIPS)':
 'VSS'<37>: CDS_PINID='VSS(37)';
NODE_NAME     J1G1 165
 '@BASEBOARD_FAB2_LIB.BASEBOARD_FAB2(SCH_1):PAGE77_I43@MSTR_SCONN.SCONN288_H44441004(CHIPS)':
 'VSS'<38>: CDS_PINID='VSS(38)';
NODE_NAME     J1G1 162
 '@BASEBOARD_FAB2_LIB.BASEBOARD_FAB2(SCH_1):PAGE77_I43@MSTR_SCONN.SCONN288_H44441004(CHIPS)':
 'VSS'<39>: CDS_PINID='VSS(39)';
NODE_NAME     J1G1 160
 '@BASEBOARD_FAB2_LIB.BASEBOARD_FAB2(SCH_1):PAGE77_I43@MSTR_SCONN.SCONN288_H44441004(CHIPS)':
 'VSS'<40>: CDS_PINID='VSS(40)';
NODE_NAME     J1G1 158
 '@BASEBOARD_FAB2_LIB.BASEBOARD_FAB2(SCH_1):PAGE77_I43@MSTR_SCONN.SCONN288_H44441004(CHIPS)':
 'VSS'<41>: CDS_PINID='VSS(41)';
NODE_NAME     J1G1 156
 '@BASEBOARD_FAB2_LIB.BASEBOARD_FAB2(SCH_1):PAGE77_I43@MSTR_SCONN.SCONN288_H44441004(CHIPS)':
 'VSS'<42>: CDS_PINID='VSS(42)';
NODE_NAME     J1G1 154
 '@BASEBOARD_FAB2_LIB.BASEBOARD_FAB2(SCH_1):PAGE77_I43@MSTR_SCONN.SCONN288_H44441004(CHIPS)':
 'VSS'<43>: CDS_PINID='VSS(43)';
NODE_NAME     J1G1 151
 '@BASEBOARD_FAB2_LIB.BASEBOARD_FAB2(SCH_1):PAGE77_I43@MSTR_SCONN.SCONN288_H44441004(CHIPS)':
 'VSS'<44>: CDS_PINID='VSS(44)';
NODE_NAME     J1G1 149
 '@BASEBOARD_FAB2_LIB.BASEBOARD_FAB2(SCH_1):PAGE77_I43@MSTR_SCONN.SCONN288_H44441004(CHIPS)':
 'VSS'<45>: CDS_PINID='VSS(45)';
NODE_NAME     J1G1 147
 '@BASEBOARD_FAB2_LIB.BASEBOARD_FAB2(SCH_1):PAGE77_I43@MSTR_SCONN.SCONN288_H44441004(CHIPS)':
 'VSS'<46>: CDS_PINID='VSS(46)';
NODE_NAME     J1G1 138
 '@BASEBOARD_FAB2_LIB.BASEBOARD_FAB2(SCH_1):PAGE77_I43@MSTR_SCONN.SCONN288_H44441004(CHIPS)':
 'VSS'<47>: CDS_PINID='VSS(47)';
NODE_NAME     J1G1 136
 '@BASEBOARD_FAB2_LIB.BASEBOARD_FAB2(SCH_1):PAGE77_I43@MSTR_SCONN.SCONN288_H44441004(CHIPS)':
 'VSS'<48>: CDS_PINID='VSS(48)';
NODE_NAME     J1G1 134
 '@BASEBOARD_FAB2_LIB.BASEBOARD_FAB2(SCH_1):PAGE77_I43@MSTR_SCONN.SCONN288_H44441004(CHIPS)':
 'VSS'<49>: CDS_PINID='VSS(49)';
NODE_NAME     J1G1 131
 '@BASEBOARD_FAB2_LIB.BASEBOARD_FAB2(SCH_1):PAGE77_I43@MSTR_SCONN.SCONN288_H44441004(CHIPS)':
 'VSS'<50>: CDS_PINID='VSS(50)';
NODE_NAME     J1G1 129
 '@BASEBOARD_FAB2_LIB.BASEBOARD_FAB2(SCH_1):PAGE77_I43@MSTR_SCONN.SCONN288_H44441004(CHIPS)':
 'VSS'<51>: CDS_PINID='VSS(51)';
NODE_NAME     J1G1 127
 '@BASEBOARD_FAB2_LIB.BASEBOARD_FAB2(SCH_1):PAGE77_I43@MSTR_SCONN.SCONN288_H44441004(CHIPS)':
 'VSS'<52>: CDS_PINID='VSS(52)';
NODE_NAME     J1G1 125
 '@BASEBOARD_FAB2_LIB.BASEBOARD_FAB2(SCH_1):PAGE77_I43@MSTR_SCONN.SCONN288_H44441004(CHIPS)':
 'VSS'<53>: CDS_PINID='VSS(53)';
NODE_NAME     J1G1 123
 '@BASEBOARD_FAB2_LIB.BASEBOARD_FAB2(SCH_1):PAGE77_I43@MSTR_SCONN.SCONN288_H44441004(CHIPS)':
 'VSS'<54>: CDS_PINID='VSS(54)';
NODE_NAME     J1G1 120
 '@BASEBOARD_FAB2_LIB.BASEBOARD_FAB2(SCH_1):PAGE77_I43@MSTR_SCONN.SCONN288_H44441004(CHIPS)':
 'VSS'<55>: CDS_PINID='VSS(55)';
NODE_NAME     J1G1 118
 '@BASEBOARD_FAB2_LIB.BASEBOARD_FAB2(SCH_1):PAGE77_I43@MSTR_SCONN.SCONN288_H44441004(CHIPS)':
 'VSS'<56>: CDS_PINID='VSS(56)';
NODE_NAME     J1G1 116
 '@BASEBOARD_FAB2_LIB.BASEBOARD_FAB2(SCH_1):PAGE77_I43@MSTR_SCONN.SCONN288_H44441004(CHIPS)':
 'VSS'<57>: CDS_PINID='VSS(57)';
NODE_NAME     J1G1 114
 '@BASEBOARD_FAB2_LIB.BASEBOARD_FAB2(SCH_1):PAGE77_I43@MSTR_SCONN.SCONN288_H44441004(CHIPS)':
 'VSS'<58>: CDS_PINID='VSS(58)';
NODE_NAME     J1G1 112
 '@BASEBOARD_FAB2_LIB.BASEBOARD_FAB2(SCH_1):PAGE77_I43@MSTR_SCONN.SCONN288_H44441004(CHIPS)':
 'VSS'<59>: CDS_PINID='VSS(59)';
NODE_NAME     J1G1 109
 '@BASEBOARD_FAB2_LIB.BASEBOARD_FAB2(SCH_1):PAGE77_I43@MSTR_SCONN.SCONN288_H44441004(CHIPS)':
 'VSS'<60>: CDS_PINID='VSS(60)';
NODE_NAME     J1G1 107
 '@BASEBOARD_FAB2_LIB.BASEBOARD_FAB2(SCH_1):PAGE77_I43@MSTR_SCONN.SCONN288_H44441004(CHIPS)':
 'VSS'<61>: CDS_PINID='VSS(61)';
NODE_NAME     J1G1 105
 '@BASEBOARD_FAB2_LIB.BASEBOARD_FAB2(SCH_1):PAGE77_I43@MSTR_SCONN.SCONN288_H44441004(CHIPS)':
 'VSS'<62>: CDS_PINID='VSS(62)';
NODE_NAME     J1G1 103
 '@BASEBOARD_FAB2_LIB.BASEBOARD_FAB2(SCH_1):PAGE77_I43@MSTR_SCONN.SCONN288_H44441004(CHIPS)':
 'VSS'<63>: CDS_PINID='VSS(63)';
NODE_NAME     J1G1 101
 '@BASEBOARD_FAB2_LIB.BASEBOARD_FAB2(SCH_1):PAGE77_I43@MSTR_SCONN.SCONN288_H44441004(CHIPS)':
 'VSS'<64>: CDS_PINID='VSS(64)';
NODE_NAME     J1G1 98
 '@BASEBOARD_FAB2_LIB.BASEBOARD_FAB2(SCH_1):PAGE77_I43@MSTR_SCONN.SCONN288_H44441004(CHIPS)':
 'VSS'<65>: CDS_PINID='VSS(65)';
NODE_NAME     J1G1 96
 '@BASEBOARD_FAB2_LIB.BASEBOARD_FAB2(SCH_1):PAGE77_I43@MSTR_SCONN.SCONN288_H44441004(CHIPS)':
 'VSS'<66>: CDS_PINID='VSS(66)';
NODE_NAME     J1G1 94
 '@BASEBOARD_FAB2_LIB.BASEBOARD_FAB2(SCH_1):PAGE77_I43@MSTR_SCONN.SCONN288_H44441004(CHIPS)':
 'VSS'<67>: CDS_PINID='VSS(67)';
NODE_NAME     J1G1 57
 '@BASEBOARD_FAB2_LIB.BASEBOARD_FAB2(SCH_1):PAGE77_I43@MSTR_SCONN.SCONN288_H44441004(CHIPS)':
 'VSS'<68>: CDS_PINID='VSS(68)';
NODE_NAME     J1G1 55
 '@BASEBOARD_FAB2_LIB.BASEBOARD_FAB2(SCH_1):PAGE77_I43@MSTR_SCONN.SCONN288_H44441004(CHIPS)':
 'VSS'<69>: CDS_PINID='VSS(69)';
NODE_NAME     J1G1 53
 '@BASEBOARD_FAB2_LIB.BASEBOARD_FAB2(SCH_1):PAGE77_I43@MSTR_SCONN.SCONN288_H44441004(CHIPS)':
 'VSS'<70>: CDS_PINID='VSS(70)';
NODE_NAME     J1G1 50
 '@BASEBOARD_FAB2_LIB.BASEBOARD_FAB2(SCH_1):PAGE77_I43@MSTR_SCONN.SCONN288_H44441004(CHIPS)':
 'VSS'<71>: CDS_PINID='VSS(71)';
NODE_NAME     J1G1 48
 '@BASEBOARD_FAB2_LIB.BASEBOARD_FAB2(SCH_1):PAGE77_I43@MSTR_SCONN.SCONN288_H44441004(CHIPS)':
 'VSS'<72>: CDS_PINID='VSS(72)';
NODE_NAME     J1G1 46
 '@BASEBOARD_FAB2_LIB.BASEBOARD_FAB2(SCH_1):PAGE77_I43@MSTR_SCONN.SCONN288_H44441004(CHIPS)':
 'VSS'<73>: CDS_PINID='VSS(73)';
NODE_NAME     J1G1 44
 '@BASEBOARD_FAB2_LIB.BASEBOARD_FAB2(SCH_1):PAGE77_I43@MSTR_SCONN.SCONN288_H44441004(CHIPS)':
 'VSS'<74>: CDS_PINID='VSS(74)';
NODE_NAME     J1G1 42
 '@BASEBOARD_FAB2_LIB.BASEBOARD_FAB2(SCH_1):PAGE77_I43@MSTR_SCONN.SCONN288_H44441004(CHIPS)':
 'VSS'<75>: CDS_PINID='VSS(75)';
NODE_NAME     J1G1 39
 '@BASEBOARD_FAB2_LIB.BASEBOARD_FAB2(SCH_1):PAGE77_I43@MSTR_SCONN.SCONN288_H44441004(CHIPS)':
 'VSS'<76>: CDS_PINID='VSS(76)';
NODE_NAME     J1G1 37
 '@BASEBOARD_FAB2_LIB.BASEBOARD_FAB2(SCH_1):PAGE77_I43@MSTR_SCONN.SCONN288_H44441004(CHIPS)':
 'VSS'<77>: CDS_PINID='VSS(77)';
NODE_NAME     J1G1 35
 '@BASEBOARD_FAB2_LIB.BASEBOARD_FAB2(SCH_1):PAGE77_I43@MSTR_SCONN.SCONN288_H44441004(CHIPS)':
 'VSS'<78>: CDS_PINID='VSS(78)';
NODE_NAME     J1G1 33
 '@BASEBOARD_FAB2_LIB.BASEBOARD_FAB2(SCH_1):PAGE77_I43@MSTR_SCONN.SCONN288_H44441004(CHIPS)':
 'VSS'<79>: CDS_PINID='VSS(79)';
NODE_NAME     J1G1 31
 '@BASEBOARD_FAB2_LIB.BASEBOARD_FAB2(SCH_1):PAGE77_I43@MSTR_SCONN.SCONN288_H44441004(CHIPS)':
 'VSS'<80>: CDS_PINID='VSS(80)';
NODE_NAME     J1G1 28
 '@BASEBOARD_FAB2_LIB.BASEBOARD_FAB2(SCH_1):PAGE77_I43@MSTR_SCONN.SCONN288_H44441004(CHIPS)':
 'VSS'<81>: CDS_PINID='VSS(81)';
NODE_NAME     J1G1 26
 '@BASEBOARD_FAB2_LIB.BASEBOARD_FAB2(SCH_1):PAGE77_I43@MSTR_SCONN.SCONN288_H44441004(CHIPS)':
 'VSS'<82>: CDS_PINID='VSS(82)';
NODE_NAME     J1G1 24
 '@BASEBOARD_FAB2_LIB.BASEBOARD_FAB2(SCH_1):PAGE77_I43@MSTR_SCONN.SCONN288_H44441004(CHIPS)':
 'VSS'<83>: CDS_PINID='VSS(83)';
NODE_NAME     J1G1 22
 '@BASEBOARD_FAB2_LIB.BASEBOARD_FAB2(SCH_1):PAGE77_I43@MSTR_SCONN.SCONN288_H44441004(CHIPS)':
 'VSS'<84>: CDS_PINID='VSS(84)';
NODE_NAME     J1G1 20
 '@BASEBOARD_FAB2_LIB.BASEBOARD_FAB2(SCH_1):PAGE77_I43@MSTR_SCONN.SCONN288_H44441004(CHIPS)':
 'VSS'<85>: CDS_PINID='VSS(85)';
NODE_NAME     J1G1 17
 '@BASEBOARD_FAB2_LIB.BASEBOARD_FAB2(SCH_1):PAGE77_I43@MSTR_SCONN.SCONN288_H44441004(CHIPS)':
 'VSS'<86>: CDS_PINID='VSS(86)';
NODE_NAME     J1G1 15
 '@BASEBOARD_FAB2_LIB.BASEBOARD_FAB2(SCH_1):PAGE77_I43@MSTR_SCONN.SCONN288_H44441004(CHIPS)':
 'VSS'<87>: CDS_PINID='VSS(87)';
NODE_NAME     J1G1 13
 '@BASEBOARD_FAB2_LIB.BASEBOARD_FAB2(SCH_1):PAGE77_I43@MSTR_SCONN.SCONN288_H44441004(CHIPS)':
 'VSS'<88>: CDS_PINID='VSS(88)';
NODE_NAME     J1G1 11
 '@BASEBOARD_FAB2_LIB.BASEBOARD_FAB2(SCH_1):PAGE77_I43@MSTR_SCONN.SCONN288_H44441004(CHIPS)':
 'VSS'<89>: CDS_PINID='VSS(89)';
NODE_NAME     J1G1 9
 '@BASEBOARD_FAB2_LIB.BASEBOARD_FAB2(SCH_1):PAGE77_I43@MSTR_SCONN.SCONN288_H44441004(CHIPS)':
 'VSS'<90>: CDS_PINID='VSS(90)';
NODE_NAME     J1G1 6
 '@BASEBOARD_FAB2_LIB.BASEBOARD_FAB2(SCH_1):PAGE77_I43@MSTR_SCONN.SCONN288_H44441004(CHIPS)':
 'VSS'<91>: CDS_PINID='VSS(91)';
NODE_NAME     J1G1 4
 '@BASEBOARD_FAB2_LIB.BASEBOARD_FAB2(SCH_1):PAGE77_I43@MSTR_SCONN.SCONN288_H44441004(CHIPS)':
 'VSS'<92>: CDS_PINID='VSS(92)';
NODE_NAME     J1G1 2
 '@BASEBOARD_FAB2_LIB.BASEBOARD_FAB2(SCH_1):PAGE77_I43@MSTR_SCONN.SCONN288_H44441004(CHIPS)':
 'VSS'<93>: CDS_PINID='VSS(93)';
NODE_NAME     J1G1 139
 '@BASEBOARD_FAB2_LIB.BASEBOARD_FAB2(SCH_1):PAGE77_I111@MSTR_SCONN.SCONN288_H44441004(CHIPS)':
 'SA'<0>: CDS_PINID='SA(0)';
NODE_NAME     J1G1 140
 '@BASEBOARD_FAB2_LIB.BASEBOARD_FAB2(SCH_1):PAGE77_I111@MSTR_SCONN.SCONN288_H44441004(CHIPS)':
 'SA'<1>: CDS_PINID='SA(1)';
NODE_NAME     J1G1 238
 '@BASEBOARD_FAB2_LIB.BASEBOARD_FAB2(SCH_1):PAGE77_I111@MSTR_SCONN.SCONN288_H44441004(CHIPS)':
 'SA'<2>: CDS_PINID='SA(2)';
NODE_NAME     C1F22 2
 '@BASEBOARD_FAB2_LIB.BASEBOARD_FAB2(SCH_1):PAGE77_I181@DEV_DISCRETE.CAP_A(CHIPS)':
 'B': CDS_PINID='B';
NODE_NAME     C9T7 2
 '@BASEBOARD_FAB2_LIB.BASEBOARD_FAB2(SCH_1):PAGE78_I2@DEV_DISCRETE.CAP_A(CHIPS)':
 'B': CDS_PINID='B';
NODE_NAME     J9T1 140
 '@BASEBOARD_FAB2_LIB.BASEBOARD_FAB2(SCH_1):PAGE78_I13@MSTR_SCONN.SCONN288_H44441003(CHIPS)':
 'SA'<1>: CDS_PINID='SA(1)';
NODE_NAME     J9T1 238
 '@BASEBOARD_FAB2_LIB.BASEBOARD_FAB2(SCH_1):PAGE78_I13@MSTR_SCONN.SCONN288_H44441003(CHIPS)':
 'SA'<2>: CDS_PINID='SA(2)';
NODE_NAME     J9T1 283
 '@BASEBOARD_FAB2_LIB.BASEBOARD_FAB2(SCH_1):PAGE78_I144@MSTR_SCONN.SCONN288_H44441003(CHIPS)':
 'VSS'<0>: CDS_PINID='VSS(0)';
NODE_NAME     J9T1 281
 '@BASEBOARD_FAB2_LIB.BASEBOARD_FAB2(SCH_1):PAGE78_I144@MSTR_SCONN.SCONN288_H44441003(CHIPS)':
 'VSS'<1>: CDS_PINID='VSS(1)';
NODE_NAME     J9T1 279
 '@BASEBOARD_FAB2_LIB.BASEBOARD_FAB2(SCH_1):PAGE78_I144@MSTR_SCONN.SCONN288_H44441003(CHIPS)':
 'VSS'<2>: CDS_PINID='VSS(2)';
NODE_NAME     J9T1 276
 '@BASEBOARD_FAB2_LIB.BASEBOARD_FAB2(SCH_1):PAGE78_I144@MSTR_SCONN.SCONN288_H44441003(CHIPS)':
 'VSS'<3>: CDS_PINID='VSS(3)';
NODE_NAME     J9T1 274
 '@BASEBOARD_FAB2_LIB.BASEBOARD_FAB2(SCH_1):PAGE78_I144@MSTR_SCONN.SCONN288_H44441003(CHIPS)':
 'VSS'<4>: CDS_PINID='VSS(4)';
NODE_NAME     J9T1 272
 '@BASEBOARD_FAB2_LIB.BASEBOARD_FAB2(SCH_1):PAGE78_I144@MSTR_SCONN.SCONN288_H44441003(CHIPS)':
 'VSS'<5>: CDS_PINID='VSS(5)';
NODE_NAME     J9T1 270
 '@BASEBOARD_FAB2_LIB.BASEBOARD_FAB2(SCH_1):PAGE78_I144@MSTR_SCONN.SCONN288_H44441003(CHIPS)':
 'VSS'<6>: CDS_PINID='VSS(6)';
NODE_NAME     J9T1 268
 '@BASEBOARD_FAB2_LIB.BASEBOARD_FAB2(SCH_1):PAGE78_I144@MSTR_SCONN.SCONN288_H44441003(CHIPS)':
 'VSS'<7>: CDS_PINID='VSS(7)';
NODE_NAME     J9T1 265
 '@BASEBOARD_FAB2_LIB.BASEBOARD_FAB2(SCH_1):PAGE78_I144@MSTR_SCONN.SCONN288_H44441003(CHIPS)':
 'VSS'<8>: CDS_PINID='VSS(8)';
NODE_NAME     J9T1 263
 '@BASEBOARD_FAB2_LIB.BASEBOARD_FAB2(SCH_1):PAGE78_I144@MSTR_SCONN.SCONN288_H44441003(CHIPS)':
 'VSS'<9>: CDS_PINID='VSS(9)';
NODE_NAME     J9T1 261
 '@BASEBOARD_FAB2_LIB.BASEBOARD_FAB2(SCH_1):PAGE78_I144@MSTR_SCONN.SCONN288_H44441003(CHIPS)':
 'VSS'<10>: CDS_PINID='VSS(10)';
NODE_NAME     J9T1 259
 '@BASEBOARD_FAB2_LIB.BASEBOARD_FAB2(SCH_1):PAGE78_I144@MSTR_SCONN.SCONN288_H44441003(CHIPS)':
 'VSS'<11>: CDS_PINID='VSS(11)';
NODE_NAME     J9T1 257
 '@BASEBOARD_FAB2_LIB.BASEBOARD_FAB2(SCH_1):PAGE78_I144@MSTR_SCONN.SCONN288_H44441003(CHIPS)':
 'VSS'<12>: CDS_PINID='VSS(12)';
NODE_NAME     J9T1 254
 '@BASEBOARD_FAB2_LIB.BASEBOARD_FAB2(SCH_1):PAGE78_I144@MSTR_SCONN.SCONN288_H44441003(CHIPS)':
 'VSS'<13>: CDS_PINID='VSS(13)';
NODE_NAME     J9T1 252
 '@BASEBOARD_FAB2_LIB.BASEBOARD_FAB2(SCH_1):PAGE78_I144@MSTR_SCONN.SCONN288_H44441003(CHIPS)':
 'VSS'<14>: CDS_PINID='VSS(14)';
NODE_NAME     J9T1 250
 '@BASEBOARD_FAB2_LIB.BASEBOARD_FAB2(SCH_1):PAGE78_I144@MSTR_SCONN.SCONN288_H44441003(CHIPS)':
 'VSS'<15>: CDS_PINID='VSS(15)';
NODE_NAME     J9T1 248
 '@BASEBOARD_FAB2_LIB.BASEBOARD_FAB2(SCH_1):PAGE78_I144@MSTR_SCONN.SCONN288_H44441003(CHIPS)':
 'VSS'<16>: CDS_PINID='VSS(16)';
NODE_NAME     J9T1 246
 '@BASEBOARD_FAB2_LIB.BASEBOARD_FAB2(SCH_1):PAGE78_I144@MSTR_SCONN.SCONN288_H44441003(CHIPS)':
 'VSS'<17>: CDS_PINID='VSS(17)';
NODE_NAME     J9T1 243
 '@BASEBOARD_FAB2_LIB.BASEBOARD_FAB2(SCH_1):PAGE78_I144@MSTR_SCONN.SCONN288_H44441003(CHIPS)':
 'VSS'<18>: CDS_PINID='VSS(18)';
NODE_NAME     J9T1 241
 '@BASEBOARD_FAB2_LIB.BASEBOARD_FAB2(SCH_1):PAGE78_I144@MSTR_SCONN.SCONN288_H44441003(CHIPS)':
 'VSS'<19>: CDS_PINID='VSS(19)';
NODE_NAME     J9T1 239
 '@BASEBOARD_FAB2_LIB.BASEBOARD_FAB2(SCH_1):PAGE78_I144@MSTR_SCONN.SCONN288_H44441003(CHIPS)':
 'VSS'<20>: CDS_PINID='VSS(20)';
NODE_NAME     J9T1 202
 '@BASEBOARD_FAB2_LIB.BASEBOARD_FAB2(SCH_1):PAGE78_I144@MSTR_SCONN.SCONN288_H44441003(CHIPS)':
 'VSS'<21>: CDS_PINID='VSS(21)';
NODE_NAME     J9T1 200
 '@BASEBOARD_FAB2_LIB.BASEBOARD_FAB2(SCH_1):PAGE78_I144@MSTR_SCONN.SCONN288_H44441003(CHIPS)':
 'VSS'<22>: CDS_PINID='VSS(22)';
NODE_NAME     J9T1 198
 '@BASEBOARD_FAB2_LIB.BASEBOARD_FAB2(SCH_1):PAGE78_I144@MSTR_SCONN.SCONN288_H44441003(CHIPS)':
 'VSS'<23>: CDS_PINID='VSS(23)';
NODE_NAME     J9T1 195
 '@BASEBOARD_FAB2_LIB.BASEBOARD_FAB2(SCH_1):PAGE78_I144@MSTR_SCONN.SCONN288_H44441003(CHIPS)':
 'VSS'<24>: CDS_PINID='VSS(24)';
NODE_NAME     J9T1 193
 '@BASEBOARD_FAB2_LIB.BASEBOARD_FAB2(SCH_1):PAGE78_I144@MSTR_SCONN.SCONN288_H44441003(CHIPS)':
 'VSS'<25>: CDS_PINID='VSS(25)';
NODE_NAME     J9T1 191
 '@BASEBOARD_FAB2_LIB.BASEBOARD_FAB2(SCH_1):PAGE78_I144@MSTR_SCONN.SCONN288_H44441003(CHIPS)':
 'VSS'<26>: CDS_PINID='VSS(26)';
NODE_NAME     J9T1 189
 '@BASEBOARD_FAB2_LIB.BASEBOARD_FAB2(SCH_1):PAGE78_I144@MSTR_SCONN.SCONN288_H44441003(CHIPS)':
 'VSS'<27>: CDS_PINID='VSS(27)';
NODE_NAME     J9T1 187
 '@BASEBOARD_FAB2_LIB.BASEBOARD_FAB2(SCH_1):PAGE78_I144@MSTR_SCONN.SCONN288_H44441003(CHIPS)':
 'VSS'<28>: CDS_PINID='VSS(28)';
NODE_NAME     J9T1 184
 '@BASEBOARD_FAB2_LIB.BASEBOARD_FAB2(SCH_1):PAGE78_I144@MSTR_SCONN.SCONN288_H44441003(CHIPS)':
 'VSS'<29>: CDS_PINID='VSS(29)';
NODE_NAME     J9T1 182
 '@BASEBOARD_FAB2_LIB.BASEBOARD_FAB2(SCH_1):PAGE78_I144@MSTR_SCONN.SCONN288_H44441003(CHIPS)':
 'VSS'<30>: CDS_PINID='VSS(30)';
NODE_NAME     J9T1 180
 '@BASEBOARD_FAB2_LIB.BASEBOARD_FAB2(SCH_1):PAGE78_I144@MSTR_SCONN.SCONN288_H44441003(CHIPS)':
 'VSS'<31>: CDS_PINID='VSS(31)';
NODE_NAME     J9T1 178
 '@BASEBOARD_FAB2_LIB.BASEBOARD_FAB2(SCH_1):PAGE78_I144@MSTR_SCONN.SCONN288_H44441003(CHIPS)':
 'VSS'<32>: CDS_PINID='VSS(32)';
NODE_NAME     J9T1 176
 '@BASEBOARD_FAB2_LIB.BASEBOARD_FAB2(SCH_1):PAGE78_I144@MSTR_SCONN.SCONN288_H44441003(CHIPS)':
 'VSS'<33>: CDS_PINID='VSS(33)';
NODE_NAME     J9T1 173
 '@BASEBOARD_FAB2_LIB.BASEBOARD_FAB2(SCH_1):PAGE78_I144@MSTR_SCONN.SCONN288_H44441003(CHIPS)':
 'VSS'<34>: CDS_PINID='VSS(34)';
NODE_NAME     J9T1 171
 '@BASEBOARD_FAB2_LIB.BASEBOARD_FAB2(SCH_1):PAGE78_I144@MSTR_SCONN.SCONN288_H44441003(CHIPS)':
 'VSS'<35>: CDS_PINID='VSS(35)';
NODE_NAME     J9T1 169
 '@BASEBOARD_FAB2_LIB.BASEBOARD_FAB2(SCH_1):PAGE78_I144@MSTR_SCONN.SCONN288_H44441003(CHIPS)':
 'VSS'<36>: CDS_PINID='VSS(36)';
NODE_NAME     J9T1 167
 '@BASEBOARD_FAB2_LIB.BASEBOARD_FAB2(SCH_1):PAGE78_I144@MSTR_SCONN.SCONN288_H44441003(CHIPS)':
 'VSS'<37>: CDS_PINID='VSS(37)';
NODE_NAME     J9T1 165
 '@BASEBOARD_FAB2_LIB.BASEBOARD_FAB2(SCH_1):PAGE78_I144@MSTR_SCONN.SCONN288_H44441003(CHIPS)':
 'VSS'<38>: CDS_PINID='VSS(38)';
NODE_NAME     J9T1 162
 '@BASEBOARD_FAB2_LIB.BASEBOARD_FAB2(SCH_1):PAGE78_I144@MSTR_SCONN.SCONN288_H44441003(CHIPS)':
 'VSS'<39>: CDS_PINID='VSS(39)';
NODE_NAME     J9T1 160
 '@BASEBOARD_FAB2_LIB.BASEBOARD_FAB2(SCH_1):PAGE78_I144@MSTR_SCONN.SCONN288_H44441003(CHIPS)':
 'VSS'<40>: CDS_PINID='VSS(40)';
NODE_NAME     J9T1 158
 '@BASEBOARD_FAB2_LIB.BASEBOARD_FAB2(SCH_1):PAGE78_I144@MSTR_SCONN.SCONN288_H44441003(CHIPS)':
 'VSS'<41>: CDS_PINID='VSS(41)';
NODE_NAME     J9T1 156
 '@BASEBOARD_FAB2_LIB.BASEBOARD_FAB2(SCH_1):PAGE78_I144@MSTR_SCONN.SCONN288_H44441003(CHIPS)':
 'VSS'<42>: CDS_PINID='VSS(42)';
NODE_NAME     J9T1 154
 '@BASEBOARD_FAB2_LIB.BASEBOARD_FAB2(SCH_1):PAGE78_I144@MSTR_SCONN.SCONN288_H44441003(CHIPS)':
 'VSS'<43>: CDS_PINID='VSS(43)';
NODE_NAME     J9T1 151
 '@BASEBOARD_FAB2_LIB.BASEBOARD_FAB2(SCH_1):PAGE78_I144@MSTR_SCONN.SCONN288_H44441003(CHIPS)':
 'VSS'<44>: CDS_PINID='VSS(44)';
NODE_NAME     J9T1 149
 '@BASEBOARD_FAB2_LIB.BASEBOARD_FAB2(SCH_1):PAGE78_I144@MSTR_SCONN.SCONN288_H44441003(CHIPS)':
 'VSS'<45>: CDS_PINID='VSS(45)';
NODE_NAME     J9T1 147
 '@BASEBOARD_FAB2_LIB.BASEBOARD_FAB2(SCH_1):PAGE78_I144@MSTR_SCONN.SCONN288_H44441003(CHIPS)':
 'VSS'<46>: CDS_PINID='VSS(46)';
NODE_NAME     J9T1 138
 '@BASEBOARD_FAB2_LIB.BASEBOARD_FAB2(SCH_1):PAGE78_I144@MSTR_SCONN.SCONN288_H44441003(CHIPS)':
 'VSS'<47>: CDS_PINID='VSS(47)';
NODE_NAME     J9T1 136
 '@BASEBOARD_FAB2_LIB.BASEBOARD_FAB2(SCH_1):PAGE78_I144@MSTR_SCONN.SCONN288_H44441003(CHIPS)':
 'VSS'<48>: CDS_PINID='VSS(48)';
NODE_NAME     J9T1 134
 '@BASEBOARD_FAB2_LIB.BASEBOARD_FAB2(SCH_1):PAGE78_I144@MSTR_SCONN.SCONN288_H44441003(CHIPS)':
 'VSS'<49>: CDS_PINID='VSS(49)';
NODE_NAME     J9T1 131
 '@BASEBOARD_FAB2_LIB.BASEBOARD_FAB2(SCH_1):PAGE78_I144@MSTR_SCONN.SCONN288_H44441003(CHIPS)':
 'VSS'<50>: CDS_PINID='VSS(50)';
NODE_NAME     J9T1 129
 '@BASEBOARD_FAB2_LIB.BASEBOARD_FAB2(SCH_1):PAGE78_I144@MSTR_SCONN.SCONN288_H44441003(CHIPS)':
 'VSS'<51>: CDS_PINID='VSS(51)';
NODE_NAME     J9T1 127
 '@BASEBOARD_FAB2_LIB.BASEBOARD_FAB2(SCH_1):PAGE78_I144@MSTR_SCONN.SCONN288_H44441003(CHIPS)':
 'VSS'<52>: CDS_PINID='VSS(52)';
NODE_NAME     J9T1 125
 '@BASEBOARD_FAB2_LIB.BASEBOARD_FAB2(SCH_1):PAGE78_I144@MSTR_SCONN.SCONN288_H44441003(CHIPS)':
 'VSS'<53>: CDS_PINID='VSS(53)';
NODE_NAME     J9T1 123
 '@BASEBOARD_FAB2_LIB.BASEBOARD_FAB2(SCH_1):PAGE78_I144@MSTR_SCONN.SCONN288_H44441003(CHIPS)':
 'VSS'<54>: CDS_PINID='VSS(54)';
NODE_NAME     J9T1 120
 '@BASEBOARD_FAB2_LIB.BASEBOARD_FAB2(SCH_1):PAGE78_I144@MSTR_SCONN.SCONN288_H44441003(CHIPS)':
 'VSS'<55>: CDS_PINID='VSS(55)';
NODE_NAME     J9T1 118
 '@BASEBOARD_FAB2_LIB.BASEBOARD_FAB2(SCH_1):PAGE78_I144@MSTR_SCONN.SCONN288_H44441003(CHIPS)':
 'VSS'<56>: CDS_PINID='VSS(56)';
NODE_NAME     J9T1 116
 '@BASEBOARD_FAB2_LIB.BASEBOARD_FAB2(SCH_1):PAGE78_I144@MSTR_SCONN.SCONN288_H44441003(CHIPS)':
 'VSS'<57>: CDS_PINID='VSS(57)';
NODE_NAME     J9T1 114
 '@BASEBOARD_FAB2_LIB.BASEBOARD_FAB2(SCH_1):PAGE78_I144@MSTR_SCONN.SCONN288_H44441003(CHIPS)':
 'VSS'<58>: CDS_PINID='VSS(58)';
NODE_NAME     J9T1 112
 '@BASEBOARD_FAB2_LIB.BASEBOARD_FAB2(SCH_1):PAGE78_I144@MSTR_SCONN.SCONN288_H44441003(CHIPS)':
 'VSS'<59>: CDS_PINID='VSS(59)';
NODE_NAME     J9T1 109
 '@BASEBOARD_FAB2_LIB.BASEBOARD_FAB2(SCH_1):PAGE78_I144@MSTR_SCONN.SCONN288_H44441003(CHIPS)':
 'VSS'<60>: CDS_PINID='VSS(60)';
NODE_NAME     J9T1 107
 '@BASEBOARD_FAB2_LIB.BASEBOARD_FAB2(SCH_1):PAGE78_I144@MSTR_SCONN.SCONN288_H44441003(CHIPS)':
 'VSS'<61>: CDS_PINID='VSS(61)';
NODE_NAME     J9T1 105
 '@BASEBOARD_FAB2_LIB.BASEBOARD_FAB2(SCH_1):PAGE78_I144@MSTR_SCONN.SCONN288_H44441003(CHIPS)':
 'VSS'<62>: CDS_PINID='VSS(62)';
NODE_NAME     J9T1 103
 '@BASEBOARD_FAB2_LIB.BASEBOARD_FAB2(SCH_1):PAGE78_I144@MSTR_SCONN.SCONN288_H44441003(CHIPS)':
 'VSS'<63>: CDS_PINID='VSS(63)';
NODE_NAME     J9T1 101
 '@BASEBOARD_FAB2_LIB.BASEBOARD_FAB2(SCH_1):PAGE78_I144@MSTR_SCONN.SCONN288_H44441003(CHIPS)':
 'VSS'<64>: CDS_PINID='VSS(64)';
NODE_NAME     J9T1 98
 '@BASEBOARD_FAB2_LIB.BASEBOARD_FAB2(SCH_1):PAGE78_I144@MSTR_SCONN.SCONN288_H44441003(CHIPS)':
 'VSS'<65>: CDS_PINID='VSS(65)';
NODE_NAME     J9T1 96
 '@BASEBOARD_FAB2_LIB.BASEBOARD_FAB2(SCH_1):PAGE78_I144@MSTR_SCONN.SCONN288_H44441003(CHIPS)':
 'VSS'<66>: CDS_PINID='VSS(66)';
NODE_NAME     J9T1 94
 '@BASEBOARD_FAB2_LIB.BASEBOARD_FAB2(SCH_1):PAGE78_I144@MSTR_SCONN.SCONN288_H44441003(CHIPS)':
 'VSS'<67>: CDS_PINID='VSS(67)';
NODE_NAME     J9T1 57
 '@BASEBOARD_FAB2_LIB.BASEBOARD_FAB2(SCH_1):PAGE78_I144@MSTR_SCONN.SCONN288_H44441003(CHIPS)':
 'VSS'<68>: CDS_PINID='VSS(68)';
NODE_NAME     J9T1 55
 '@BASEBOARD_FAB2_LIB.BASEBOARD_FAB2(SCH_1):PAGE78_I144@MSTR_SCONN.SCONN288_H44441003(CHIPS)':
 'VSS'<69>: CDS_PINID='VSS(69)';
NODE_NAME     J9T1 53
 '@BASEBOARD_FAB2_LIB.BASEBOARD_FAB2(SCH_1):PAGE78_I144@MSTR_SCONN.SCONN288_H44441003(CHIPS)':
 'VSS'<70>: CDS_PINID='VSS(70)';
NODE_NAME     J9T1 50
 '@BASEBOARD_FAB2_LIB.BASEBOARD_FAB2(SCH_1):PAGE78_I144@MSTR_SCONN.SCONN288_H44441003(CHIPS)':
 'VSS'<71>: CDS_PINID='VSS(71)';
NODE_NAME     J9T1 48
 '@BASEBOARD_FAB2_LIB.BASEBOARD_FAB2(SCH_1):PAGE78_I144@MSTR_SCONN.SCONN288_H44441003(CHIPS)':
 'VSS'<72>: CDS_PINID='VSS(72)';
NODE_NAME     J9T1 46
 '@BASEBOARD_FAB2_LIB.BASEBOARD_FAB2(SCH_1):PAGE78_I144@MSTR_SCONN.SCONN288_H44441003(CHIPS)':
 'VSS'<73>: CDS_PINID='VSS(73)';
NODE_NAME     J9T1 44
 '@BASEBOARD_FAB2_LIB.BASEBOARD_FAB2(SCH_1):PAGE78_I144@MSTR_SCONN.SCONN288_H44441003(CHIPS)':
 'VSS'<74>: CDS_PINID='VSS(74)';
NODE_NAME     J9T1 42
 '@BASEBOARD_FAB2_LIB.BASEBOARD_FAB2(SCH_1):PAGE78_I144@MSTR_SCONN.SCONN288_H44441003(CHIPS)':
 'VSS'<75>: CDS_PINID='VSS(75)';
NODE_NAME     J9T1 39
 '@BASEBOARD_FAB2_LIB.BASEBOARD_FAB2(SCH_1):PAGE78_I144@MSTR_SCONN.SCONN288_H44441003(CHIPS)':
 'VSS'<76>: CDS_PINID='VSS(76)';
NODE_NAME     J9T1 37
 '@BASEBOARD_FAB2_LIB.BASEBOARD_FAB2(SCH_1):PAGE78_I144@MSTR_SCONN.SCONN288_H44441003(CHIPS)':
 'VSS'<77>: CDS_PINID='VSS(77)';
NODE_NAME     J9T1 35
 '@BASEBOARD_FAB2_LIB.BASEBOARD_FAB2(SCH_1):PAGE78_I144@MSTR_SCONN.SCONN288_H44441003(CHIPS)':
 'VSS'<78>: CDS_PINID='VSS(78)';
NODE_NAME     J9T1 33
 '@BASEBOARD_FAB2_LIB.BASEBOARD_FAB2(SCH_1):PAGE78_I144@MSTR_SCONN.SCONN288_H44441003(CHIPS)':
 'VSS'<79>: CDS_PINID='VSS(79)';
NODE_NAME     J9T1 31
 '@BASEBOARD_FAB2_LIB.BASEBOARD_FAB2(SCH_1):PAGE78_I144@MSTR_SCONN.SCONN288_H44441003(CHIPS)':
 'VSS'<80>: CDS_PINID='VSS(80)';
NODE_NAME     J9T1 28
 '@BASEBOARD_FAB2_LIB.BASEBOARD_FAB2(SCH_1):PAGE78_I144@MSTR_SCONN.SCONN288_H44441003(CHIPS)':
 'VSS'<81>: CDS_PINID='VSS(81)';
NODE_NAME     J9T1 26
 '@BASEBOARD_FAB2_LIB.BASEBOARD_FAB2(SCH_1):PAGE78_I144@MSTR_SCONN.SCONN288_H44441003(CHIPS)':
 'VSS'<82>: CDS_PINID='VSS(82)';
NODE_NAME     J9T1 24
 '@BASEBOARD_FAB2_LIB.BASEBOARD_FAB2(SCH_1):PAGE78_I144@MSTR_SCONN.SCONN288_H44441003(CHIPS)':
 'VSS'<83>: CDS_PINID='VSS(83)';
NODE_NAME     J9T1 22
 '@BASEBOARD_FAB2_LIB.BASEBOARD_FAB2(SCH_1):PAGE78_I144@MSTR_SCONN.SCONN288_H44441003(CHIPS)':
 'VSS'<84>: CDS_PINID='VSS(84)';
NODE_NAME     J9T1 20
 '@BASEBOARD_FAB2_LIB.BASEBOARD_FAB2(SCH_1):PAGE78_I144@MSTR_SCONN.SCONN288_H44441003(CHIPS)':
 'VSS'<85>: CDS_PINID='VSS(85)';
NODE_NAME     J9T1 17
 '@BASEBOARD_FAB2_LIB.BASEBOARD_FAB2(SCH_1):PAGE78_I144@MSTR_SCONN.SCONN288_H44441003(CHIPS)':
 'VSS'<86>: CDS_PINID='VSS(86)';
NODE_NAME     J9T1 15
 '@BASEBOARD_FAB2_LIB.BASEBOARD_FAB2(SCH_1):PAGE78_I144@MSTR_SCONN.SCONN288_H44441003(CHIPS)':
 'VSS'<87>: CDS_PINID='VSS(87)';
NODE_NAME     J9T1 13
 '@BASEBOARD_FAB2_LIB.BASEBOARD_FAB2(SCH_1):PAGE78_I144@MSTR_SCONN.SCONN288_H44441003(CHIPS)':
 'VSS'<88>: CDS_PINID='VSS(88)';
NODE_NAME     J9T1 11
 '@BASEBOARD_FAB2_LIB.BASEBOARD_FAB2(SCH_1):PAGE78_I144@MSTR_SCONN.SCONN288_H44441003(CHIPS)':
 'VSS'<89>: CDS_PINID='VSS(89)';
NODE_NAME     J9T1 9
 '@BASEBOARD_FAB2_LIB.BASEBOARD_FAB2(SCH_1):PAGE78_I144@MSTR_SCONN.SCONN288_H44441003(CHIPS)':
 'VSS'<90>: CDS_PINID='VSS(90)';
NODE_NAME     J9T1 6
 '@BASEBOARD_FAB2_LIB.BASEBOARD_FAB2(SCH_1):PAGE78_I144@MSTR_SCONN.SCONN288_H44441003(CHIPS)':
 'VSS'<91>: CDS_PINID='VSS(91)';
NODE_NAME     J9T1 4
 '@BASEBOARD_FAB2_LIB.BASEBOARD_FAB2(SCH_1):PAGE78_I144@MSTR_SCONN.SCONN288_H44441003(CHIPS)':
 'VSS'<92>: CDS_PINID='VSS(92)';
NODE_NAME     J9T1 2
 '@BASEBOARD_FAB2_LIB.BASEBOARD_FAB2(SCH_1):PAGE78_I144@MSTR_SCONN.SCONN288_H44441003(CHIPS)':
 'VSS'<93>: CDS_PINID='VSS(93)';
NODE_NAME     J1G2 283
 '@BASEBOARD_FAB2_LIB.BASEBOARD_FAB2(SCH_1):PAGE79_I43@MSTR_SCONN.SCONN288_H44441004(CHIPS)':
 'VSS'<0>: CDS_PINID='VSS(0)';
NODE_NAME     J1G2 281
 '@BASEBOARD_FAB2_LIB.BASEBOARD_FAB2(SCH_1):PAGE79_I43@MSTR_SCONN.SCONN288_H44441004(CHIPS)':
 'VSS'<1>: CDS_PINID='VSS(1)';
NODE_NAME     J1G2 279
 '@BASEBOARD_FAB2_LIB.BASEBOARD_FAB2(SCH_1):PAGE79_I43@MSTR_SCONN.SCONN288_H44441004(CHIPS)':
 'VSS'<2>: CDS_PINID='VSS(2)';
NODE_NAME     J1G2 276
 '@BASEBOARD_FAB2_LIB.BASEBOARD_FAB2(SCH_1):PAGE79_I43@MSTR_SCONN.SCONN288_H44441004(CHIPS)':
 'VSS'<3>: CDS_PINID='VSS(3)';
NODE_NAME     J1G2 274
 '@BASEBOARD_FAB2_LIB.BASEBOARD_FAB2(SCH_1):PAGE79_I43@MSTR_SCONN.SCONN288_H44441004(CHIPS)':
 'VSS'<4>: CDS_PINID='VSS(4)';
NODE_NAME     J1G2 272
 '@BASEBOARD_FAB2_LIB.BASEBOARD_FAB2(SCH_1):PAGE79_I43@MSTR_SCONN.SCONN288_H44441004(CHIPS)':
 'VSS'<5>: CDS_PINID='VSS(5)';
NODE_NAME     J1G2 270
 '@BASEBOARD_FAB2_LIB.BASEBOARD_FAB2(SCH_1):PAGE79_I43@MSTR_SCONN.SCONN288_H44441004(CHIPS)':
 'VSS'<6>: CDS_PINID='VSS(6)';
NODE_NAME     J1G2 268
 '@BASEBOARD_FAB2_LIB.BASEBOARD_FAB2(SCH_1):PAGE79_I43@MSTR_SCONN.SCONN288_H44441004(CHIPS)':
 'VSS'<7>: CDS_PINID='VSS(7)';
NODE_NAME     J1G2 265
 '@BASEBOARD_FAB2_LIB.BASEBOARD_FAB2(SCH_1):PAGE79_I43@MSTR_SCONN.SCONN288_H44441004(CHIPS)':
 'VSS'<8>: CDS_PINID='VSS(8)';
NODE_NAME     J1G2 263
 '@BASEBOARD_FAB2_LIB.BASEBOARD_FAB2(SCH_1):PAGE79_I43@MSTR_SCONN.SCONN288_H44441004(CHIPS)':
 'VSS'<9>: CDS_PINID='VSS(9)';
NODE_NAME     J1G2 261
 '@BASEBOARD_FAB2_LIB.BASEBOARD_FAB2(SCH_1):PAGE79_I43@MSTR_SCONN.SCONN288_H44441004(CHIPS)':
 'VSS'<10>: CDS_PINID='VSS(10)';
NODE_NAME     J1G2 259
 '@BASEBOARD_FAB2_LIB.BASEBOARD_FAB2(SCH_1):PAGE79_I43@MSTR_SCONN.SCONN288_H44441004(CHIPS)':
 'VSS'<11>: CDS_PINID='VSS(11)';
NODE_NAME     J1G2 257
 '@BASEBOARD_FAB2_LIB.BASEBOARD_FAB2(SCH_1):PAGE79_I43@MSTR_SCONN.SCONN288_H44441004(CHIPS)':
 'VSS'<12>: CDS_PINID='VSS(12)';
NODE_NAME     J1G2 254
 '@BASEBOARD_FAB2_LIB.BASEBOARD_FAB2(SCH_1):PAGE79_I43@MSTR_SCONN.SCONN288_H44441004(CHIPS)':
 'VSS'<13>: CDS_PINID='VSS(13)';
NODE_NAME     J1G2 252
 '@BASEBOARD_FAB2_LIB.BASEBOARD_FAB2(SCH_1):PAGE79_I43@MSTR_SCONN.SCONN288_H44441004(CHIPS)':
 'VSS'<14>: CDS_PINID='VSS(14)';
NODE_NAME     J1G2 250
 '@BASEBOARD_FAB2_LIB.BASEBOARD_FAB2(SCH_1):PAGE79_I43@MSTR_SCONN.SCONN288_H44441004(CHIPS)':
 'VSS'<15>: CDS_PINID='VSS(15)';
NODE_NAME     J1G2 248
 '@BASEBOARD_FAB2_LIB.BASEBOARD_FAB2(SCH_1):PAGE79_I43@MSTR_SCONN.SCONN288_H44441004(CHIPS)':
 'VSS'<16>: CDS_PINID='VSS(16)';
NODE_NAME     J1G2 246
 '@BASEBOARD_FAB2_LIB.BASEBOARD_FAB2(SCH_1):PAGE79_I43@MSTR_SCONN.SCONN288_H44441004(CHIPS)':
 'VSS'<17>: CDS_PINID='VSS(17)';
NODE_NAME     J1G2 243
 '@BASEBOARD_FAB2_LIB.BASEBOARD_FAB2(SCH_1):PAGE79_I43@MSTR_SCONN.SCONN288_H44441004(CHIPS)':
 'VSS'<18>: CDS_PINID='VSS(18)';
NODE_NAME     J1G2 241
 '@BASEBOARD_FAB2_LIB.BASEBOARD_FAB2(SCH_1):PAGE79_I43@MSTR_SCONN.SCONN288_H44441004(CHIPS)':
 'VSS'<19>: CDS_PINID='VSS(19)';
NODE_NAME     J1G2 239
 '@BASEBOARD_FAB2_LIB.BASEBOARD_FAB2(SCH_1):PAGE79_I43@MSTR_SCONN.SCONN288_H44441004(CHIPS)':
 'VSS'<20>: CDS_PINID='VSS(20)';
NODE_NAME     J1G2 202
 '@BASEBOARD_FAB2_LIB.BASEBOARD_FAB2(SCH_1):PAGE79_I43@MSTR_SCONN.SCONN288_H44441004(CHIPS)':
 'VSS'<21>: CDS_PINID='VSS(21)';
NODE_NAME     J1G2 200
 '@BASEBOARD_FAB2_LIB.BASEBOARD_FAB2(SCH_1):PAGE79_I43@MSTR_SCONN.SCONN288_H44441004(CHIPS)':
 'VSS'<22>: CDS_PINID='VSS(22)';
NODE_NAME     J1G2 198
 '@BASEBOARD_FAB2_LIB.BASEBOARD_FAB2(SCH_1):PAGE79_I43@MSTR_SCONN.SCONN288_H44441004(CHIPS)':
 'VSS'<23>: CDS_PINID='VSS(23)';
NODE_NAME     J1G2 195
 '@BASEBOARD_FAB2_LIB.BASEBOARD_FAB2(SCH_1):PAGE79_I43@MSTR_SCONN.SCONN288_H44441004(CHIPS)':
 'VSS'<24>: CDS_PINID='VSS(24)';
NODE_NAME     J1G2 193
 '@BASEBOARD_FAB2_LIB.BASEBOARD_FAB2(SCH_1):PAGE79_I43@MSTR_SCONN.SCONN288_H44441004(CHIPS)':
 'VSS'<25>: CDS_PINID='VSS(25)';
NODE_NAME     J1G2 191
 '@BASEBOARD_FAB2_LIB.BASEBOARD_FAB2(SCH_1):PAGE79_I43@MSTR_SCONN.SCONN288_H44441004(CHIPS)':
 'VSS'<26>: CDS_PINID='VSS(26)';
NODE_NAME     J1G2 189
 '@BASEBOARD_FAB2_LIB.BASEBOARD_FAB2(SCH_1):PAGE79_I43@MSTR_SCONN.SCONN288_H44441004(CHIPS)':
 'VSS'<27>: CDS_PINID='VSS(27)';
NODE_NAME     J1G2 187
 '@BASEBOARD_FAB2_LIB.BASEBOARD_FAB2(SCH_1):PAGE79_I43@MSTR_SCONN.SCONN288_H44441004(CHIPS)':
 'VSS'<28>: CDS_PINID='VSS(28)';
NODE_NAME     J1G2 184
 '@BASEBOARD_FAB2_LIB.BASEBOARD_FAB2(SCH_1):PAGE79_I43@MSTR_SCONN.SCONN288_H44441004(CHIPS)':
 'VSS'<29>: CDS_PINID='VSS(29)';
NODE_NAME     J1G2 182
 '@BASEBOARD_FAB2_LIB.BASEBOARD_FAB2(SCH_1):PAGE79_I43@MSTR_SCONN.SCONN288_H44441004(CHIPS)':
 'VSS'<30>: CDS_PINID='VSS(30)';
NODE_NAME     J1G2 180
 '@BASEBOARD_FAB2_LIB.BASEBOARD_FAB2(SCH_1):PAGE79_I43@MSTR_SCONN.SCONN288_H44441004(CHIPS)':
 'VSS'<31>: CDS_PINID='VSS(31)';
NODE_NAME     J1G2 178
 '@BASEBOARD_FAB2_LIB.BASEBOARD_FAB2(SCH_1):PAGE79_I43@MSTR_SCONN.SCONN288_H44441004(CHIPS)':
 'VSS'<32>: CDS_PINID='VSS(32)';
NODE_NAME     J1G2 176
 '@BASEBOARD_FAB2_LIB.BASEBOARD_FAB2(SCH_1):PAGE79_I43@MSTR_SCONN.SCONN288_H44441004(CHIPS)':
 'VSS'<33>: CDS_PINID='VSS(33)';
NODE_NAME     J1G2 173
 '@BASEBOARD_FAB2_LIB.BASEBOARD_FAB2(SCH_1):PAGE79_I43@MSTR_SCONN.SCONN288_H44441004(CHIPS)':
 'VSS'<34>: CDS_PINID='VSS(34)';
NODE_NAME     J1G2 171
 '@BASEBOARD_FAB2_LIB.BASEBOARD_FAB2(SCH_1):PAGE79_I43@MSTR_SCONN.SCONN288_H44441004(CHIPS)':
 'VSS'<35>: CDS_PINID='VSS(35)';
NODE_NAME     J1G2 169
 '@BASEBOARD_FAB2_LIB.BASEBOARD_FAB2(SCH_1):PAGE79_I43@MSTR_SCONN.SCONN288_H44441004(CHIPS)':
 'VSS'<36>: CDS_PINID='VSS(36)';
NODE_NAME     J1G2 167
 '@BASEBOARD_FAB2_LIB.BASEBOARD_FAB2(SCH_1):PAGE79_I43@MSTR_SCONN.SCONN288_H44441004(CHIPS)':
 'VSS'<37>: CDS_PINID='VSS(37)';
NODE_NAME     J1G2 165
 '@BASEBOARD_FAB2_LIB.BASEBOARD_FAB2(SCH_1):PAGE79_I43@MSTR_SCONN.SCONN288_H44441004(CHIPS)':
 'VSS'<38>: CDS_PINID='VSS(38)';
NODE_NAME     J1G2 162
 '@BASEBOARD_FAB2_LIB.BASEBOARD_FAB2(SCH_1):PAGE79_I43@MSTR_SCONN.SCONN288_H44441004(CHIPS)':
 'VSS'<39>: CDS_PINID='VSS(39)';
NODE_NAME     J1G2 160
 '@BASEBOARD_FAB2_LIB.BASEBOARD_FAB2(SCH_1):PAGE79_I43@MSTR_SCONN.SCONN288_H44441004(CHIPS)':
 'VSS'<40>: CDS_PINID='VSS(40)';
NODE_NAME     J1G2 158
 '@BASEBOARD_FAB2_LIB.BASEBOARD_FAB2(SCH_1):PAGE79_I43@MSTR_SCONN.SCONN288_H44441004(CHIPS)':
 'VSS'<41>: CDS_PINID='VSS(41)';
NODE_NAME     J1G2 156
 '@BASEBOARD_FAB2_LIB.BASEBOARD_FAB2(SCH_1):PAGE79_I43@MSTR_SCONN.SCONN288_H44441004(CHIPS)':
 'VSS'<42>: CDS_PINID='VSS(42)';
NODE_NAME     J1G2 154
 '@BASEBOARD_FAB2_LIB.BASEBOARD_FAB2(SCH_1):PAGE79_I43@MSTR_SCONN.SCONN288_H44441004(CHIPS)':
 'VSS'<43>: CDS_PINID='VSS(43)';
NODE_NAME     J1G2 151
 '@BASEBOARD_FAB2_LIB.BASEBOARD_FAB2(SCH_1):PAGE79_I43@MSTR_SCONN.SCONN288_H44441004(CHIPS)':
 'VSS'<44>: CDS_PINID='VSS(44)';
NODE_NAME     J1G2 149
 '@BASEBOARD_FAB2_LIB.BASEBOARD_FAB2(SCH_1):PAGE79_I43@MSTR_SCONN.SCONN288_H44441004(CHIPS)':
 'VSS'<45>: CDS_PINID='VSS(45)';
NODE_NAME     J1G2 147
 '@BASEBOARD_FAB2_LIB.BASEBOARD_FAB2(SCH_1):PAGE79_I43@MSTR_SCONN.SCONN288_H44441004(CHIPS)':
 'VSS'<46>: CDS_PINID='VSS(46)';
NODE_NAME     J1G2 138
 '@BASEBOARD_FAB2_LIB.BASEBOARD_FAB2(SCH_1):PAGE79_I43@MSTR_SCONN.SCONN288_H44441004(CHIPS)':
 'VSS'<47>: CDS_PINID='VSS(47)';
NODE_NAME     J1G2 136
 '@BASEBOARD_FAB2_LIB.BASEBOARD_FAB2(SCH_1):PAGE79_I43@MSTR_SCONN.SCONN288_H44441004(CHIPS)':
 'VSS'<48>: CDS_PINID='VSS(48)';
NODE_NAME     J1G2 134
 '@BASEBOARD_FAB2_LIB.BASEBOARD_FAB2(SCH_1):PAGE79_I43@MSTR_SCONN.SCONN288_H44441004(CHIPS)':
 'VSS'<49>: CDS_PINID='VSS(49)';
NODE_NAME     J1G2 131
 '@BASEBOARD_FAB2_LIB.BASEBOARD_FAB2(SCH_1):PAGE79_I43@MSTR_SCONN.SCONN288_H44441004(CHIPS)':
 'VSS'<50>: CDS_PINID='VSS(50)';
NODE_NAME     J1G2 129
 '@BASEBOARD_FAB2_LIB.BASEBOARD_FAB2(SCH_1):PAGE79_I43@MSTR_SCONN.SCONN288_H44441004(CHIPS)':
 'VSS'<51>: CDS_PINID='VSS(51)';
NODE_NAME     J1G2 127
 '@BASEBOARD_FAB2_LIB.BASEBOARD_FAB2(SCH_1):PAGE79_I43@MSTR_SCONN.SCONN288_H44441004(CHIPS)':
 'VSS'<52>: CDS_PINID='VSS(52)';
NODE_NAME     J1G2 125
 '@BASEBOARD_FAB2_LIB.BASEBOARD_FAB2(SCH_1):PAGE79_I43@MSTR_SCONN.SCONN288_H44441004(CHIPS)':
 'VSS'<53>: CDS_PINID='VSS(53)';
NODE_NAME     J1G2 123
 '@BASEBOARD_FAB2_LIB.BASEBOARD_FAB2(SCH_1):PAGE79_I43@MSTR_SCONN.SCONN288_H44441004(CHIPS)':
 'VSS'<54>: CDS_PINID='VSS(54)';
NODE_NAME     J1G2 120
 '@BASEBOARD_FAB2_LIB.BASEBOARD_FAB2(SCH_1):PAGE79_I43@MSTR_SCONN.SCONN288_H44441004(CHIPS)':
 'VSS'<55>: CDS_PINID='VSS(55)';
NODE_NAME     J1G2 118
 '@BASEBOARD_FAB2_LIB.BASEBOARD_FAB2(SCH_1):PAGE79_I43@MSTR_SCONN.SCONN288_H44441004(CHIPS)':
 'VSS'<56>: CDS_PINID='VSS(56)';
NODE_NAME     J1G2 116
 '@BASEBOARD_FAB2_LIB.BASEBOARD_FAB2(SCH_1):PAGE79_I43@MSTR_SCONN.SCONN288_H44441004(CHIPS)':
 'VSS'<57>: CDS_PINID='VSS(57)';
NODE_NAME     J1G2 114
 '@BASEBOARD_FAB2_LIB.BASEBOARD_FAB2(SCH_1):PAGE79_I43@MSTR_SCONN.SCONN288_H44441004(CHIPS)':
 'VSS'<58>: CDS_PINID='VSS(58)';
NODE_NAME     J1G2 112
 '@BASEBOARD_FAB2_LIB.BASEBOARD_FAB2(SCH_1):PAGE79_I43@MSTR_SCONN.SCONN288_H44441004(CHIPS)':
 'VSS'<59>: CDS_PINID='VSS(59)';
NODE_NAME     J1G2 109
 '@BASEBOARD_FAB2_LIB.BASEBOARD_FAB2(SCH_1):PAGE79_I43@MSTR_SCONN.SCONN288_H44441004(CHIPS)':
 'VSS'<60>: CDS_PINID='VSS(60)';
NODE_NAME     J1G2 107
 '@BASEBOARD_FAB2_LIB.BASEBOARD_FAB2(SCH_1):PAGE79_I43@MSTR_SCONN.SCONN288_H44441004(CHIPS)':
 'VSS'<61>: CDS_PINID='VSS(61)';
NODE_NAME     J1G2 105
 '@BASEBOARD_FAB2_LIB.BASEBOARD_FAB2(SCH_1):PAGE79_I43@MSTR_SCONN.SCONN288_H44441004(CHIPS)':
 'VSS'<62>: CDS_PINID='VSS(62)';
NODE_NAME     J1G2 103
 '@BASEBOARD_FAB2_LIB.BASEBOARD_FAB2(SCH_1):PAGE79_I43@MSTR_SCONN.SCONN288_H44441004(CHIPS)':
 'VSS'<63>: CDS_PINID='VSS(63)';
NODE_NAME     J1G2 101
 '@BASEBOARD_FAB2_LIB.BASEBOARD_FAB2(SCH_1):PAGE79_I43@MSTR_SCONN.SCONN288_H44441004(CHIPS)':
 'VSS'<64>: CDS_PINID='VSS(64)';
NODE_NAME     J1G2 98
 '@BASEBOARD_FAB2_LIB.BASEBOARD_FAB2(SCH_1):PAGE79_I43@MSTR_SCONN.SCONN288_H44441004(CHIPS)':
 'VSS'<65>: CDS_PINID='VSS(65)';
NODE_NAME     J1G2 96
 '@BASEBOARD_FAB2_LIB.BASEBOARD_FAB2(SCH_1):PAGE79_I43@MSTR_SCONN.SCONN288_H44441004(CHIPS)':
 'VSS'<66>: CDS_PINID='VSS(66)';
NODE_NAME     J1G2 94
 '@BASEBOARD_FAB2_LIB.BASEBOARD_FAB2(SCH_1):PAGE79_I43@MSTR_SCONN.SCONN288_H44441004(CHIPS)':
 'VSS'<67>: CDS_PINID='VSS(67)';
NODE_NAME     J1G2 57
 '@BASEBOARD_FAB2_LIB.BASEBOARD_FAB2(SCH_1):PAGE79_I43@MSTR_SCONN.SCONN288_H44441004(CHIPS)':
 'VSS'<68>: CDS_PINID='VSS(68)';
NODE_NAME     J1G2 55
 '@BASEBOARD_FAB2_LIB.BASEBOARD_FAB2(SCH_1):PAGE79_I43@MSTR_SCONN.SCONN288_H44441004(CHIPS)':
 'VSS'<69>: CDS_PINID='VSS(69)';
NODE_NAME     J1G2 53
 '@BASEBOARD_FAB2_LIB.BASEBOARD_FAB2(SCH_1):PAGE79_I43@MSTR_SCONN.SCONN288_H44441004(CHIPS)':
 'VSS'<70>: CDS_PINID='VSS(70)';
NODE_NAME     J1G2 50
 '@BASEBOARD_FAB2_LIB.BASEBOARD_FAB2(SCH_1):PAGE79_I43@MSTR_SCONN.SCONN288_H44441004(CHIPS)':
 'VSS'<71>: CDS_PINID='VSS(71)';
NODE_NAME     J1G2 48
 '@BASEBOARD_FAB2_LIB.BASEBOARD_FAB2(SCH_1):PAGE79_I43@MSTR_SCONN.SCONN288_H44441004(CHIPS)':
 'VSS'<72>: CDS_PINID='VSS(72)';
NODE_NAME     J1G2 46
 '@BASEBOARD_FAB2_LIB.BASEBOARD_FAB2(SCH_1):PAGE79_I43@MSTR_SCONN.SCONN288_H44441004(CHIPS)':
 'VSS'<73>: CDS_PINID='VSS(73)';
NODE_NAME     J1G2 44
 '@BASEBOARD_FAB2_LIB.BASEBOARD_FAB2(SCH_1):PAGE79_I43@MSTR_SCONN.SCONN288_H44441004(CHIPS)':
 'VSS'<74>: CDS_PINID='VSS(74)';
NODE_NAME     J1G2 42
 '@BASEBOARD_FAB2_LIB.BASEBOARD_FAB2(SCH_1):PAGE79_I43@MSTR_SCONN.SCONN288_H44441004(CHIPS)':
 'VSS'<75>: CDS_PINID='VSS(75)';
NODE_NAME     J1G2 39
 '@BASEBOARD_FAB2_LIB.BASEBOARD_FAB2(SCH_1):PAGE79_I43@MSTR_SCONN.SCONN288_H44441004(CHIPS)':
 'VSS'<76>: CDS_PINID='VSS(76)';
NODE_NAME     J1G2 37
 '@BASEBOARD_FAB2_LIB.BASEBOARD_FAB2(SCH_1):PAGE79_I43@MSTR_SCONN.SCONN288_H44441004(CHIPS)':
 'VSS'<77>: CDS_PINID='VSS(77)';
NODE_NAME     J1G2 35
 '@BASEBOARD_FAB2_LIB.BASEBOARD_FAB2(SCH_1):PAGE79_I43@MSTR_SCONN.SCONN288_H44441004(CHIPS)':
 'VSS'<78>: CDS_PINID='VSS(78)';
NODE_NAME     J1G2 33
 '@BASEBOARD_FAB2_LIB.BASEBOARD_FAB2(SCH_1):PAGE79_I43@MSTR_SCONN.SCONN288_H44441004(CHIPS)':
 'VSS'<79>: CDS_PINID='VSS(79)';
NODE_NAME     J1G2 31
 '@BASEBOARD_FAB2_LIB.BASEBOARD_FAB2(SCH_1):PAGE79_I43@MSTR_SCONN.SCONN288_H44441004(CHIPS)':
 'VSS'<80>: CDS_PINID='VSS(80)';
NODE_NAME     J1G2 28
 '@BASEBOARD_FAB2_LIB.BASEBOARD_FAB2(SCH_1):PAGE79_I43@MSTR_SCONN.SCONN288_H44441004(CHIPS)':
 'VSS'<81>: CDS_PINID='VSS(81)';
NODE_NAME     J1G2 26
 '@BASEBOARD_FAB2_LIB.BASEBOARD_FAB2(SCH_1):PAGE79_I43@MSTR_SCONN.SCONN288_H44441004(CHIPS)':
 'VSS'<82>: CDS_PINID='VSS(82)';
NODE_NAME     J1G2 24
 '@BASEBOARD_FAB2_LIB.BASEBOARD_FAB2(SCH_1):PAGE79_I43@MSTR_SCONN.SCONN288_H44441004(CHIPS)':
 'VSS'<83>: CDS_PINID='VSS(83)';
NODE_NAME     J1G2 22
 '@BASEBOARD_FAB2_LIB.BASEBOARD_FAB2(SCH_1):PAGE79_I43@MSTR_SCONN.SCONN288_H44441004(CHIPS)':
 'VSS'<84>: CDS_PINID='VSS(84)';
NODE_NAME     J1G2 20
 '@BASEBOARD_FAB2_LIB.BASEBOARD_FAB2(SCH_1):PAGE79_I43@MSTR_SCONN.SCONN288_H44441004(CHIPS)':
 'VSS'<85>: CDS_PINID='VSS(85)';
NODE_NAME     J1G2 17
 '@BASEBOARD_FAB2_LIB.BASEBOARD_FAB2(SCH_1):PAGE79_I43@MSTR_SCONN.SCONN288_H44441004(CHIPS)':
 'VSS'<86>: CDS_PINID='VSS(86)';
NODE_NAME     J1G2 15
 '@BASEBOARD_FAB2_LIB.BASEBOARD_FAB2(SCH_1):PAGE79_I43@MSTR_SCONN.SCONN288_H44441004(CHIPS)':
 'VSS'<87>: CDS_PINID='VSS(87)';
NODE_NAME     J1G2 13
 '@BASEBOARD_FAB2_LIB.BASEBOARD_FAB2(SCH_1):PAGE79_I43@MSTR_SCONN.SCONN288_H44441004(CHIPS)':
 'VSS'<88>: CDS_PINID='VSS(88)';
NODE_NAME     J1G2 11
 '@BASEBOARD_FAB2_LIB.BASEBOARD_FAB2(SCH_1):PAGE79_I43@MSTR_SCONN.SCONN288_H44441004(CHIPS)':
 'VSS'<89>: CDS_PINID='VSS(89)';
NODE_NAME     J1G2 9
 '@BASEBOARD_FAB2_LIB.BASEBOARD_FAB2(SCH_1):PAGE79_I43@MSTR_SCONN.SCONN288_H44441004(CHIPS)':
 'VSS'<90>: CDS_PINID='VSS(90)';
NODE_NAME     J1G2 6
 '@BASEBOARD_FAB2_LIB.BASEBOARD_FAB2(SCH_1):PAGE79_I43@MSTR_SCONN.SCONN288_H44441004(CHIPS)':
 'VSS'<91>: CDS_PINID='VSS(91)';
NODE_NAME     J1G2 4
 '@BASEBOARD_FAB2_LIB.BASEBOARD_FAB2(SCH_1):PAGE79_I43@MSTR_SCONN.SCONN288_H44441004(CHIPS)':
 'VSS'<92>: CDS_PINID='VSS(92)';
NODE_NAME     J1G2 2
 '@BASEBOARD_FAB2_LIB.BASEBOARD_FAB2(SCH_1):PAGE79_I43@MSTR_SCONN.SCONN288_H44441004(CHIPS)':
 'VSS'<93>: CDS_PINID='VSS(93)';
NODE_NAME     J1G2 139
 '@BASEBOARD_FAB2_LIB.BASEBOARD_FAB2(SCH_1):PAGE79_I111@MSTR_SCONN.SCONN288_H44441004(CHIPS)':
 'SA'<0>: CDS_PINID='SA(0)';
NODE_NAME     J1G2 238
 '@BASEBOARD_FAB2_LIB.BASEBOARD_FAB2(SCH_1):PAGE79_I111@MSTR_SCONN.SCONN288_H44441004(CHIPS)':
 'SA'<2>: CDS_PINID='SA(2)';
NODE_NAME     C9U7 2
 '@BASEBOARD_FAB2_LIB.BASEBOARD_FAB2(SCH_1):PAGE79_I178@DEV_DISCRETE.CAP_A(CHIPS)':
 'B': CDS_PINID='B';
NODE_NAME     C1G10 2
 '@BASEBOARD_FAB2_LIB.BASEBOARD_FAB2(SCH_1):PAGE80_I3@DEV_DISCRETE.CAP_A(CHIPS)':
 'B': CDS_PINID='B';
NODE_NAME     J9U1 238
 '@BASEBOARD_FAB2_LIB.BASEBOARD_FAB2(SCH_1):PAGE80_I24@MSTR_SCONN.SCONN288_H44441003(CHIPS)':
 'SA'<2>: CDS_PINID='SA(2)';
NODE_NAME     J9U1 283
 '@BASEBOARD_FAB2_LIB.BASEBOARD_FAB2(SCH_1):PAGE80_I138@MSTR_SCONN.SCONN288_H44441003(CHIPS)':
 'VSS'<0>: CDS_PINID='VSS(0)';
NODE_NAME     J9U1 281
 '@BASEBOARD_FAB2_LIB.BASEBOARD_FAB2(SCH_1):PAGE80_I138@MSTR_SCONN.SCONN288_H44441003(CHIPS)':
 'VSS'<1>: CDS_PINID='VSS(1)';
NODE_NAME     J9U1 279
 '@BASEBOARD_FAB2_LIB.BASEBOARD_FAB2(SCH_1):PAGE80_I138@MSTR_SCONN.SCONN288_H44441003(CHIPS)':
 'VSS'<2>: CDS_PINID='VSS(2)';
NODE_NAME     J9U1 276
 '@BASEBOARD_FAB2_LIB.BASEBOARD_FAB2(SCH_1):PAGE80_I138@MSTR_SCONN.SCONN288_H44441003(CHIPS)':
 'VSS'<3>: CDS_PINID='VSS(3)';
NODE_NAME     J9U1 274
 '@BASEBOARD_FAB2_LIB.BASEBOARD_FAB2(SCH_1):PAGE80_I138@MSTR_SCONN.SCONN288_H44441003(CHIPS)':
 'VSS'<4>: CDS_PINID='VSS(4)';
NODE_NAME     J9U1 272
 '@BASEBOARD_FAB2_LIB.BASEBOARD_FAB2(SCH_1):PAGE80_I138@MSTR_SCONN.SCONN288_H44441003(CHIPS)':
 'VSS'<5>: CDS_PINID='VSS(5)';
NODE_NAME     J9U1 270
 '@BASEBOARD_FAB2_LIB.BASEBOARD_FAB2(SCH_1):PAGE80_I138@MSTR_SCONN.SCONN288_H44441003(CHIPS)':
 'VSS'<6>: CDS_PINID='VSS(6)';
NODE_NAME     J9U1 268
 '@BASEBOARD_FAB2_LIB.BASEBOARD_FAB2(SCH_1):PAGE80_I138@MSTR_SCONN.SCONN288_H44441003(CHIPS)':
 'VSS'<7>: CDS_PINID='VSS(7)';
NODE_NAME     J9U1 265
 '@BASEBOARD_FAB2_LIB.BASEBOARD_FAB2(SCH_1):PAGE80_I138@MSTR_SCONN.SCONN288_H44441003(CHIPS)':
 'VSS'<8>: CDS_PINID='VSS(8)';
NODE_NAME     J9U1 263
 '@BASEBOARD_FAB2_LIB.BASEBOARD_FAB2(SCH_1):PAGE80_I138@MSTR_SCONN.SCONN288_H44441003(CHIPS)':
 'VSS'<9>: CDS_PINID='VSS(9)';
NODE_NAME     J9U1 261
 '@BASEBOARD_FAB2_LIB.BASEBOARD_FAB2(SCH_1):PAGE80_I138@MSTR_SCONN.SCONN288_H44441003(CHIPS)':
 'VSS'<10>: CDS_PINID='VSS(10)';
NODE_NAME     J9U1 259
 '@BASEBOARD_FAB2_LIB.BASEBOARD_FAB2(SCH_1):PAGE80_I138@MSTR_SCONN.SCONN288_H44441003(CHIPS)':
 'VSS'<11>: CDS_PINID='VSS(11)';
NODE_NAME     J9U1 257
 '@BASEBOARD_FAB2_LIB.BASEBOARD_FAB2(SCH_1):PAGE80_I138@MSTR_SCONN.SCONN288_H44441003(CHIPS)':
 'VSS'<12>: CDS_PINID='VSS(12)';
NODE_NAME     J9U1 254
 '@BASEBOARD_FAB2_LIB.BASEBOARD_FAB2(SCH_1):PAGE80_I138@MSTR_SCONN.SCONN288_H44441003(CHIPS)':
 'VSS'<13>: CDS_PINID='VSS(13)';
NODE_NAME     J9U1 252
 '@BASEBOARD_FAB2_LIB.BASEBOARD_FAB2(SCH_1):PAGE80_I138@MSTR_SCONN.SCONN288_H44441003(CHIPS)':
 'VSS'<14>: CDS_PINID='VSS(14)';
NODE_NAME     J9U1 250
 '@BASEBOARD_FAB2_LIB.BASEBOARD_FAB2(SCH_1):PAGE80_I138@MSTR_SCONN.SCONN288_H44441003(CHIPS)':
 'VSS'<15>: CDS_PINID='VSS(15)';
NODE_NAME     J9U1 248
 '@BASEBOARD_FAB2_LIB.BASEBOARD_FAB2(SCH_1):PAGE80_I138@MSTR_SCONN.SCONN288_H44441003(CHIPS)':
 'VSS'<16>: CDS_PINID='VSS(16)';
NODE_NAME     J9U1 246
 '@BASEBOARD_FAB2_LIB.BASEBOARD_FAB2(SCH_1):PAGE80_I138@MSTR_SCONN.SCONN288_H44441003(CHIPS)':
 'VSS'<17>: CDS_PINID='VSS(17)';
NODE_NAME     J9U1 243
 '@BASEBOARD_FAB2_LIB.BASEBOARD_FAB2(SCH_1):PAGE80_I138@MSTR_SCONN.SCONN288_H44441003(CHIPS)':
 'VSS'<18>: CDS_PINID='VSS(18)';
NODE_NAME     J9U1 241
 '@BASEBOARD_FAB2_LIB.BASEBOARD_FAB2(SCH_1):PAGE80_I138@MSTR_SCONN.SCONN288_H44441003(CHIPS)':
 'VSS'<19>: CDS_PINID='VSS(19)';
NODE_NAME     J9U1 239
 '@BASEBOARD_FAB2_LIB.BASEBOARD_FAB2(SCH_1):PAGE80_I138@MSTR_SCONN.SCONN288_H44441003(CHIPS)':
 'VSS'<20>: CDS_PINID='VSS(20)';
NODE_NAME     J9U1 202
 '@BASEBOARD_FAB2_LIB.BASEBOARD_FAB2(SCH_1):PAGE80_I138@MSTR_SCONN.SCONN288_H44441003(CHIPS)':
 'VSS'<21>: CDS_PINID='VSS(21)';
NODE_NAME     J9U1 200
 '@BASEBOARD_FAB2_LIB.BASEBOARD_FAB2(SCH_1):PAGE80_I138@MSTR_SCONN.SCONN288_H44441003(CHIPS)':
 'VSS'<22>: CDS_PINID='VSS(22)';
NODE_NAME     J9U1 198
 '@BASEBOARD_FAB2_LIB.BASEBOARD_FAB2(SCH_1):PAGE80_I138@MSTR_SCONN.SCONN288_H44441003(CHIPS)':
 'VSS'<23>: CDS_PINID='VSS(23)';
NODE_NAME     J9U1 195
 '@BASEBOARD_FAB2_LIB.BASEBOARD_FAB2(SCH_1):PAGE80_I138@MSTR_SCONN.SCONN288_H44441003(CHIPS)':
 'VSS'<24>: CDS_PINID='VSS(24)';
NODE_NAME     J9U1 193
 '@BASEBOARD_FAB2_LIB.BASEBOARD_FAB2(SCH_1):PAGE80_I138@MSTR_SCONN.SCONN288_H44441003(CHIPS)':
 'VSS'<25>: CDS_PINID='VSS(25)';
NODE_NAME     J9U1 191
 '@BASEBOARD_FAB2_LIB.BASEBOARD_FAB2(SCH_1):PAGE80_I138@MSTR_SCONN.SCONN288_H44441003(CHIPS)':
 'VSS'<26>: CDS_PINID='VSS(26)';
NODE_NAME     J9U1 189
 '@BASEBOARD_FAB2_LIB.BASEBOARD_FAB2(SCH_1):PAGE80_I138@MSTR_SCONN.SCONN288_H44441003(CHIPS)':
 'VSS'<27>: CDS_PINID='VSS(27)';
NODE_NAME     J9U1 187
 '@BASEBOARD_FAB2_LIB.BASEBOARD_FAB2(SCH_1):PAGE80_I138@MSTR_SCONN.SCONN288_H44441003(CHIPS)':
 'VSS'<28>: CDS_PINID='VSS(28)';
NODE_NAME     J9U1 184
 '@BASEBOARD_FAB2_LIB.BASEBOARD_FAB2(SCH_1):PAGE80_I138@MSTR_SCONN.SCONN288_H44441003(CHIPS)':
 'VSS'<29>: CDS_PINID='VSS(29)';
NODE_NAME     J9U1 182
 '@BASEBOARD_FAB2_LIB.BASEBOARD_FAB2(SCH_1):PAGE80_I138@MSTR_SCONN.SCONN288_H44441003(CHIPS)':
 'VSS'<30>: CDS_PINID='VSS(30)';
NODE_NAME     J9U1 180
 '@BASEBOARD_FAB2_LIB.BASEBOARD_FAB2(SCH_1):PAGE80_I138@MSTR_SCONN.SCONN288_H44441003(CHIPS)':
 'VSS'<31>: CDS_PINID='VSS(31)';
NODE_NAME     J9U1 178
 '@BASEBOARD_FAB2_LIB.BASEBOARD_FAB2(SCH_1):PAGE80_I138@MSTR_SCONN.SCONN288_H44441003(CHIPS)':
 'VSS'<32>: CDS_PINID='VSS(32)';
NODE_NAME     J9U1 176
 '@BASEBOARD_FAB2_LIB.BASEBOARD_FAB2(SCH_1):PAGE80_I138@MSTR_SCONN.SCONN288_H44441003(CHIPS)':
 'VSS'<33>: CDS_PINID='VSS(33)';
NODE_NAME     J9U1 173
 '@BASEBOARD_FAB2_LIB.BASEBOARD_FAB2(SCH_1):PAGE80_I138@MSTR_SCONN.SCONN288_H44441003(CHIPS)':
 'VSS'<34>: CDS_PINID='VSS(34)';
NODE_NAME     J9U1 171
 '@BASEBOARD_FAB2_LIB.BASEBOARD_FAB2(SCH_1):PAGE80_I138@MSTR_SCONN.SCONN288_H44441003(CHIPS)':
 'VSS'<35>: CDS_PINID='VSS(35)';
NODE_NAME     J9U1 169
 '@BASEBOARD_FAB2_LIB.BASEBOARD_FAB2(SCH_1):PAGE80_I138@MSTR_SCONN.SCONN288_H44441003(CHIPS)':
 'VSS'<36>: CDS_PINID='VSS(36)';
NODE_NAME     J9U1 167
 '@BASEBOARD_FAB2_LIB.BASEBOARD_FAB2(SCH_1):PAGE80_I138@MSTR_SCONN.SCONN288_H44441003(CHIPS)':
 'VSS'<37>: CDS_PINID='VSS(37)';
NODE_NAME     J9U1 165
 '@BASEBOARD_FAB2_LIB.BASEBOARD_FAB2(SCH_1):PAGE80_I138@MSTR_SCONN.SCONN288_H44441003(CHIPS)':
 'VSS'<38>: CDS_PINID='VSS(38)';
NODE_NAME     J9U1 162
 '@BASEBOARD_FAB2_LIB.BASEBOARD_FAB2(SCH_1):PAGE80_I138@MSTR_SCONN.SCONN288_H44441003(CHIPS)':
 'VSS'<39>: CDS_PINID='VSS(39)';
NODE_NAME     J9U1 160
 '@BASEBOARD_FAB2_LIB.BASEBOARD_FAB2(SCH_1):PAGE80_I138@MSTR_SCONN.SCONN288_H44441003(CHIPS)':
 'VSS'<40>: CDS_PINID='VSS(40)';
NODE_NAME     J9U1 158
 '@BASEBOARD_FAB2_LIB.BASEBOARD_FAB2(SCH_1):PAGE80_I138@MSTR_SCONN.SCONN288_H44441003(CHIPS)':
 'VSS'<41>: CDS_PINID='VSS(41)';
NODE_NAME     J9U1 156
 '@BASEBOARD_FAB2_LIB.BASEBOARD_FAB2(SCH_1):PAGE80_I138@MSTR_SCONN.SCONN288_H44441003(CHIPS)':
 'VSS'<42>: CDS_PINID='VSS(42)';
NODE_NAME     J9U1 154
 '@BASEBOARD_FAB2_LIB.BASEBOARD_FAB2(SCH_1):PAGE80_I138@MSTR_SCONN.SCONN288_H44441003(CHIPS)':
 'VSS'<43>: CDS_PINID='VSS(43)';
NODE_NAME     J9U1 151
 '@BASEBOARD_FAB2_LIB.BASEBOARD_FAB2(SCH_1):PAGE80_I138@MSTR_SCONN.SCONN288_H44441003(CHIPS)':
 'VSS'<44>: CDS_PINID='VSS(44)';
NODE_NAME     J9U1 149
 '@BASEBOARD_FAB2_LIB.BASEBOARD_FAB2(SCH_1):PAGE80_I138@MSTR_SCONN.SCONN288_H44441003(CHIPS)':
 'VSS'<45>: CDS_PINID='VSS(45)';
NODE_NAME     J9U1 147
 '@BASEBOARD_FAB2_LIB.BASEBOARD_FAB2(SCH_1):PAGE80_I138@MSTR_SCONN.SCONN288_H44441003(CHIPS)':
 'VSS'<46>: CDS_PINID='VSS(46)';
NODE_NAME     J9U1 138
 '@BASEBOARD_FAB2_LIB.BASEBOARD_FAB2(SCH_1):PAGE80_I138@MSTR_SCONN.SCONN288_H44441003(CHIPS)':
 'VSS'<47>: CDS_PINID='VSS(47)';
NODE_NAME     J9U1 136
 '@BASEBOARD_FAB2_LIB.BASEBOARD_FAB2(SCH_1):PAGE80_I138@MSTR_SCONN.SCONN288_H44441003(CHIPS)':
 'VSS'<48>: CDS_PINID='VSS(48)';
NODE_NAME     J9U1 134
 '@BASEBOARD_FAB2_LIB.BASEBOARD_FAB2(SCH_1):PAGE80_I138@MSTR_SCONN.SCONN288_H44441003(CHIPS)':
 'VSS'<49>: CDS_PINID='VSS(49)';
NODE_NAME     J9U1 131
 '@BASEBOARD_FAB2_LIB.BASEBOARD_FAB2(SCH_1):PAGE80_I138@MSTR_SCONN.SCONN288_H44441003(CHIPS)':
 'VSS'<50>: CDS_PINID='VSS(50)';
NODE_NAME     J9U1 129
 '@BASEBOARD_FAB2_LIB.BASEBOARD_FAB2(SCH_1):PAGE80_I138@MSTR_SCONN.SCONN288_H44441003(CHIPS)':
 'VSS'<51>: CDS_PINID='VSS(51)';
NODE_NAME     J9U1 127
 '@BASEBOARD_FAB2_LIB.BASEBOARD_FAB2(SCH_1):PAGE80_I138@MSTR_SCONN.SCONN288_H44441003(CHIPS)':
 'VSS'<52>: CDS_PINID='VSS(52)';
NODE_NAME     J9U1 125
 '@BASEBOARD_FAB2_LIB.BASEBOARD_FAB2(SCH_1):PAGE80_I138@MSTR_SCONN.SCONN288_H44441003(CHIPS)':
 'VSS'<53>: CDS_PINID='VSS(53)';
NODE_NAME     J9U1 123
 '@BASEBOARD_FAB2_LIB.BASEBOARD_FAB2(SCH_1):PAGE80_I138@MSTR_SCONN.SCONN288_H44441003(CHIPS)':
 'VSS'<54>: CDS_PINID='VSS(54)';
NODE_NAME     J9U1 120
 '@BASEBOARD_FAB2_LIB.BASEBOARD_FAB2(SCH_1):PAGE80_I138@MSTR_SCONN.SCONN288_H44441003(CHIPS)':
 'VSS'<55>: CDS_PINID='VSS(55)';
NODE_NAME     J9U1 118
 '@BASEBOARD_FAB2_LIB.BASEBOARD_FAB2(SCH_1):PAGE80_I138@MSTR_SCONN.SCONN288_H44441003(CHIPS)':
 'VSS'<56>: CDS_PINID='VSS(56)';
NODE_NAME     J9U1 116
 '@BASEBOARD_FAB2_LIB.BASEBOARD_FAB2(SCH_1):PAGE80_I138@MSTR_SCONN.SCONN288_H44441003(CHIPS)':
 'VSS'<57>: CDS_PINID='VSS(57)';
NODE_NAME     J9U1 114
 '@BASEBOARD_FAB2_LIB.BASEBOARD_FAB2(SCH_1):PAGE80_I138@MSTR_SCONN.SCONN288_H44441003(CHIPS)':
 'VSS'<58>: CDS_PINID='VSS(58)';
NODE_NAME     J9U1 112
 '@BASEBOARD_FAB2_LIB.BASEBOARD_FAB2(SCH_1):PAGE80_I138@MSTR_SCONN.SCONN288_H44441003(CHIPS)':
 'VSS'<59>: CDS_PINID='VSS(59)';
NODE_NAME     J9U1 109
 '@BASEBOARD_FAB2_LIB.BASEBOARD_FAB2(SCH_1):PAGE80_I138@MSTR_SCONN.SCONN288_H44441003(CHIPS)':
 'VSS'<60>: CDS_PINID='VSS(60)';
NODE_NAME     J9U1 107
 '@BASEBOARD_FAB2_LIB.BASEBOARD_FAB2(SCH_1):PAGE80_I138@MSTR_SCONN.SCONN288_H44441003(CHIPS)':
 'VSS'<61>: CDS_PINID='VSS(61)';
NODE_NAME     J9U1 105
 '@BASEBOARD_FAB2_LIB.BASEBOARD_FAB2(SCH_1):PAGE80_I138@MSTR_SCONN.SCONN288_H44441003(CHIPS)':
 'VSS'<62>: CDS_PINID='VSS(62)';
NODE_NAME     J9U1 103
 '@BASEBOARD_FAB2_LIB.BASEBOARD_FAB2(SCH_1):PAGE80_I138@MSTR_SCONN.SCONN288_H44441003(CHIPS)':
 'VSS'<63>: CDS_PINID='VSS(63)';
NODE_NAME     J9U1 101
 '@BASEBOARD_FAB2_LIB.BASEBOARD_FAB2(SCH_1):PAGE80_I138@MSTR_SCONN.SCONN288_H44441003(CHIPS)':
 'VSS'<64>: CDS_PINID='VSS(64)';
NODE_NAME     J9U1 98
 '@BASEBOARD_FAB2_LIB.BASEBOARD_FAB2(SCH_1):PAGE80_I138@MSTR_SCONN.SCONN288_H44441003(CHIPS)':
 'VSS'<65>: CDS_PINID='VSS(65)';
NODE_NAME     J9U1 96
 '@BASEBOARD_FAB2_LIB.BASEBOARD_FAB2(SCH_1):PAGE80_I138@MSTR_SCONN.SCONN288_H44441003(CHIPS)':
 'VSS'<66>: CDS_PINID='VSS(66)';
NODE_NAME     J9U1 94
 '@BASEBOARD_FAB2_LIB.BASEBOARD_FAB2(SCH_1):PAGE80_I138@MSTR_SCONN.SCONN288_H44441003(CHIPS)':
 'VSS'<67>: CDS_PINID='VSS(67)';
NODE_NAME     J9U1 57
 '@BASEBOARD_FAB2_LIB.BASEBOARD_FAB2(SCH_1):PAGE80_I138@MSTR_SCONN.SCONN288_H44441003(CHIPS)':
 'VSS'<68>: CDS_PINID='VSS(68)';
NODE_NAME     J9U1 55
 '@BASEBOARD_FAB2_LIB.BASEBOARD_FAB2(SCH_1):PAGE80_I138@MSTR_SCONN.SCONN288_H44441003(CHIPS)':
 'VSS'<69>: CDS_PINID='VSS(69)';
NODE_NAME     J9U1 53
 '@BASEBOARD_FAB2_LIB.BASEBOARD_FAB2(SCH_1):PAGE80_I138@MSTR_SCONN.SCONN288_H44441003(CHIPS)':
 'VSS'<70>: CDS_PINID='VSS(70)';
NODE_NAME     J9U1 50
 '@BASEBOARD_FAB2_LIB.BASEBOARD_FAB2(SCH_1):PAGE80_I138@MSTR_SCONN.SCONN288_H44441003(CHIPS)':
 'VSS'<71>: CDS_PINID='VSS(71)';
NODE_NAME     J9U1 48
 '@BASEBOARD_FAB2_LIB.BASEBOARD_FAB2(SCH_1):PAGE80_I138@MSTR_SCONN.SCONN288_H44441003(CHIPS)':
 'VSS'<72>: CDS_PINID='VSS(72)';
NODE_NAME     J9U1 46
 '@BASEBOARD_FAB2_LIB.BASEBOARD_FAB2(SCH_1):PAGE80_I138@MSTR_SCONN.SCONN288_H44441003(CHIPS)':
 'VSS'<73>: CDS_PINID='VSS(73)';
NODE_NAME     J9U1 44
 '@BASEBOARD_FAB2_LIB.BASEBOARD_FAB2(SCH_1):PAGE80_I138@MSTR_SCONN.SCONN288_H44441003(CHIPS)':
 'VSS'<74>: CDS_PINID='VSS(74)';
NODE_NAME     J9U1 42
 '@BASEBOARD_FAB2_LIB.BASEBOARD_FAB2(SCH_1):PAGE80_I138@MSTR_SCONN.SCONN288_H44441003(CHIPS)':
 'VSS'<75>: CDS_PINID='VSS(75)';
NODE_NAME     J9U1 39
 '@BASEBOARD_FAB2_LIB.BASEBOARD_FAB2(SCH_1):PAGE80_I138@MSTR_SCONN.SCONN288_H44441003(CHIPS)':
 'VSS'<76>: CDS_PINID='VSS(76)';
NODE_NAME     J9U1 37
 '@BASEBOARD_FAB2_LIB.BASEBOARD_FAB2(SCH_1):PAGE80_I138@MSTR_SCONN.SCONN288_H44441003(CHIPS)':
 'VSS'<77>: CDS_PINID='VSS(77)';
NODE_NAME     J9U1 35
 '@BASEBOARD_FAB2_LIB.BASEBOARD_FAB2(SCH_1):PAGE80_I138@MSTR_SCONN.SCONN288_H44441003(CHIPS)':
 'VSS'<78>: CDS_PINID='VSS(78)';
NODE_NAME     J9U1 33
 '@BASEBOARD_FAB2_LIB.BASEBOARD_FAB2(SCH_1):PAGE80_I138@MSTR_SCONN.SCONN288_H44441003(CHIPS)':
 'VSS'<79>: CDS_PINID='VSS(79)';
NODE_NAME     J9U1 31
 '@BASEBOARD_FAB2_LIB.BASEBOARD_FAB2(SCH_1):PAGE80_I138@MSTR_SCONN.SCONN288_H44441003(CHIPS)':
 'VSS'<80>: CDS_PINID='VSS(80)';
NODE_NAME     J9U1 28
 '@BASEBOARD_FAB2_LIB.BASEBOARD_FAB2(SCH_1):PAGE80_I138@MSTR_SCONN.SCONN288_H44441003(CHIPS)':
 'VSS'<81>: CDS_PINID='VSS(81)';
NODE_NAME     J9U1 26
 '@BASEBOARD_FAB2_LIB.BASEBOARD_FAB2(SCH_1):PAGE80_I138@MSTR_SCONN.SCONN288_H44441003(CHIPS)':
 'VSS'<82>: CDS_PINID='VSS(82)';
NODE_NAME     J9U1 24
 '@BASEBOARD_FAB2_LIB.BASEBOARD_FAB2(SCH_1):PAGE80_I138@MSTR_SCONN.SCONN288_H44441003(CHIPS)':
 'VSS'<83>: CDS_PINID='VSS(83)';
NODE_NAME     J9U1 22
 '@BASEBOARD_FAB2_LIB.BASEBOARD_FAB2(SCH_1):PAGE80_I138@MSTR_SCONN.SCONN288_H44441003(CHIPS)':
 'VSS'<84>: CDS_PINID='VSS(84)';
NODE_NAME     J9U1 20
 '@BASEBOARD_FAB2_LIB.BASEBOARD_FAB2(SCH_1):PAGE80_I138@MSTR_SCONN.SCONN288_H44441003(CHIPS)':
 'VSS'<85>: CDS_PINID='VSS(85)';
NODE_NAME     J9U1 17
 '@BASEBOARD_FAB2_LIB.BASEBOARD_FAB2(SCH_1):PAGE80_I138@MSTR_SCONN.SCONN288_H44441003(CHIPS)':
 'VSS'<86>: CDS_PINID='VSS(86)';
NODE_NAME     J9U1 15
 '@BASEBOARD_FAB2_LIB.BASEBOARD_FAB2(SCH_1):PAGE80_I138@MSTR_SCONN.SCONN288_H44441003(CHIPS)':
 'VSS'<87>: CDS_PINID='VSS(87)';
NODE_NAME     J9U1 13
 '@BASEBOARD_FAB2_LIB.BASEBOARD_FAB2(SCH_1):PAGE80_I138@MSTR_SCONN.SCONN288_H44441003(CHIPS)':
 'VSS'<88>: CDS_PINID='VSS(88)';
NODE_NAME     J9U1 11
 '@BASEBOARD_FAB2_LIB.BASEBOARD_FAB2(SCH_1):PAGE80_I138@MSTR_SCONN.SCONN288_H44441003(CHIPS)':
 'VSS'<89>: CDS_PINID='VSS(89)';
NODE_NAME     J9U1 9
 '@BASEBOARD_FAB2_LIB.BASEBOARD_FAB2(SCH_1):PAGE80_I138@MSTR_SCONN.SCONN288_H44441003(CHIPS)':
 'VSS'<90>: CDS_PINID='VSS(90)';
NODE_NAME     J9U1 6
 '@BASEBOARD_FAB2_LIB.BASEBOARD_FAB2(SCH_1):PAGE80_I138@MSTR_SCONN.SCONN288_H44441003(CHIPS)':
 'VSS'<91>: CDS_PINID='VSS(91)';
NODE_NAME     J9U1 4
 '@BASEBOARD_FAB2_LIB.BASEBOARD_FAB2(SCH_1):PAGE80_I138@MSTR_SCONN.SCONN288_H44441003(CHIPS)':
 'VSS'<92>: CDS_PINID='VSS(92)';
NODE_NAME     J9U1 2
 '@BASEBOARD_FAB2_LIB.BASEBOARD_FAB2(SCH_1):PAGE80_I138@MSTR_SCONN.SCONN288_H44441003(CHIPS)':
 'VSS'<93>: CDS_PINID='VSS(93)';
NODE_NAME     C9U10 2
 '@BASEBOARD_FAB2_LIB.BASEBOARD_FAB2(SCH_1):PAGE81_I178@DEV_DISCRETE.CAP_A(CHIPS)':
 'B': CDS_PINID='B';
NODE_NAME     J1G3 283
 '@BASEBOARD_FAB2_LIB.BASEBOARD_FAB2(SCH_1):PAGE81_I185@MSTR_SCONN.SCONN288_H44441004(CHIPS)':
 'VSS'<0>: CDS_PINID='VSS(0)';
NODE_NAME     J1G3 281
 '@BASEBOARD_FAB2_LIB.BASEBOARD_FAB2(SCH_1):PAGE81_I185@MSTR_SCONN.SCONN288_H44441004(CHIPS)':
 'VSS'<1>: CDS_PINID='VSS(1)';
NODE_NAME     J1G3 279
 '@BASEBOARD_FAB2_LIB.BASEBOARD_FAB2(SCH_1):PAGE81_I185@MSTR_SCONN.SCONN288_H44441004(CHIPS)':
 'VSS'<2>: CDS_PINID='VSS(2)';
NODE_NAME     J1G3 276
 '@BASEBOARD_FAB2_LIB.BASEBOARD_FAB2(SCH_1):PAGE81_I185@MSTR_SCONN.SCONN288_H44441004(CHIPS)':
 'VSS'<3>: CDS_PINID='VSS(3)';
NODE_NAME     J1G3 274
 '@BASEBOARD_FAB2_LIB.BASEBOARD_FAB2(SCH_1):PAGE81_I185@MSTR_SCONN.SCONN288_H44441004(CHIPS)':
 'VSS'<4>: CDS_PINID='VSS(4)';
NODE_NAME     J1G3 272
 '@BASEBOARD_FAB2_LIB.BASEBOARD_FAB2(SCH_1):PAGE81_I185@MSTR_SCONN.SCONN288_H44441004(CHIPS)':
 'VSS'<5>: CDS_PINID='VSS(5)';
NODE_NAME     J1G3 270
 '@BASEBOARD_FAB2_LIB.BASEBOARD_FAB2(SCH_1):PAGE81_I185@MSTR_SCONN.SCONN288_H44441004(CHIPS)':
 'VSS'<6>: CDS_PINID='VSS(6)';
NODE_NAME     J1G3 268
 '@BASEBOARD_FAB2_LIB.BASEBOARD_FAB2(SCH_1):PAGE81_I185@MSTR_SCONN.SCONN288_H44441004(CHIPS)':
 'VSS'<7>: CDS_PINID='VSS(7)';
NODE_NAME     J1G3 265
 '@BASEBOARD_FAB2_LIB.BASEBOARD_FAB2(SCH_1):PAGE81_I185@MSTR_SCONN.SCONN288_H44441004(CHIPS)':
 'VSS'<8>: CDS_PINID='VSS(8)';
NODE_NAME     J1G3 263
 '@BASEBOARD_FAB2_LIB.BASEBOARD_FAB2(SCH_1):PAGE81_I185@MSTR_SCONN.SCONN288_H44441004(CHIPS)':
 'VSS'<9>: CDS_PINID='VSS(9)';
NODE_NAME     J1G3 261
 '@BASEBOARD_FAB2_LIB.BASEBOARD_FAB2(SCH_1):PAGE81_I185@MSTR_SCONN.SCONN288_H44441004(CHIPS)':
 'VSS'<10>: CDS_PINID='VSS(10)';
NODE_NAME     J1G3 259
 '@BASEBOARD_FAB2_LIB.BASEBOARD_FAB2(SCH_1):PAGE81_I185@MSTR_SCONN.SCONN288_H44441004(CHIPS)':
 'VSS'<11>: CDS_PINID='VSS(11)';
NODE_NAME     J1G3 257
 '@BASEBOARD_FAB2_LIB.BASEBOARD_FAB2(SCH_1):PAGE81_I185@MSTR_SCONN.SCONN288_H44441004(CHIPS)':
 'VSS'<12>: CDS_PINID='VSS(12)';
NODE_NAME     J1G3 254
 '@BASEBOARD_FAB2_LIB.BASEBOARD_FAB2(SCH_1):PAGE81_I185@MSTR_SCONN.SCONN288_H44441004(CHIPS)':
 'VSS'<13>: CDS_PINID='VSS(13)';
NODE_NAME     J1G3 252
 '@BASEBOARD_FAB2_LIB.BASEBOARD_FAB2(SCH_1):PAGE81_I185@MSTR_SCONN.SCONN288_H44441004(CHIPS)':
 'VSS'<14>: CDS_PINID='VSS(14)';
NODE_NAME     J1G3 250
 '@BASEBOARD_FAB2_LIB.BASEBOARD_FAB2(SCH_1):PAGE81_I185@MSTR_SCONN.SCONN288_H44441004(CHIPS)':
 'VSS'<15>: CDS_PINID='VSS(15)';
NODE_NAME     J1G3 248
 '@BASEBOARD_FAB2_LIB.BASEBOARD_FAB2(SCH_1):PAGE81_I185@MSTR_SCONN.SCONN288_H44441004(CHIPS)':
 'VSS'<16>: CDS_PINID='VSS(16)';
NODE_NAME     J1G3 246
 '@BASEBOARD_FAB2_LIB.BASEBOARD_FAB2(SCH_1):PAGE81_I185@MSTR_SCONN.SCONN288_H44441004(CHIPS)':
 'VSS'<17>: CDS_PINID='VSS(17)';
NODE_NAME     J1G3 243
 '@BASEBOARD_FAB2_LIB.BASEBOARD_FAB2(SCH_1):PAGE81_I185@MSTR_SCONN.SCONN288_H44441004(CHIPS)':
 'VSS'<18>: CDS_PINID='VSS(18)';
NODE_NAME     J1G3 241
 '@BASEBOARD_FAB2_LIB.BASEBOARD_FAB2(SCH_1):PAGE81_I185@MSTR_SCONN.SCONN288_H44441004(CHIPS)':
 'VSS'<19>: CDS_PINID='VSS(19)';
NODE_NAME     J1G3 239
 '@BASEBOARD_FAB2_LIB.BASEBOARD_FAB2(SCH_1):PAGE81_I185@MSTR_SCONN.SCONN288_H44441004(CHIPS)':
 'VSS'<20>: CDS_PINID='VSS(20)';
NODE_NAME     J1G3 202
 '@BASEBOARD_FAB2_LIB.BASEBOARD_FAB2(SCH_1):PAGE81_I185@MSTR_SCONN.SCONN288_H44441004(CHIPS)':
 'VSS'<21>: CDS_PINID='VSS(21)';
NODE_NAME     J1G3 200
 '@BASEBOARD_FAB2_LIB.BASEBOARD_FAB2(SCH_1):PAGE81_I185@MSTR_SCONN.SCONN288_H44441004(CHIPS)':
 'VSS'<22>: CDS_PINID='VSS(22)';
NODE_NAME     J1G3 198
 '@BASEBOARD_FAB2_LIB.BASEBOARD_FAB2(SCH_1):PAGE81_I185@MSTR_SCONN.SCONN288_H44441004(CHIPS)':
 'VSS'<23>: CDS_PINID='VSS(23)';
NODE_NAME     J1G3 195
 '@BASEBOARD_FAB2_LIB.BASEBOARD_FAB2(SCH_1):PAGE81_I185@MSTR_SCONN.SCONN288_H44441004(CHIPS)':
 'VSS'<24>: CDS_PINID='VSS(24)';
NODE_NAME     J1G3 193
 '@BASEBOARD_FAB2_LIB.BASEBOARD_FAB2(SCH_1):PAGE81_I185@MSTR_SCONN.SCONN288_H44441004(CHIPS)':
 'VSS'<25>: CDS_PINID='VSS(25)';
NODE_NAME     J1G3 191
 '@BASEBOARD_FAB2_LIB.BASEBOARD_FAB2(SCH_1):PAGE81_I185@MSTR_SCONN.SCONN288_H44441004(CHIPS)':
 'VSS'<26>: CDS_PINID='VSS(26)';
NODE_NAME     J1G3 189
 '@BASEBOARD_FAB2_LIB.BASEBOARD_FAB2(SCH_1):PAGE81_I185@MSTR_SCONN.SCONN288_H44441004(CHIPS)':
 'VSS'<27>: CDS_PINID='VSS(27)';
NODE_NAME     J1G3 187
 '@BASEBOARD_FAB2_LIB.BASEBOARD_FAB2(SCH_1):PAGE81_I185@MSTR_SCONN.SCONN288_H44441004(CHIPS)':
 'VSS'<28>: CDS_PINID='VSS(28)';
NODE_NAME     J1G3 184
 '@BASEBOARD_FAB2_LIB.BASEBOARD_FAB2(SCH_1):PAGE81_I185@MSTR_SCONN.SCONN288_H44441004(CHIPS)':
 'VSS'<29>: CDS_PINID='VSS(29)';
NODE_NAME     J1G3 182
 '@BASEBOARD_FAB2_LIB.BASEBOARD_FAB2(SCH_1):PAGE81_I185@MSTR_SCONN.SCONN288_H44441004(CHIPS)':
 'VSS'<30>: CDS_PINID='VSS(30)';
NODE_NAME     J1G3 180
 '@BASEBOARD_FAB2_LIB.BASEBOARD_FAB2(SCH_1):PAGE81_I185@MSTR_SCONN.SCONN288_H44441004(CHIPS)':
 'VSS'<31>: CDS_PINID='VSS(31)';
NODE_NAME     J1G3 178
 '@BASEBOARD_FAB2_LIB.BASEBOARD_FAB2(SCH_1):PAGE81_I185@MSTR_SCONN.SCONN288_H44441004(CHIPS)':
 'VSS'<32>: CDS_PINID='VSS(32)';
NODE_NAME     J1G3 176
 '@BASEBOARD_FAB2_LIB.BASEBOARD_FAB2(SCH_1):PAGE81_I185@MSTR_SCONN.SCONN288_H44441004(CHIPS)':
 'VSS'<33>: CDS_PINID='VSS(33)';
NODE_NAME     J1G3 173
 '@BASEBOARD_FAB2_LIB.BASEBOARD_FAB2(SCH_1):PAGE81_I185@MSTR_SCONN.SCONN288_H44441004(CHIPS)':
 'VSS'<34>: CDS_PINID='VSS(34)';
NODE_NAME     J1G3 171
 '@BASEBOARD_FAB2_LIB.BASEBOARD_FAB2(SCH_1):PAGE81_I185@MSTR_SCONN.SCONN288_H44441004(CHIPS)':
 'VSS'<35>: CDS_PINID='VSS(35)';
NODE_NAME     J1G3 169
 '@BASEBOARD_FAB2_LIB.BASEBOARD_FAB2(SCH_1):PAGE81_I185@MSTR_SCONN.SCONN288_H44441004(CHIPS)':
 'VSS'<36>: CDS_PINID='VSS(36)';
NODE_NAME     J1G3 167
 '@BASEBOARD_FAB2_LIB.BASEBOARD_FAB2(SCH_1):PAGE81_I185@MSTR_SCONN.SCONN288_H44441004(CHIPS)':
 'VSS'<37>: CDS_PINID='VSS(37)';
NODE_NAME     J1G3 165
 '@BASEBOARD_FAB2_LIB.BASEBOARD_FAB2(SCH_1):PAGE81_I185@MSTR_SCONN.SCONN288_H44441004(CHIPS)':
 'VSS'<38>: CDS_PINID='VSS(38)';
NODE_NAME     J1G3 162
 '@BASEBOARD_FAB2_LIB.BASEBOARD_FAB2(SCH_1):PAGE81_I185@MSTR_SCONN.SCONN288_H44441004(CHIPS)':
 'VSS'<39>: CDS_PINID='VSS(39)';
NODE_NAME     J1G3 160
 '@BASEBOARD_FAB2_LIB.BASEBOARD_FAB2(SCH_1):PAGE81_I185@MSTR_SCONN.SCONN288_H44441004(CHIPS)':
 'VSS'<40>: CDS_PINID='VSS(40)';
NODE_NAME     J1G3 158
 '@BASEBOARD_FAB2_LIB.BASEBOARD_FAB2(SCH_1):PAGE81_I185@MSTR_SCONN.SCONN288_H44441004(CHIPS)':
 'VSS'<41>: CDS_PINID='VSS(41)';
NODE_NAME     J1G3 156
 '@BASEBOARD_FAB2_LIB.BASEBOARD_FAB2(SCH_1):PAGE81_I185@MSTR_SCONN.SCONN288_H44441004(CHIPS)':
 'VSS'<42>: CDS_PINID='VSS(42)';
NODE_NAME     J1G3 154
 '@BASEBOARD_FAB2_LIB.BASEBOARD_FAB2(SCH_1):PAGE81_I185@MSTR_SCONN.SCONN288_H44441004(CHIPS)':
 'VSS'<43>: CDS_PINID='VSS(43)';
NODE_NAME     J1G3 151
 '@BASEBOARD_FAB2_LIB.BASEBOARD_FAB2(SCH_1):PAGE81_I185@MSTR_SCONN.SCONN288_H44441004(CHIPS)':
 'VSS'<44>: CDS_PINID='VSS(44)';
NODE_NAME     J1G3 149
 '@BASEBOARD_FAB2_LIB.BASEBOARD_FAB2(SCH_1):PAGE81_I185@MSTR_SCONN.SCONN288_H44441004(CHIPS)':
 'VSS'<45>: CDS_PINID='VSS(45)';
NODE_NAME     J1G3 147
 '@BASEBOARD_FAB2_LIB.BASEBOARD_FAB2(SCH_1):PAGE81_I185@MSTR_SCONN.SCONN288_H44441004(CHIPS)':
 'VSS'<46>: CDS_PINID='VSS(46)';
NODE_NAME     J1G3 138
 '@BASEBOARD_FAB2_LIB.BASEBOARD_FAB2(SCH_1):PAGE81_I185@MSTR_SCONN.SCONN288_H44441004(CHIPS)':
 'VSS'<47>: CDS_PINID='VSS(47)';
NODE_NAME     J1G3 136
 '@BASEBOARD_FAB2_LIB.BASEBOARD_FAB2(SCH_1):PAGE81_I185@MSTR_SCONN.SCONN288_H44441004(CHIPS)':
 'VSS'<48>: CDS_PINID='VSS(48)';
NODE_NAME     J1G3 134
 '@BASEBOARD_FAB2_LIB.BASEBOARD_FAB2(SCH_1):PAGE81_I185@MSTR_SCONN.SCONN288_H44441004(CHIPS)':
 'VSS'<49>: CDS_PINID='VSS(49)';
NODE_NAME     J1G3 131
 '@BASEBOARD_FAB2_LIB.BASEBOARD_FAB2(SCH_1):PAGE81_I185@MSTR_SCONN.SCONN288_H44441004(CHIPS)':
 'VSS'<50>: CDS_PINID='VSS(50)';
NODE_NAME     J1G3 129
 '@BASEBOARD_FAB2_LIB.BASEBOARD_FAB2(SCH_1):PAGE81_I185@MSTR_SCONN.SCONN288_H44441004(CHIPS)':
 'VSS'<51>: CDS_PINID='VSS(51)';
NODE_NAME     J1G3 127
 '@BASEBOARD_FAB2_LIB.BASEBOARD_FAB2(SCH_1):PAGE81_I185@MSTR_SCONN.SCONN288_H44441004(CHIPS)':
 'VSS'<52>: CDS_PINID='VSS(52)';
NODE_NAME     J1G3 125
 '@BASEBOARD_FAB2_LIB.BASEBOARD_FAB2(SCH_1):PAGE81_I185@MSTR_SCONN.SCONN288_H44441004(CHIPS)':
 'VSS'<53>: CDS_PINID='VSS(53)';
NODE_NAME     J1G3 123
 '@BASEBOARD_FAB2_LIB.BASEBOARD_FAB2(SCH_1):PAGE81_I185@MSTR_SCONN.SCONN288_H44441004(CHIPS)':
 'VSS'<54>: CDS_PINID='VSS(54)';
NODE_NAME     J1G3 120
 '@BASEBOARD_FAB2_LIB.BASEBOARD_FAB2(SCH_1):PAGE81_I185@MSTR_SCONN.SCONN288_H44441004(CHIPS)':
 'VSS'<55>: CDS_PINID='VSS(55)';
NODE_NAME     J1G3 118
 '@BASEBOARD_FAB2_LIB.BASEBOARD_FAB2(SCH_1):PAGE81_I185@MSTR_SCONN.SCONN288_H44441004(CHIPS)':
 'VSS'<56>: CDS_PINID='VSS(56)';
NODE_NAME     J1G3 116
 '@BASEBOARD_FAB2_LIB.BASEBOARD_FAB2(SCH_1):PAGE81_I185@MSTR_SCONN.SCONN288_H44441004(CHIPS)':
 'VSS'<57>: CDS_PINID='VSS(57)';
NODE_NAME     J1G3 114
 '@BASEBOARD_FAB2_LIB.BASEBOARD_FAB2(SCH_1):PAGE81_I185@MSTR_SCONN.SCONN288_H44441004(CHIPS)':
 'VSS'<58>: CDS_PINID='VSS(58)';
NODE_NAME     J1G3 112
 '@BASEBOARD_FAB2_LIB.BASEBOARD_FAB2(SCH_1):PAGE81_I185@MSTR_SCONN.SCONN288_H44441004(CHIPS)':
 'VSS'<59>: CDS_PINID='VSS(59)';
NODE_NAME     J1G3 109
 '@BASEBOARD_FAB2_LIB.BASEBOARD_FAB2(SCH_1):PAGE81_I185@MSTR_SCONN.SCONN288_H44441004(CHIPS)':
 'VSS'<60>: CDS_PINID='VSS(60)';
NODE_NAME     J1G3 107
 '@BASEBOARD_FAB2_LIB.BASEBOARD_FAB2(SCH_1):PAGE81_I185@MSTR_SCONN.SCONN288_H44441004(CHIPS)':
 'VSS'<61>: CDS_PINID='VSS(61)';
NODE_NAME     J1G3 105
 '@BASEBOARD_FAB2_LIB.BASEBOARD_FAB2(SCH_1):PAGE81_I185@MSTR_SCONN.SCONN288_H44441004(CHIPS)':
 'VSS'<62>: CDS_PINID='VSS(62)';
NODE_NAME     J1G3 103
 '@BASEBOARD_FAB2_LIB.BASEBOARD_FAB2(SCH_1):PAGE81_I185@MSTR_SCONN.SCONN288_H44441004(CHIPS)':
 'VSS'<63>: CDS_PINID='VSS(63)';
NODE_NAME     J1G3 101
 '@BASEBOARD_FAB2_LIB.BASEBOARD_FAB2(SCH_1):PAGE81_I185@MSTR_SCONN.SCONN288_H44441004(CHIPS)':
 'VSS'<64>: CDS_PINID='VSS(64)';
NODE_NAME     J1G3 98
 '@BASEBOARD_FAB2_LIB.BASEBOARD_FAB2(SCH_1):PAGE81_I185@MSTR_SCONN.SCONN288_H44441004(CHIPS)':
 'VSS'<65>: CDS_PINID='VSS(65)';
NODE_NAME     J1G3 96
 '@BASEBOARD_FAB2_LIB.BASEBOARD_FAB2(SCH_1):PAGE81_I185@MSTR_SCONN.SCONN288_H44441004(CHIPS)':
 'VSS'<66>: CDS_PINID='VSS(66)';
NODE_NAME     J1G3 94
 '@BASEBOARD_FAB2_LIB.BASEBOARD_FAB2(SCH_1):PAGE81_I185@MSTR_SCONN.SCONN288_H44441004(CHIPS)':
 'VSS'<67>: CDS_PINID='VSS(67)';
NODE_NAME     J1G3 57
 '@BASEBOARD_FAB2_LIB.BASEBOARD_FAB2(SCH_1):PAGE81_I185@MSTR_SCONN.SCONN288_H44441004(CHIPS)':
 'VSS'<68>: CDS_PINID='VSS(68)';
NODE_NAME     J1G3 55
 '@BASEBOARD_FAB2_LIB.BASEBOARD_FAB2(SCH_1):PAGE81_I185@MSTR_SCONN.SCONN288_H44441004(CHIPS)':
 'VSS'<69>: CDS_PINID='VSS(69)';
NODE_NAME     J1G3 53
 '@BASEBOARD_FAB2_LIB.BASEBOARD_FAB2(SCH_1):PAGE81_I185@MSTR_SCONN.SCONN288_H44441004(CHIPS)':
 'VSS'<70>: CDS_PINID='VSS(70)';
NODE_NAME     J1G3 50
 '@BASEBOARD_FAB2_LIB.BASEBOARD_FAB2(SCH_1):PAGE81_I185@MSTR_SCONN.SCONN288_H44441004(CHIPS)':
 'VSS'<71>: CDS_PINID='VSS(71)';
NODE_NAME     J1G3 48
 '@BASEBOARD_FAB2_LIB.BASEBOARD_FAB2(SCH_1):PAGE81_I185@MSTR_SCONN.SCONN288_H44441004(CHIPS)':
 'VSS'<72>: CDS_PINID='VSS(72)';
NODE_NAME     J1G3 46
 '@BASEBOARD_FAB2_LIB.BASEBOARD_FAB2(SCH_1):PAGE81_I185@MSTR_SCONN.SCONN288_H44441004(CHIPS)':
 'VSS'<73>: CDS_PINID='VSS(73)';
NODE_NAME     J1G3 44
 '@BASEBOARD_FAB2_LIB.BASEBOARD_FAB2(SCH_1):PAGE81_I185@MSTR_SCONN.SCONN288_H44441004(CHIPS)':
 'VSS'<74>: CDS_PINID='VSS(74)';
NODE_NAME     J1G3 42
 '@BASEBOARD_FAB2_LIB.BASEBOARD_FAB2(SCH_1):PAGE81_I185@MSTR_SCONN.SCONN288_H44441004(CHIPS)':
 'VSS'<75>: CDS_PINID='VSS(75)';
NODE_NAME     J1G3 39
 '@BASEBOARD_FAB2_LIB.BASEBOARD_FAB2(SCH_1):PAGE81_I185@MSTR_SCONN.SCONN288_H44441004(CHIPS)':
 'VSS'<76>: CDS_PINID='VSS(76)';
NODE_NAME     J1G3 37
 '@BASEBOARD_FAB2_LIB.BASEBOARD_FAB2(SCH_1):PAGE81_I185@MSTR_SCONN.SCONN288_H44441004(CHIPS)':
 'VSS'<77>: CDS_PINID='VSS(77)';
NODE_NAME     J1G3 35
 '@BASEBOARD_FAB2_LIB.BASEBOARD_FAB2(SCH_1):PAGE81_I185@MSTR_SCONN.SCONN288_H44441004(CHIPS)':
 'VSS'<78>: CDS_PINID='VSS(78)';
NODE_NAME     J1G3 33
 '@BASEBOARD_FAB2_LIB.BASEBOARD_FAB2(SCH_1):PAGE81_I185@MSTR_SCONN.SCONN288_H44441004(CHIPS)':
 'VSS'<79>: CDS_PINID='VSS(79)';
NODE_NAME     J1G3 31
 '@BASEBOARD_FAB2_LIB.BASEBOARD_FAB2(SCH_1):PAGE81_I185@MSTR_SCONN.SCONN288_H44441004(CHIPS)':
 'VSS'<80>: CDS_PINID='VSS(80)';
NODE_NAME     J1G3 28
 '@BASEBOARD_FAB2_LIB.BASEBOARD_FAB2(SCH_1):PAGE81_I185@MSTR_SCONN.SCONN288_H44441004(CHIPS)':
 'VSS'<81>: CDS_PINID='VSS(81)';
NODE_NAME     J1G3 26
 '@BASEBOARD_FAB2_LIB.BASEBOARD_FAB2(SCH_1):PAGE81_I185@MSTR_SCONN.SCONN288_H44441004(CHIPS)':
 'VSS'<82>: CDS_PINID='VSS(82)';
NODE_NAME     J1G3 24
 '@BASEBOARD_FAB2_LIB.BASEBOARD_FAB2(SCH_1):PAGE81_I185@MSTR_SCONN.SCONN288_H44441004(CHIPS)':
 'VSS'<83>: CDS_PINID='VSS(83)';
NODE_NAME     J1G3 22
 '@BASEBOARD_FAB2_LIB.BASEBOARD_FAB2(SCH_1):PAGE81_I185@MSTR_SCONN.SCONN288_H44441004(CHIPS)':
 'VSS'<84>: CDS_PINID='VSS(84)';
NODE_NAME     J1G3 20
 '@BASEBOARD_FAB2_LIB.BASEBOARD_FAB2(SCH_1):PAGE81_I185@MSTR_SCONN.SCONN288_H44441004(CHIPS)':
 'VSS'<85>: CDS_PINID='VSS(85)';
NODE_NAME     J1G3 17
 '@BASEBOARD_FAB2_LIB.BASEBOARD_FAB2(SCH_1):PAGE81_I185@MSTR_SCONN.SCONN288_H44441004(CHIPS)':
 'VSS'<86>: CDS_PINID='VSS(86)';
NODE_NAME     J1G3 15
 '@BASEBOARD_FAB2_LIB.BASEBOARD_FAB2(SCH_1):PAGE81_I185@MSTR_SCONN.SCONN288_H44441004(CHIPS)':
 'VSS'<87>: CDS_PINID='VSS(87)';
NODE_NAME     J1G3 13
 '@BASEBOARD_FAB2_LIB.BASEBOARD_FAB2(SCH_1):PAGE81_I185@MSTR_SCONN.SCONN288_H44441004(CHIPS)':
 'VSS'<88>: CDS_PINID='VSS(88)';
NODE_NAME     J1G3 11
 '@BASEBOARD_FAB2_LIB.BASEBOARD_FAB2(SCH_1):PAGE81_I185@MSTR_SCONN.SCONN288_H44441004(CHIPS)':
 'VSS'<89>: CDS_PINID='VSS(89)';
NODE_NAME     J1G3 9
 '@BASEBOARD_FAB2_LIB.BASEBOARD_FAB2(SCH_1):PAGE81_I185@MSTR_SCONN.SCONN288_H44441004(CHIPS)':
 'VSS'<90>: CDS_PINID='VSS(90)';
NODE_NAME     J1G3 6
 '@BASEBOARD_FAB2_LIB.BASEBOARD_FAB2(SCH_1):PAGE81_I185@MSTR_SCONN.SCONN288_H44441004(CHIPS)':
 'VSS'<91>: CDS_PINID='VSS(91)';
NODE_NAME     J1G3 4
 '@BASEBOARD_FAB2_LIB.BASEBOARD_FAB2(SCH_1):PAGE81_I185@MSTR_SCONN.SCONN288_H44441004(CHIPS)':
 'VSS'<92>: CDS_PINID='VSS(92)';
NODE_NAME     J1G3 2
 '@BASEBOARD_FAB2_LIB.BASEBOARD_FAB2(SCH_1):PAGE81_I185@MSTR_SCONN.SCONN288_H44441004(CHIPS)':
 'VSS'<93>: CDS_PINID='VSS(93)';
NODE_NAME     J1G3 139
 '@BASEBOARD_FAB2_LIB.BASEBOARD_FAB2(SCH_1):PAGE81_I186@MSTR_SCONN.SCONN288_H44441004(CHIPS)':
 'SA'<0>: CDS_PINID='SA(0)';
NODE_NAME     J1G3 140
 '@BASEBOARD_FAB2_LIB.BASEBOARD_FAB2(SCH_1):PAGE81_I186@MSTR_SCONN.SCONN288_H44441004(CHIPS)':
 'SA'<1>: CDS_PINID='SA(1)';
NODE_NAME     C1G19 2
 '@BASEBOARD_FAB2_LIB.BASEBOARD_FAB2(SCH_1):PAGE82_I180@DEV_DISCRETE.CAP_A(CHIPS)':
 'B': CDS_PINID='B';
NODE_NAME     J9U2 140
 '@BASEBOARD_FAB2_LIB.BASEBOARD_FAB2(SCH_1):PAGE82_I187@MSTR_SCONN.SCONN288_H44441003(CHIPS)':
 'SA'<1>: CDS_PINID='SA(1)';
NODE_NAME     J9U2 283
 '@BASEBOARD_FAB2_LIB.BASEBOARD_FAB2(SCH_1):PAGE82_I188@MSTR_SCONN.SCONN288_H44441003(CHIPS)':
 'VSS'<0>: CDS_PINID='VSS(0)';
NODE_NAME     J9U2 281
 '@BASEBOARD_FAB2_LIB.BASEBOARD_FAB2(SCH_1):PAGE82_I188@MSTR_SCONN.SCONN288_H44441003(CHIPS)':
 'VSS'<1>: CDS_PINID='VSS(1)';
NODE_NAME     J9U2 279
 '@BASEBOARD_FAB2_LIB.BASEBOARD_FAB2(SCH_1):PAGE82_I188@MSTR_SCONN.SCONN288_H44441003(CHIPS)':
 'VSS'<2>: CDS_PINID='VSS(2)';
NODE_NAME     J9U2 276
 '@BASEBOARD_FAB2_LIB.BASEBOARD_FAB2(SCH_1):PAGE82_I188@MSTR_SCONN.SCONN288_H44441003(CHIPS)':
 'VSS'<3>: CDS_PINID='VSS(3)';
NODE_NAME     J9U2 274
 '@BASEBOARD_FAB2_LIB.BASEBOARD_FAB2(SCH_1):PAGE82_I188@MSTR_SCONN.SCONN288_H44441003(CHIPS)':
 'VSS'<4>: CDS_PINID='VSS(4)';
NODE_NAME     J9U2 272
 '@BASEBOARD_FAB2_LIB.BASEBOARD_FAB2(SCH_1):PAGE82_I188@MSTR_SCONN.SCONN288_H44441003(CHIPS)':
 'VSS'<5>: CDS_PINID='VSS(5)';
NODE_NAME     J9U2 270
 '@BASEBOARD_FAB2_LIB.BASEBOARD_FAB2(SCH_1):PAGE82_I188@MSTR_SCONN.SCONN288_H44441003(CHIPS)':
 'VSS'<6>: CDS_PINID='VSS(6)';
NODE_NAME     J9U2 268
 '@BASEBOARD_FAB2_LIB.BASEBOARD_FAB2(SCH_1):PAGE82_I188@MSTR_SCONN.SCONN288_H44441003(CHIPS)':
 'VSS'<7>: CDS_PINID='VSS(7)';
NODE_NAME     J9U2 265
 '@BASEBOARD_FAB2_LIB.BASEBOARD_FAB2(SCH_1):PAGE82_I188@MSTR_SCONN.SCONN288_H44441003(CHIPS)':
 'VSS'<8>: CDS_PINID='VSS(8)';
NODE_NAME     J9U2 263
 '@BASEBOARD_FAB2_LIB.BASEBOARD_FAB2(SCH_1):PAGE82_I188@MSTR_SCONN.SCONN288_H44441003(CHIPS)':
 'VSS'<9>: CDS_PINID='VSS(9)';
NODE_NAME     J9U2 261
 '@BASEBOARD_FAB2_LIB.BASEBOARD_FAB2(SCH_1):PAGE82_I188@MSTR_SCONN.SCONN288_H44441003(CHIPS)':
 'VSS'<10>: CDS_PINID='VSS(10)';
NODE_NAME     J9U2 259
 '@BASEBOARD_FAB2_LIB.BASEBOARD_FAB2(SCH_1):PAGE82_I188@MSTR_SCONN.SCONN288_H44441003(CHIPS)':
 'VSS'<11>: CDS_PINID='VSS(11)';
NODE_NAME     J9U2 257
 '@BASEBOARD_FAB2_LIB.BASEBOARD_FAB2(SCH_1):PAGE82_I188@MSTR_SCONN.SCONN288_H44441003(CHIPS)':
 'VSS'<12>: CDS_PINID='VSS(12)';
NODE_NAME     J9U2 254
 '@BASEBOARD_FAB2_LIB.BASEBOARD_FAB2(SCH_1):PAGE82_I188@MSTR_SCONN.SCONN288_H44441003(CHIPS)':
 'VSS'<13>: CDS_PINID='VSS(13)';
NODE_NAME     J9U2 252
 '@BASEBOARD_FAB2_LIB.BASEBOARD_FAB2(SCH_1):PAGE82_I188@MSTR_SCONN.SCONN288_H44441003(CHIPS)':
 'VSS'<14>: CDS_PINID='VSS(14)';
NODE_NAME     J9U2 250
 '@BASEBOARD_FAB2_LIB.BASEBOARD_FAB2(SCH_1):PAGE82_I188@MSTR_SCONN.SCONN288_H44441003(CHIPS)':
 'VSS'<15>: CDS_PINID='VSS(15)';
NODE_NAME     J9U2 248
 '@BASEBOARD_FAB2_LIB.BASEBOARD_FAB2(SCH_1):PAGE82_I188@MSTR_SCONN.SCONN288_H44441003(CHIPS)':
 'VSS'<16>: CDS_PINID='VSS(16)';
NODE_NAME     J9U2 246
 '@BASEBOARD_FAB2_LIB.BASEBOARD_FAB2(SCH_1):PAGE82_I188@MSTR_SCONN.SCONN288_H44441003(CHIPS)':
 'VSS'<17>: CDS_PINID='VSS(17)';
NODE_NAME     J9U2 243
 '@BASEBOARD_FAB2_LIB.BASEBOARD_FAB2(SCH_1):PAGE82_I188@MSTR_SCONN.SCONN288_H44441003(CHIPS)':
 'VSS'<18>: CDS_PINID='VSS(18)';
NODE_NAME     J9U2 241
 '@BASEBOARD_FAB2_LIB.BASEBOARD_FAB2(SCH_1):PAGE82_I188@MSTR_SCONN.SCONN288_H44441003(CHIPS)':
 'VSS'<19>: CDS_PINID='VSS(19)';
NODE_NAME     J9U2 239
 '@BASEBOARD_FAB2_LIB.BASEBOARD_FAB2(SCH_1):PAGE82_I188@MSTR_SCONN.SCONN288_H44441003(CHIPS)':
 'VSS'<20>: CDS_PINID='VSS(20)';
NODE_NAME     J9U2 202
 '@BASEBOARD_FAB2_LIB.BASEBOARD_FAB2(SCH_1):PAGE82_I188@MSTR_SCONN.SCONN288_H44441003(CHIPS)':
 'VSS'<21>: CDS_PINID='VSS(21)';
NODE_NAME     J9U2 200
 '@BASEBOARD_FAB2_LIB.BASEBOARD_FAB2(SCH_1):PAGE82_I188@MSTR_SCONN.SCONN288_H44441003(CHIPS)':
 'VSS'<22>: CDS_PINID='VSS(22)';
NODE_NAME     J9U2 198
 '@BASEBOARD_FAB2_LIB.BASEBOARD_FAB2(SCH_1):PAGE82_I188@MSTR_SCONN.SCONN288_H44441003(CHIPS)':
 'VSS'<23>: CDS_PINID='VSS(23)';
NODE_NAME     J9U2 195
 '@BASEBOARD_FAB2_LIB.BASEBOARD_FAB2(SCH_1):PAGE82_I188@MSTR_SCONN.SCONN288_H44441003(CHIPS)':
 'VSS'<24>: CDS_PINID='VSS(24)';
NODE_NAME     J9U2 193
 '@BASEBOARD_FAB2_LIB.BASEBOARD_FAB2(SCH_1):PAGE82_I188@MSTR_SCONN.SCONN288_H44441003(CHIPS)':
 'VSS'<25>: CDS_PINID='VSS(25)';
NODE_NAME     J9U2 191
 '@BASEBOARD_FAB2_LIB.BASEBOARD_FAB2(SCH_1):PAGE82_I188@MSTR_SCONN.SCONN288_H44441003(CHIPS)':
 'VSS'<26>: CDS_PINID='VSS(26)';
NODE_NAME     J9U2 189
 '@BASEBOARD_FAB2_LIB.BASEBOARD_FAB2(SCH_1):PAGE82_I188@MSTR_SCONN.SCONN288_H44441003(CHIPS)':
 'VSS'<27>: CDS_PINID='VSS(27)';
NODE_NAME     J9U2 187
 '@BASEBOARD_FAB2_LIB.BASEBOARD_FAB2(SCH_1):PAGE82_I188@MSTR_SCONN.SCONN288_H44441003(CHIPS)':
 'VSS'<28>: CDS_PINID='VSS(28)';
NODE_NAME     J9U2 184
 '@BASEBOARD_FAB2_LIB.BASEBOARD_FAB2(SCH_1):PAGE82_I188@MSTR_SCONN.SCONN288_H44441003(CHIPS)':
 'VSS'<29>: CDS_PINID='VSS(29)';
NODE_NAME     J9U2 182
 '@BASEBOARD_FAB2_LIB.BASEBOARD_FAB2(SCH_1):PAGE82_I188@MSTR_SCONN.SCONN288_H44441003(CHIPS)':
 'VSS'<30>: CDS_PINID='VSS(30)';
NODE_NAME     J9U2 180
 '@BASEBOARD_FAB2_LIB.BASEBOARD_FAB2(SCH_1):PAGE82_I188@MSTR_SCONN.SCONN288_H44441003(CHIPS)':
 'VSS'<31>: CDS_PINID='VSS(31)';
NODE_NAME     J9U2 178
 '@BASEBOARD_FAB2_LIB.BASEBOARD_FAB2(SCH_1):PAGE82_I188@MSTR_SCONN.SCONN288_H44441003(CHIPS)':
 'VSS'<32>: CDS_PINID='VSS(32)';
NODE_NAME     J9U2 176
 '@BASEBOARD_FAB2_LIB.BASEBOARD_FAB2(SCH_1):PAGE82_I188@MSTR_SCONN.SCONN288_H44441003(CHIPS)':
 'VSS'<33>: CDS_PINID='VSS(33)';
NODE_NAME     J9U2 173
 '@BASEBOARD_FAB2_LIB.BASEBOARD_FAB2(SCH_1):PAGE82_I188@MSTR_SCONN.SCONN288_H44441003(CHIPS)':
 'VSS'<34>: CDS_PINID='VSS(34)';
NODE_NAME     J9U2 171
 '@BASEBOARD_FAB2_LIB.BASEBOARD_FAB2(SCH_1):PAGE82_I188@MSTR_SCONN.SCONN288_H44441003(CHIPS)':
 'VSS'<35>: CDS_PINID='VSS(35)';
NODE_NAME     J9U2 169
 '@BASEBOARD_FAB2_LIB.BASEBOARD_FAB2(SCH_1):PAGE82_I188@MSTR_SCONN.SCONN288_H44441003(CHIPS)':
 'VSS'<36>: CDS_PINID='VSS(36)';
NODE_NAME     J9U2 167
 '@BASEBOARD_FAB2_LIB.BASEBOARD_FAB2(SCH_1):PAGE82_I188@MSTR_SCONN.SCONN288_H44441003(CHIPS)':
 'VSS'<37>: CDS_PINID='VSS(37)';
NODE_NAME     J9U2 165
 '@BASEBOARD_FAB2_LIB.BASEBOARD_FAB2(SCH_1):PAGE82_I188@MSTR_SCONN.SCONN288_H44441003(CHIPS)':
 'VSS'<38>: CDS_PINID='VSS(38)';
NODE_NAME     J9U2 162
 '@BASEBOARD_FAB2_LIB.BASEBOARD_FAB2(SCH_1):PAGE82_I188@MSTR_SCONN.SCONN288_H44441003(CHIPS)':
 'VSS'<39>: CDS_PINID='VSS(39)';
NODE_NAME     J9U2 160
 '@BASEBOARD_FAB2_LIB.BASEBOARD_FAB2(SCH_1):PAGE82_I188@MSTR_SCONN.SCONN288_H44441003(CHIPS)':
 'VSS'<40>: CDS_PINID='VSS(40)';
NODE_NAME     J9U2 158
 '@BASEBOARD_FAB2_LIB.BASEBOARD_FAB2(SCH_1):PAGE82_I188@MSTR_SCONN.SCONN288_H44441003(CHIPS)':
 'VSS'<41>: CDS_PINID='VSS(41)';
NODE_NAME     J9U2 156
 '@BASEBOARD_FAB2_LIB.BASEBOARD_FAB2(SCH_1):PAGE82_I188@MSTR_SCONN.SCONN288_H44441003(CHIPS)':
 'VSS'<42>: CDS_PINID='VSS(42)';
NODE_NAME     J9U2 154
 '@BASEBOARD_FAB2_LIB.BASEBOARD_FAB2(SCH_1):PAGE82_I188@MSTR_SCONN.SCONN288_H44441003(CHIPS)':
 'VSS'<43>: CDS_PINID='VSS(43)';
NODE_NAME     J9U2 151
 '@BASEBOARD_FAB2_LIB.BASEBOARD_FAB2(SCH_1):PAGE82_I188@MSTR_SCONN.SCONN288_H44441003(CHIPS)':
 'VSS'<44>: CDS_PINID='VSS(44)';
NODE_NAME     J9U2 149
 '@BASEBOARD_FAB2_LIB.BASEBOARD_FAB2(SCH_1):PAGE82_I188@MSTR_SCONN.SCONN288_H44441003(CHIPS)':
 'VSS'<45>: CDS_PINID='VSS(45)';
NODE_NAME     J9U2 147
 '@BASEBOARD_FAB2_LIB.BASEBOARD_FAB2(SCH_1):PAGE82_I188@MSTR_SCONN.SCONN288_H44441003(CHIPS)':
 'VSS'<46>: CDS_PINID='VSS(46)';
NODE_NAME     J9U2 138
 '@BASEBOARD_FAB2_LIB.BASEBOARD_FAB2(SCH_1):PAGE82_I188@MSTR_SCONN.SCONN288_H44441003(CHIPS)':
 'VSS'<47>: CDS_PINID='VSS(47)';
NODE_NAME     J9U2 136
 '@BASEBOARD_FAB2_LIB.BASEBOARD_FAB2(SCH_1):PAGE82_I188@MSTR_SCONN.SCONN288_H44441003(CHIPS)':
 'VSS'<48>: CDS_PINID='VSS(48)';
NODE_NAME     J9U2 134
 '@BASEBOARD_FAB2_LIB.BASEBOARD_FAB2(SCH_1):PAGE82_I188@MSTR_SCONN.SCONN288_H44441003(CHIPS)':
 'VSS'<49>: CDS_PINID='VSS(49)';
NODE_NAME     J9U2 131
 '@BASEBOARD_FAB2_LIB.BASEBOARD_FAB2(SCH_1):PAGE82_I188@MSTR_SCONN.SCONN288_H44441003(CHIPS)':
 'VSS'<50>: CDS_PINID='VSS(50)';
NODE_NAME     J9U2 129
 '@BASEBOARD_FAB2_LIB.BASEBOARD_FAB2(SCH_1):PAGE82_I188@MSTR_SCONN.SCONN288_H44441003(CHIPS)':
 'VSS'<51>: CDS_PINID='VSS(51)';
NODE_NAME     J9U2 127
 '@BASEBOARD_FAB2_LIB.BASEBOARD_FAB2(SCH_1):PAGE82_I188@MSTR_SCONN.SCONN288_H44441003(CHIPS)':
 'VSS'<52>: CDS_PINID='VSS(52)';
NODE_NAME     J9U2 125
 '@BASEBOARD_FAB2_LIB.BASEBOARD_FAB2(SCH_1):PAGE82_I188@MSTR_SCONN.SCONN288_H44441003(CHIPS)':
 'VSS'<53>: CDS_PINID='VSS(53)';
NODE_NAME     J9U2 123
 '@BASEBOARD_FAB2_LIB.BASEBOARD_FAB2(SCH_1):PAGE82_I188@MSTR_SCONN.SCONN288_H44441003(CHIPS)':
 'VSS'<54>: CDS_PINID='VSS(54)';
NODE_NAME     J9U2 120
 '@BASEBOARD_FAB2_LIB.BASEBOARD_FAB2(SCH_1):PAGE82_I188@MSTR_SCONN.SCONN288_H44441003(CHIPS)':
 'VSS'<55>: CDS_PINID='VSS(55)';
NODE_NAME     J9U2 118
 '@BASEBOARD_FAB2_LIB.BASEBOARD_FAB2(SCH_1):PAGE82_I188@MSTR_SCONN.SCONN288_H44441003(CHIPS)':
 'VSS'<56>: CDS_PINID='VSS(56)';
NODE_NAME     J9U2 116
 '@BASEBOARD_FAB2_LIB.BASEBOARD_FAB2(SCH_1):PAGE82_I188@MSTR_SCONN.SCONN288_H44441003(CHIPS)':
 'VSS'<57>: CDS_PINID='VSS(57)';
NODE_NAME     J9U2 114
 '@BASEBOARD_FAB2_LIB.BASEBOARD_FAB2(SCH_1):PAGE82_I188@MSTR_SCONN.SCONN288_H44441003(CHIPS)':
 'VSS'<58>: CDS_PINID='VSS(58)';
NODE_NAME     J9U2 112
 '@BASEBOARD_FAB2_LIB.BASEBOARD_FAB2(SCH_1):PAGE82_I188@MSTR_SCONN.SCONN288_H44441003(CHIPS)':
 'VSS'<59>: CDS_PINID='VSS(59)';
NODE_NAME     J9U2 109
 '@BASEBOARD_FAB2_LIB.BASEBOARD_FAB2(SCH_1):PAGE82_I188@MSTR_SCONN.SCONN288_H44441003(CHIPS)':
 'VSS'<60>: CDS_PINID='VSS(60)';
NODE_NAME     J9U2 107
 '@BASEBOARD_FAB2_LIB.BASEBOARD_FAB2(SCH_1):PAGE82_I188@MSTR_SCONN.SCONN288_H44441003(CHIPS)':
 'VSS'<61>: CDS_PINID='VSS(61)';
NODE_NAME     J9U2 105
 '@BASEBOARD_FAB2_LIB.BASEBOARD_FAB2(SCH_1):PAGE82_I188@MSTR_SCONN.SCONN288_H44441003(CHIPS)':
 'VSS'<62>: CDS_PINID='VSS(62)';
NODE_NAME     J9U2 103
 '@BASEBOARD_FAB2_LIB.BASEBOARD_FAB2(SCH_1):PAGE82_I188@MSTR_SCONN.SCONN288_H44441003(CHIPS)':
 'VSS'<63>: CDS_PINID='VSS(63)';
NODE_NAME     J9U2 101
 '@BASEBOARD_FAB2_LIB.BASEBOARD_FAB2(SCH_1):PAGE82_I188@MSTR_SCONN.SCONN288_H44441003(CHIPS)':
 'VSS'<64>: CDS_PINID='VSS(64)';
NODE_NAME     J9U2 98
 '@BASEBOARD_FAB2_LIB.BASEBOARD_FAB2(SCH_1):PAGE82_I188@MSTR_SCONN.SCONN288_H44441003(CHIPS)':
 'VSS'<65>: CDS_PINID='VSS(65)';
NODE_NAME     J9U2 96
 '@BASEBOARD_FAB2_LIB.BASEBOARD_FAB2(SCH_1):PAGE82_I188@MSTR_SCONN.SCONN288_H44441003(CHIPS)':
 'VSS'<66>: CDS_PINID='VSS(66)';
NODE_NAME     J9U2 94
 '@BASEBOARD_FAB2_LIB.BASEBOARD_FAB2(SCH_1):PAGE82_I188@MSTR_SCONN.SCONN288_H44441003(CHIPS)':
 'VSS'<67>: CDS_PINID='VSS(67)';
NODE_NAME     J9U2 57
 '@BASEBOARD_FAB2_LIB.BASEBOARD_FAB2(SCH_1):PAGE82_I188@MSTR_SCONN.SCONN288_H44441003(CHIPS)':
 'VSS'<68>: CDS_PINID='VSS(68)';
NODE_NAME     J9U2 55
 '@BASEBOARD_FAB2_LIB.BASEBOARD_FAB2(SCH_1):PAGE82_I188@MSTR_SCONN.SCONN288_H44441003(CHIPS)':
 'VSS'<69>: CDS_PINID='VSS(69)';
NODE_NAME     J9U2 53
 '@BASEBOARD_FAB2_LIB.BASEBOARD_FAB2(SCH_1):PAGE82_I188@MSTR_SCONN.SCONN288_H44441003(CHIPS)':
 'VSS'<70>: CDS_PINID='VSS(70)';
NODE_NAME     J9U2 50
 '@BASEBOARD_FAB2_LIB.BASEBOARD_FAB2(SCH_1):PAGE82_I188@MSTR_SCONN.SCONN288_H44441003(CHIPS)':
 'VSS'<71>: CDS_PINID='VSS(71)';
NODE_NAME     J9U2 48
 '@BASEBOARD_FAB2_LIB.BASEBOARD_FAB2(SCH_1):PAGE82_I188@MSTR_SCONN.SCONN288_H44441003(CHIPS)':
 'VSS'<72>: CDS_PINID='VSS(72)';
NODE_NAME     J9U2 46
 '@BASEBOARD_FAB2_LIB.BASEBOARD_FAB2(SCH_1):PAGE82_I188@MSTR_SCONN.SCONN288_H44441003(CHIPS)':
 'VSS'<73>: CDS_PINID='VSS(73)';
NODE_NAME     J9U2 44
 '@BASEBOARD_FAB2_LIB.BASEBOARD_FAB2(SCH_1):PAGE82_I188@MSTR_SCONN.SCONN288_H44441003(CHIPS)':
 'VSS'<74>: CDS_PINID='VSS(74)';
NODE_NAME     J9U2 42
 '@BASEBOARD_FAB2_LIB.BASEBOARD_FAB2(SCH_1):PAGE82_I188@MSTR_SCONN.SCONN288_H44441003(CHIPS)':
 'VSS'<75>: CDS_PINID='VSS(75)';
NODE_NAME     J9U2 39
 '@BASEBOARD_FAB2_LIB.BASEBOARD_FAB2(SCH_1):PAGE82_I188@MSTR_SCONN.SCONN288_H44441003(CHIPS)':
 'VSS'<76>: CDS_PINID='VSS(76)';
NODE_NAME     J9U2 37
 '@BASEBOARD_FAB2_LIB.BASEBOARD_FAB2(SCH_1):PAGE82_I188@MSTR_SCONN.SCONN288_H44441003(CHIPS)':
 'VSS'<77>: CDS_PINID='VSS(77)';
NODE_NAME     J9U2 35
 '@BASEBOARD_FAB2_LIB.BASEBOARD_FAB2(SCH_1):PAGE82_I188@MSTR_SCONN.SCONN288_H44441003(CHIPS)':
 'VSS'<78>: CDS_PINID='VSS(78)';
NODE_NAME     J9U2 33
 '@BASEBOARD_FAB2_LIB.BASEBOARD_FAB2(SCH_1):PAGE82_I188@MSTR_SCONN.SCONN288_H44441003(CHIPS)':
 'VSS'<79>: CDS_PINID='VSS(79)';
NODE_NAME     J9U2 31
 '@BASEBOARD_FAB2_LIB.BASEBOARD_FAB2(SCH_1):PAGE82_I188@MSTR_SCONN.SCONN288_H44441003(CHIPS)':
 'VSS'<80>: CDS_PINID='VSS(80)';
NODE_NAME     J9U2 28
 '@BASEBOARD_FAB2_LIB.BASEBOARD_FAB2(SCH_1):PAGE82_I188@MSTR_SCONN.SCONN288_H44441003(CHIPS)':
 'VSS'<81>: CDS_PINID='VSS(81)';
NODE_NAME     J9U2 26
 '@BASEBOARD_FAB2_LIB.BASEBOARD_FAB2(SCH_1):PAGE82_I188@MSTR_SCONN.SCONN288_H44441003(CHIPS)':
 'VSS'<82>: CDS_PINID='VSS(82)';
NODE_NAME     J9U2 24
 '@BASEBOARD_FAB2_LIB.BASEBOARD_FAB2(SCH_1):PAGE82_I188@MSTR_SCONN.SCONN288_H44441003(CHIPS)':
 'VSS'<83>: CDS_PINID='VSS(83)';
NODE_NAME     J9U2 22
 '@BASEBOARD_FAB2_LIB.BASEBOARD_FAB2(SCH_1):PAGE82_I188@MSTR_SCONN.SCONN288_H44441003(CHIPS)':
 'VSS'<84>: CDS_PINID='VSS(84)';
NODE_NAME     J9U2 20
 '@BASEBOARD_FAB2_LIB.BASEBOARD_FAB2(SCH_1):PAGE82_I188@MSTR_SCONN.SCONN288_H44441003(CHIPS)':
 'VSS'<85>: CDS_PINID='VSS(85)';
NODE_NAME     J9U2 17
 '@BASEBOARD_FAB2_LIB.BASEBOARD_FAB2(SCH_1):PAGE82_I188@MSTR_SCONN.SCONN288_H44441003(CHIPS)':
 'VSS'<86>: CDS_PINID='VSS(86)';
NODE_NAME     J9U2 15
 '@BASEBOARD_FAB2_LIB.BASEBOARD_FAB2(SCH_1):PAGE82_I188@MSTR_SCONN.SCONN288_H44441003(CHIPS)':
 'VSS'<87>: CDS_PINID='VSS(87)';
NODE_NAME     J9U2 13
 '@BASEBOARD_FAB2_LIB.BASEBOARD_FAB2(SCH_1):PAGE82_I188@MSTR_SCONN.SCONN288_H44441003(CHIPS)':
 'VSS'<88>: CDS_PINID='VSS(88)';
NODE_NAME     J9U2 11
 '@BASEBOARD_FAB2_LIB.BASEBOARD_FAB2(SCH_1):PAGE82_I188@MSTR_SCONN.SCONN288_H44441003(CHIPS)':
 'VSS'<89>: CDS_PINID='VSS(89)';
NODE_NAME     J9U2 9
 '@BASEBOARD_FAB2_LIB.BASEBOARD_FAB2(SCH_1):PAGE82_I188@MSTR_SCONN.SCONN288_H44441003(CHIPS)':
 'VSS'<90>: CDS_PINID='VSS(90)';
NODE_NAME     J9U2 6
 '@BASEBOARD_FAB2_LIB.BASEBOARD_FAB2(SCH_1):PAGE82_I188@MSTR_SCONN.SCONN288_H44441003(CHIPS)':
 'VSS'<91>: CDS_PINID='VSS(91)';
NODE_NAME     J9U2 4
 '@BASEBOARD_FAB2_LIB.BASEBOARD_FAB2(SCH_1):PAGE82_I188@MSTR_SCONN.SCONN288_H44441003(CHIPS)':
 'VSS'<92>: CDS_PINID='VSS(92)';
NODE_NAME     J9U2 2
 '@BASEBOARD_FAB2_LIB.BASEBOARD_FAB2(SCH_1):PAGE82_I188@MSTR_SCONN.SCONN288_H44441003(CHIPS)':
 'VSS'<93>: CDS_PINID='VSS(93)';
NODE_NAME     J1B1 283
 '@BASEBOARD_FAB2_LIB.BASEBOARD_FAB2(SCH_1):PAGE83_I43@MSTR_SCONN.SCONN288_H44441004(CHIPS)':
 'VSS'<0>: CDS_PINID='VSS(0)';
NODE_NAME     J1B1 281
 '@BASEBOARD_FAB2_LIB.BASEBOARD_FAB2(SCH_1):PAGE83_I43@MSTR_SCONN.SCONN288_H44441004(CHIPS)':
 'VSS'<1>: CDS_PINID='VSS(1)';
NODE_NAME     J1B1 279
 '@BASEBOARD_FAB2_LIB.BASEBOARD_FAB2(SCH_1):PAGE83_I43@MSTR_SCONN.SCONN288_H44441004(CHIPS)':
 'VSS'<2>: CDS_PINID='VSS(2)';
NODE_NAME     J1B1 276
 '@BASEBOARD_FAB2_LIB.BASEBOARD_FAB2(SCH_1):PAGE83_I43@MSTR_SCONN.SCONN288_H44441004(CHIPS)':
 'VSS'<3>: CDS_PINID='VSS(3)';
NODE_NAME     J1B1 274
 '@BASEBOARD_FAB2_LIB.BASEBOARD_FAB2(SCH_1):PAGE83_I43@MSTR_SCONN.SCONN288_H44441004(CHIPS)':
 'VSS'<4>: CDS_PINID='VSS(4)';
NODE_NAME     J1B1 272
 '@BASEBOARD_FAB2_LIB.BASEBOARD_FAB2(SCH_1):PAGE83_I43@MSTR_SCONN.SCONN288_H44441004(CHIPS)':
 'VSS'<5>: CDS_PINID='VSS(5)';
NODE_NAME     J1B1 270
 '@BASEBOARD_FAB2_LIB.BASEBOARD_FAB2(SCH_1):PAGE83_I43@MSTR_SCONN.SCONN288_H44441004(CHIPS)':
 'VSS'<6>: CDS_PINID='VSS(6)';
NODE_NAME     J1B1 268
 '@BASEBOARD_FAB2_LIB.BASEBOARD_FAB2(SCH_1):PAGE83_I43@MSTR_SCONN.SCONN288_H44441004(CHIPS)':
 'VSS'<7>: CDS_PINID='VSS(7)';
NODE_NAME     J1B1 265
 '@BASEBOARD_FAB2_LIB.BASEBOARD_FAB2(SCH_1):PAGE83_I43@MSTR_SCONN.SCONN288_H44441004(CHIPS)':
 'VSS'<8>: CDS_PINID='VSS(8)';
NODE_NAME     J1B1 263
 '@BASEBOARD_FAB2_LIB.BASEBOARD_FAB2(SCH_1):PAGE83_I43@MSTR_SCONN.SCONN288_H44441004(CHIPS)':
 'VSS'<9>: CDS_PINID='VSS(9)';
NODE_NAME     J1B1 261
 '@BASEBOARD_FAB2_LIB.BASEBOARD_FAB2(SCH_1):PAGE83_I43@MSTR_SCONN.SCONN288_H44441004(CHIPS)':
 'VSS'<10>: CDS_PINID='VSS(10)';
NODE_NAME     J1B1 259
 '@BASEBOARD_FAB2_LIB.BASEBOARD_FAB2(SCH_1):PAGE83_I43@MSTR_SCONN.SCONN288_H44441004(CHIPS)':
 'VSS'<11>: CDS_PINID='VSS(11)';
NODE_NAME     J1B1 257
 '@BASEBOARD_FAB2_LIB.BASEBOARD_FAB2(SCH_1):PAGE83_I43@MSTR_SCONN.SCONN288_H44441004(CHIPS)':
 'VSS'<12>: CDS_PINID='VSS(12)';
NODE_NAME     J1B1 254
 '@BASEBOARD_FAB2_LIB.BASEBOARD_FAB2(SCH_1):PAGE83_I43@MSTR_SCONN.SCONN288_H44441004(CHIPS)':
 'VSS'<13>: CDS_PINID='VSS(13)';
NODE_NAME     J1B1 252
 '@BASEBOARD_FAB2_LIB.BASEBOARD_FAB2(SCH_1):PAGE83_I43@MSTR_SCONN.SCONN288_H44441004(CHIPS)':
 'VSS'<14>: CDS_PINID='VSS(14)';
NODE_NAME     J1B1 250
 '@BASEBOARD_FAB2_LIB.BASEBOARD_FAB2(SCH_1):PAGE83_I43@MSTR_SCONN.SCONN288_H44441004(CHIPS)':
 'VSS'<15>: CDS_PINID='VSS(15)';
NODE_NAME     J1B1 248
 '@BASEBOARD_FAB2_LIB.BASEBOARD_FAB2(SCH_1):PAGE83_I43@MSTR_SCONN.SCONN288_H44441004(CHIPS)':
 'VSS'<16>: CDS_PINID='VSS(16)';
NODE_NAME     J1B1 246
 '@BASEBOARD_FAB2_LIB.BASEBOARD_FAB2(SCH_1):PAGE83_I43@MSTR_SCONN.SCONN288_H44441004(CHIPS)':
 'VSS'<17>: CDS_PINID='VSS(17)';
NODE_NAME     J1B1 243
 '@BASEBOARD_FAB2_LIB.BASEBOARD_FAB2(SCH_1):PAGE83_I43@MSTR_SCONN.SCONN288_H44441004(CHIPS)':
 'VSS'<18>: CDS_PINID='VSS(18)';
NODE_NAME     J1B1 241
 '@BASEBOARD_FAB2_LIB.BASEBOARD_FAB2(SCH_1):PAGE83_I43@MSTR_SCONN.SCONN288_H44441004(CHIPS)':
 'VSS'<19>: CDS_PINID='VSS(19)';
NODE_NAME     J1B1 239
 '@BASEBOARD_FAB2_LIB.BASEBOARD_FAB2(SCH_1):PAGE83_I43@MSTR_SCONN.SCONN288_H44441004(CHIPS)':
 'VSS'<20>: CDS_PINID='VSS(20)';
NODE_NAME     J1B1 202
 '@BASEBOARD_FAB2_LIB.BASEBOARD_FAB2(SCH_1):PAGE83_I43@MSTR_SCONN.SCONN288_H44441004(CHIPS)':
 'VSS'<21>: CDS_PINID='VSS(21)';
NODE_NAME     J1B1 200
 '@BASEBOARD_FAB2_LIB.BASEBOARD_FAB2(SCH_1):PAGE83_I43@MSTR_SCONN.SCONN288_H44441004(CHIPS)':
 'VSS'<22>: CDS_PINID='VSS(22)';
NODE_NAME     J1B1 198
 '@BASEBOARD_FAB2_LIB.BASEBOARD_FAB2(SCH_1):PAGE83_I43@MSTR_SCONN.SCONN288_H44441004(CHIPS)':
 'VSS'<23>: CDS_PINID='VSS(23)';
NODE_NAME     J1B1 195
 '@BASEBOARD_FAB2_LIB.BASEBOARD_FAB2(SCH_1):PAGE83_I43@MSTR_SCONN.SCONN288_H44441004(CHIPS)':
 'VSS'<24>: CDS_PINID='VSS(24)';
NODE_NAME     J1B1 193
 '@BASEBOARD_FAB2_LIB.BASEBOARD_FAB2(SCH_1):PAGE83_I43@MSTR_SCONN.SCONN288_H44441004(CHIPS)':
 'VSS'<25>: CDS_PINID='VSS(25)';
NODE_NAME     J1B1 191
 '@BASEBOARD_FAB2_LIB.BASEBOARD_FAB2(SCH_1):PAGE83_I43@MSTR_SCONN.SCONN288_H44441004(CHIPS)':
 'VSS'<26>: CDS_PINID='VSS(26)';
NODE_NAME     J1B1 189
 '@BASEBOARD_FAB2_LIB.BASEBOARD_FAB2(SCH_1):PAGE83_I43@MSTR_SCONN.SCONN288_H44441004(CHIPS)':
 'VSS'<27>: CDS_PINID='VSS(27)';
NODE_NAME     J1B1 187
 '@BASEBOARD_FAB2_LIB.BASEBOARD_FAB2(SCH_1):PAGE83_I43@MSTR_SCONN.SCONN288_H44441004(CHIPS)':
 'VSS'<28>: CDS_PINID='VSS(28)';
NODE_NAME     J1B1 184
 '@BASEBOARD_FAB2_LIB.BASEBOARD_FAB2(SCH_1):PAGE83_I43@MSTR_SCONN.SCONN288_H44441004(CHIPS)':
 'VSS'<29>: CDS_PINID='VSS(29)';
NODE_NAME     J1B1 182
 '@BASEBOARD_FAB2_LIB.BASEBOARD_FAB2(SCH_1):PAGE83_I43@MSTR_SCONN.SCONN288_H44441004(CHIPS)':
 'VSS'<30>: CDS_PINID='VSS(30)';
NODE_NAME     J1B1 180
 '@BASEBOARD_FAB2_LIB.BASEBOARD_FAB2(SCH_1):PAGE83_I43@MSTR_SCONN.SCONN288_H44441004(CHIPS)':
 'VSS'<31>: CDS_PINID='VSS(31)';
NODE_NAME     J1B1 178
 '@BASEBOARD_FAB2_LIB.BASEBOARD_FAB2(SCH_1):PAGE83_I43@MSTR_SCONN.SCONN288_H44441004(CHIPS)':
 'VSS'<32>: CDS_PINID='VSS(32)';
NODE_NAME     J1B1 176
 '@BASEBOARD_FAB2_LIB.BASEBOARD_FAB2(SCH_1):PAGE83_I43@MSTR_SCONN.SCONN288_H44441004(CHIPS)':
 'VSS'<33>: CDS_PINID='VSS(33)';
NODE_NAME     J1B1 173
 '@BASEBOARD_FAB2_LIB.BASEBOARD_FAB2(SCH_1):PAGE83_I43@MSTR_SCONN.SCONN288_H44441004(CHIPS)':
 'VSS'<34>: CDS_PINID='VSS(34)';
NODE_NAME     J1B1 171
 '@BASEBOARD_FAB2_LIB.BASEBOARD_FAB2(SCH_1):PAGE83_I43@MSTR_SCONN.SCONN288_H44441004(CHIPS)':
 'VSS'<35>: CDS_PINID='VSS(35)';
NODE_NAME     J1B1 169
 '@BASEBOARD_FAB2_LIB.BASEBOARD_FAB2(SCH_1):PAGE83_I43@MSTR_SCONN.SCONN288_H44441004(CHIPS)':
 'VSS'<36>: CDS_PINID='VSS(36)';
NODE_NAME     J1B1 167
 '@BASEBOARD_FAB2_LIB.BASEBOARD_FAB2(SCH_1):PAGE83_I43@MSTR_SCONN.SCONN288_H44441004(CHIPS)':
 'VSS'<37>: CDS_PINID='VSS(37)';
NODE_NAME     J1B1 165
 '@BASEBOARD_FAB2_LIB.BASEBOARD_FAB2(SCH_1):PAGE83_I43@MSTR_SCONN.SCONN288_H44441004(CHIPS)':
 'VSS'<38>: CDS_PINID='VSS(38)';
NODE_NAME     J1B1 162
 '@BASEBOARD_FAB2_LIB.BASEBOARD_FAB2(SCH_1):PAGE83_I43@MSTR_SCONN.SCONN288_H44441004(CHIPS)':
 'VSS'<39>: CDS_PINID='VSS(39)';
NODE_NAME     J1B1 160
 '@BASEBOARD_FAB2_LIB.BASEBOARD_FAB2(SCH_1):PAGE83_I43@MSTR_SCONN.SCONN288_H44441004(CHIPS)':
 'VSS'<40>: CDS_PINID='VSS(40)';
NODE_NAME     J1B1 158
 '@BASEBOARD_FAB2_LIB.BASEBOARD_FAB2(SCH_1):PAGE83_I43@MSTR_SCONN.SCONN288_H44441004(CHIPS)':
 'VSS'<41>: CDS_PINID='VSS(41)';
NODE_NAME     J1B1 156
 '@BASEBOARD_FAB2_LIB.BASEBOARD_FAB2(SCH_1):PAGE83_I43@MSTR_SCONN.SCONN288_H44441004(CHIPS)':
 'VSS'<42>: CDS_PINID='VSS(42)';
NODE_NAME     J1B1 154
 '@BASEBOARD_FAB2_LIB.BASEBOARD_FAB2(SCH_1):PAGE83_I43@MSTR_SCONN.SCONN288_H44441004(CHIPS)':
 'VSS'<43>: CDS_PINID='VSS(43)';
NODE_NAME     J1B1 151
 '@BASEBOARD_FAB2_LIB.BASEBOARD_FAB2(SCH_1):PAGE83_I43@MSTR_SCONN.SCONN288_H44441004(CHIPS)':
 'VSS'<44>: CDS_PINID='VSS(44)';
NODE_NAME     J1B1 149
 '@BASEBOARD_FAB2_LIB.BASEBOARD_FAB2(SCH_1):PAGE83_I43@MSTR_SCONN.SCONN288_H44441004(CHIPS)':
 'VSS'<45>: CDS_PINID='VSS(45)';
NODE_NAME     J1B1 147
 '@BASEBOARD_FAB2_LIB.BASEBOARD_FAB2(SCH_1):PAGE83_I43@MSTR_SCONN.SCONN288_H44441004(CHIPS)':
 'VSS'<46>: CDS_PINID='VSS(46)';
NODE_NAME     J1B1 138
 '@BASEBOARD_FAB2_LIB.BASEBOARD_FAB2(SCH_1):PAGE83_I43@MSTR_SCONN.SCONN288_H44441004(CHIPS)':
 'VSS'<47>: CDS_PINID='VSS(47)';
NODE_NAME     J1B1 136
 '@BASEBOARD_FAB2_LIB.BASEBOARD_FAB2(SCH_1):PAGE83_I43@MSTR_SCONN.SCONN288_H44441004(CHIPS)':
 'VSS'<48>: CDS_PINID='VSS(48)';
NODE_NAME     J1B1 134
 '@BASEBOARD_FAB2_LIB.BASEBOARD_FAB2(SCH_1):PAGE83_I43@MSTR_SCONN.SCONN288_H44441004(CHIPS)':
 'VSS'<49>: CDS_PINID='VSS(49)';
NODE_NAME     J1B1 131
 '@BASEBOARD_FAB2_LIB.BASEBOARD_FAB2(SCH_1):PAGE83_I43@MSTR_SCONN.SCONN288_H44441004(CHIPS)':
 'VSS'<50>: CDS_PINID='VSS(50)';
NODE_NAME     J1B1 129
 '@BASEBOARD_FAB2_LIB.BASEBOARD_FAB2(SCH_1):PAGE83_I43@MSTR_SCONN.SCONN288_H44441004(CHIPS)':
 'VSS'<51>: CDS_PINID='VSS(51)';
NODE_NAME     J1B1 127
 '@BASEBOARD_FAB2_LIB.BASEBOARD_FAB2(SCH_1):PAGE83_I43@MSTR_SCONN.SCONN288_H44441004(CHIPS)':
 'VSS'<52>: CDS_PINID='VSS(52)';
NODE_NAME     J1B1 125
 '@BASEBOARD_FAB2_LIB.BASEBOARD_FAB2(SCH_1):PAGE83_I43@MSTR_SCONN.SCONN288_H44441004(CHIPS)':
 'VSS'<53>: CDS_PINID='VSS(53)';
NODE_NAME     J1B1 123
 '@BASEBOARD_FAB2_LIB.BASEBOARD_FAB2(SCH_1):PAGE83_I43@MSTR_SCONN.SCONN288_H44441004(CHIPS)':
 'VSS'<54>: CDS_PINID='VSS(54)';
NODE_NAME     J1B1 120
 '@BASEBOARD_FAB2_LIB.BASEBOARD_FAB2(SCH_1):PAGE83_I43@MSTR_SCONN.SCONN288_H44441004(CHIPS)':
 'VSS'<55>: CDS_PINID='VSS(55)';
NODE_NAME     J1B1 118
 '@BASEBOARD_FAB2_LIB.BASEBOARD_FAB2(SCH_1):PAGE83_I43@MSTR_SCONN.SCONN288_H44441004(CHIPS)':
 'VSS'<56>: CDS_PINID='VSS(56)';
NODE_NAME     J1B1 116
 '@BASEBOARD_FAB2_LIB.BASEBOARD_FAB2(SCH_1):PAGE83_I43@MSTR_SCONN.SCONN288_H44441004(CHIPS)':
 'VSS'<57>: CDS_PINID='VSS(57)';
NODE_NAME     J1B1 114
 '@BASEBOARD_FAB2_LIB.BASEBOARD_FAB2(SCH_1):PAGE83_I43@MSTR_SCONN.SCONN288_H44441004(CHIPS)':
 'VSS'<58>: CDS_PINID='VSS(58)';
NODE_NAME     J1B1 112
 '@BASEBOARD_FAB2_LIB.BASEBOARD_FAB2(SCH_1):PAGE83_I43@MSTR_SCONN.SCONN288_H44441004(CHIPS)':
 'VSS'<59>: CDS_PINID='VSS(59)';
NODE_NAME     J1B1 109
 '@BASEBOARD_FAB2_LIB.BASEBOARD_FAB2(SCH_1):PAGE83_I43@MSTR_SCONN.SCONN288_H44441004(CHIPS)':
 'VSS'<60>: CDS_PINID='VSS(60)';
NODE_NAME     J1B1 107
 '@BASEBOARD_FAB2_LIB.BASEBOARD_FAB2(SCH_1):PAGE83_I43@MSTR_SCONN.SCONN288_H44441004(CHIPS)':
 'VSS'<61>: CDS_PINID='VSS(61)';
NODE_NAME     J1B1 105
 '@BASEBOARD_FAB2_LIB.BASEBOARD_FAB2(SCH_1):PAGE83_I43@MSTR_SCONN.SCONN288_H44441004(CHIPS)':
 'VSS'<62>: CDS_PINID='VSS(62)';
NODE_NAME     J1B1 103
 '@BASEBOARD_FAB2_LIB.BASEBOARD_FAB2(SCH_1):PAGE83_I43@MSTR_SCONN.SCONN288_H44441004(CHIPS)':
 'VSS'<63>: CDS_PINID='VSS(63)';
NODE_NAME     J1B1 101
 '@BASEBOARD_FAB2_LIB.BASEBOARD_FAB2(SCH_1):PAGE83_I43@MSTR_SCONN.SCONN288_H44441004(CHIPS)':
 'VSS'<64>: CDS_PINID='VSS(64)';
NODE_NAME     J1B1 98
 '@BASEBOARD_FAB2_LIB.BASEBOARD_FAB2(SCH_1):PAGE83_I43@MSTR_SCONN.SCONN288_H44441004(CHIPS)':
 'VSS'<65>: CDS_PINID='VSS(65)';
NODE_NAME     J1B1 96
 '@BASEBOARD_FAB2_LIB.BASEBOARD_FAB2(SCH_1):PAGE83_I43@MSTR_SCONN.SCONN288_H44441004(CHIPS)':
 'VSS'<66>: CDS_PINID='VSS(66)';
NODE_NAME     J1B1 94
 '@BASEBOARD_FAB2_LIB.BASEBOARD_FAB2(SCH_1):PAGE83_I43@MSTR_SCONN.SCONN288_H44441004(CHIPS)':
 'VSS'<67>: CDS_PINID='VSS(67)';
NODE_NAME     J1B1 57
 '@BASEBOARD_FAB2_LIB.BASEBOARD_FAB2(SCH_1):PAGE83_I43@MSTR_SCONN.SCONN288_H44441004(CHIPS)':
 'VSS'<68>: CDS_PINID='VSS(68)';
NODE_NAME     J1B1 55
 '@BASEBOARD_FAB2_LIB.BASEBOARD_FAB2(SCH_1):PAGE83_I43@MSTR_SCONN.SCONN288_H44441004(CHIPS)':
 'VSS'<69>: CDS_PINID='VSS(69)';
NODE_NAME     J1B1 53
 '@BASEBOARD_FAB2_LIB.BASEBOARD_FAB2(SCH_1):PAGE83_I43@MSTR_SCONN.SCONN288_H44441004(CHIPS)':
 'VSS'<70>: CDS_PINID='VSS(70)';
NODE_NAME     J1B1 50
 '@BASEBOARD_FAB2_LIB.BASEBOARD_FAB2(SCH_1):PAGE83_I43@MSTR_SCONN.SCONN288_H44441004(CHIPS)':
 'VSS'<71>: CDS_PINID='VSS(71)';
NODE_NAME     J1B1 48
 '@BASEBOARD_FAB2_LIB.BASEBOARD_FAB2(SCH_1):PAGE83_I43@MSTR_SCONN.SCONN288_H44441004(CHIPS)':
 'VSS'<72>: CDS_PINID='VSS(72)';
NODE_NAME     J1B1 46
 '@BASEBOARD_FAB2_LIB.BASEBOARD_FAB2(SCH_1):PAGE83_I43@MSTR_SCONN.SCONN288_H44441004(CHIPS)':
 'VSS'<73>: CDS_PINID='VSS(73)';
NODE_NAME     J1B1 44
 '@BASEBOARD_FAB2_LIB.BASEBOARD_FAB2(SCH_1):PAGE83_I43@MSTR_SCONN.SCONN288_H44441004(CHIPS)':
 'VSS'<74>: CDS_PINID='VSS(74)';
NODE_NAME     J1B1 42
 '@BASEBOARD_FAB2_LIB.BASEBOARD_FAB2(SCH_1):PAGE83_I43@MSTR_SCONN.SCONN288_H44441004(CHIPS)':
 'VSS'<75>: CDS_PINID='VSS(75)';
NODE_NAME     J1B1 39
 '@BASEBOARD_FAB2_LIB.BASEBOARD_FAB2(SCH_1):PAGE83_I43@MSTR_SCONN.SCONN288_H44441004(CHIPS)':
 'VSS'<76>: CDS_PINID='VSS(76)';
NODE_NAME     J1B1 37
 '@BASEBOARD_FAB2_LIB.BASEBOARD_FAB2(SCH_1):PAGE83_I43@MSTR_SCONN.SCONN288_H44441004(CHIPS)':
 'VSS'<77>: CDS_PINID='VSS(77)';
NODE_NAME     J1B1 35
 '@BASEBOARD_FAB2_LIB.BASEBOARD_FAB2(SCH_1):PAGE83_I43@MSTR_SCONN.SCONN288_H44441004(CHIPS)':
 'VSS'<78>: CDS_PINID='VSS(78)';
NODE_NAME     J1B1 33
 '@BASEBOARD_FAB2_LIB.BASEBOARD_FAB2(SCH_1):PAGE83_I43@MSTR_SCONN.SCONN288_H44441004(CHIPS)':
 'VSS'<79>: CDS_PINID='VSS(79)';
NODE_NAME     J1B1 31
 '@BASEBOARD_FAB2_LIB.BASEBOARD_FAB2(SCH_1):PAGE83_I43@MSTR_SCONN.SCONN288_H44441004(CHIPS)':
 'VSS'<80>: CDS_PINID='VSS(80)';
NODE_NAME     J1B1 28
 '@BASEBOARD_FAB2_LIB.BASEBOARD_FAB2(SCH_1):PAGE83_I43@MSTR_SCONN.SCONN288_H44441004(CHIPS)':
 'VSS'<81>: CDS_PINID='VSS(81)';
NODE_NAME     J1B1 26
 '@BASEBOARD_FAB2_LIB.BASEBOARD_FAB2(SCH_1):PAGE83_I43@MSTR_SCONN.SCONN288_H44441004(CHIPS)':
 'VSS'<82>: CDS_PINID='VSS(82)';
NODE_NAME     J1B1 24
 '@BASEBOARD_FAB2_LIB.BASEBOARD_FAB2(SCH_1):PAGE83_I43@MSTR_SCONN.SCONN288_H44441004(CHIPS)':
 'VSS'<83>: CDS_PINID='VSS(83)';
NODE_NAME     J1B1 22
 '@BASEBOARD_FAB2_LIB.BASEBOARD_FAB2(SCH_1):PAGE83_I43@MSTR_SCONN.SCONN288_H44441004(CHIPS)':
 'VSS'<84>: CDS_PINID='VSS(84)';
NODE_NAME     J1B1 20
 '@BASEBOARD_FAB2_LIB.BASEBOARD_FAB2(SCH_1):PAGE83_I43@MSTR_SCONN.SCONN288_H44441004(CHIPS)':
 'VSS'<85>: CDS_PINID='VSS(85)';
NODE_NAME     J1B1 17
 '@BASEBOARD_FAB2_LIB.BASEBOARD_FAB2(SCH_1):PAGE83_I43@MSTR_SCONN.SCONN288_H44441004(CHIPS)':
 'VSS'<86>: CDS_PINID='VSS(86)';
NODE_NAME     J1B1 15
 '@BASEBOARD_FAB2_LIB.BASEBOARD_FAB2(SCH_1):PAGE83_I43@MSTR_SCONN.SCONN288_H44441004(CHIPS)':
 'VSS'<87>: CDS_PINID='VSS(87)';
NODE_NAME     J1B1 13
 '@BASEBOARD_FAB2_LIB.BASEBOARD_FAB2(SCH_1):PAGE83_I43@MSTR_SCONN.SCONN288_H44441004(CHIPS)':
 'VSS'<88>: CDS_PINID='VSS(88)';
NODE_NAME     J1B1 11
 '@BASEBOARD_FAB2_LIB.BASEBOARD_FAB2(SCH_1):PAGE83_I43@MSTR_SCONN.SCONN288_H44441004(CHIPS)':
 'VSS'<89>: CDS_PINID='VSS(89)';
NODE_NAME     J1B1 9
 '@BASEBOARD_FAB2_LIB.BASEBOARD_FAB2(SCH_1):PAGE83_I43@MSTR_SCONN.SCONN288_H44441004(CHIPS)':
 'VSS'<90>: CDS_PINID='VSS(90)';
NODE_NAME     J1B1 6
 '@BASEBOARD_FAB2_LIB.BASEBOARD_FAB2(SCH_1):PAGE83_I43@MSTR_SCONN.SCONN288_H44441004(CHIPS)':
 'VSS'<91>: CDS_PINID='VSS(91)';
NODE_NAME     J1B1 4
 '@BASEBOARD_FAB2_LIB.BASEBOARD_FAB2(SCH_1):PAGE83_I43@MSTR_SCONN.SCONN288_H44441004(CHIPS)':
 'VSS'<92>: CDS_PINID='VSS(92)';
NODE_NAME     J1B1 2
 '@BASEBOARD_FAB2_LIB.BASEBOARD_FAB2(SCH_1):PAGE83_I43@MSTR_SCONN.SCONN288_H44441004(CHIPS)':
 'VSS'<93>: CDS_PINID='VSS(93)';
NODE_NAME     J1B1 139
 '@BASEBOARD_FAB2_LIB.BASEBOARD_FAB2(SCH_1):PAGE83_I111@MSTR_SCONN.SCONN288_H44441004(CHIPS)':
 'SA'<0>: CDS_PINID='SA(0)';
NODE_NAME     J1B1 140
 '@BASEBOARD_FAB2_LIB.BASEBOARD_FAB2(SCH_1):PAGE83_I111@MSTR_SCONN.SCONN288_H44441004(CHIPS)':
 'SA'<1>: CDS_PINID='SA(1)';
NODE_NAME     J1B1 238
 '@BASEBOARD_FAB2_LIB.BASEBOARD_FAB2(SCH_1):PAGE83_I111@MSTR_SCONN.SCONN288_H44441004(CHIPS)':
 'SA'<2>: CDS_PINID='SA(2)';
NODE_NAME     C1B9 2
 '@BASEBOARD_FAB2_LIB.BASEBOARD_FAB2(SCH_1):PAGE83_I176@DEV_DISCRETE.CAP_A(CHIPS)':
 'B': CDS_PINID='B';
NODE_NAME     C9M1 2
 '@BASEBOARD_FAB2_LIB.BASEBOARD_FAB2(SCH_1):PAGE84_I4@DEV_DISCRETE.CAP_A(CHIPS)':
 'B': CDS_PINID='B';
NODE_NAME     J9M1 140
 '@BASEBOARD_FAB2_LIB.BASEBOARD_FAB2(SCH_1):PAGE84_I14@MSTR_SCONN.SCONN288_H44441003(CHIPS)':
 'SA'<1>: CDS_PINID='SA(1)';
NODE_NAME     J9M1 238
 '@BASEBOARD_FAB2_LIB.BASEBOARD_FAB2(SCH_1):PAGE84_I14@MSTR_SCONN.SCONN288_H44441003(CHIPS)':
 'SA'<2>: CDS_PINID='SA(2)';
NODE_NAME     J9M1 283
 '@BASEBOARD_FAB2_LIB.BASEBOARD_FAB2(SCH_1):PAGE84_I138@MSTR_SCONN.SCONN288_H44441003(CHIPS)':
 'VSS'<0>: CDS_PINID='VSS(0)';
NODE_NAME     J9M1 281
 '@BASEBOARD_FAB2_LIB.BASEBOARD_FAB2(SCH_1):PAGE84_I138@MSTR_SCONN.SCONN288_H44441003(CHIPS)':
 'VSS'<1>: CDS_PINID='VSS(1)';
NODE_NAME     J9M1 279
 '@BASEBOARD_FAB2_LIB.BASEBOARD_FAB2(SCH_1):PAGE84_I138@MSTR_SCONN.SCONN288_H44441003(CHIPS)':
 'VSS'<2>: CDS_PINID='VSS(2)';
NODE_NAME     J9M1 276
 '@BASEBOARD_FAB2_LIB.BASEBOARD_FAB2(SCH_1):PAGE84_I138@MSTR_SCONN.SCONN288_H44441003(CHIPS)':
 'VSS'<3>: CDS_PINID='VSS(3)';
NODE_NAME     J9M1 274
 '@BASEBOARD_FAB2_LIB.BASEBOARD_FAB2(SCH_1):PAGE84_I138@MSTR_SCONN.SCONN288_H44441003(CHIPS)':
 'VSS'<4>: CDS_PINID='VSS(4)';
NODE_NAME     J9M1 272
 '@BASEBOARD_FAB2_LIB.BASEBOARD_FAB2(SCH_1):PAGE84_I138@MSTR_SCONN.SCONN288_H44441003(CHIPS)':
 'VSS'<5>: CDS_PINID='VSS(5)';
NODE_NAME     J9M1 270
 '@BASEBOARD_FAB2_LIB.BASEBOARD_FAB2(SCH_1):PAGE84_I138@MSTR_SCONN.SCONN288_H44441003(CHIPS)':
 'VSS'<6>: CDS_PINID='VSS(6)';
NODE_NAME     J9M1 268
 '@BASEBOARD_FAB2_LIB.BASEBOARD_FAB2(SCH_1):PAGE84_I138@MSTR_SCONN.SCONN288_H44441003(CHIPS)':
 'VSS'<7>: CDS_PINID='VSS(7)';
NODE_NAME     J9M1 265
 '@BASEBOARD_FAB2_LIB.BASEBOARD_FAB2(SCH_1):PAGE84_I138@MSTR_SCONN.SCONN288_H44441003(CHIPS)':
 'VSS'<8>: CDS_PINID='VSS(8)';
NODE_NAME     J9M1 263
 '@BASEBOARD_FAB2_LIB.BASEBOARD_FAB2(SCH_1):PAGE84_I138@MSTR_SCONN.SCONN288_H44441003(CHIPS)':
 'VSS'<9>: CDS_PINID='VSS(9)';
NODE_NAME     J9M1 261
 '@BASEBOARD_FAB2_LIB.BASEBOARD_FAB2(SCH_1):PAGE84_I138@MSTR_SCONN.SCONN288_H44441003(CHIPS)':
 'VSS'<10>: CDS_PINID='VSS(10)';
NODE_NAME     J9M1 259
 '@BASEBOARD_FAB2_LIB.BASEBOARD_FAB2(SCH_1):PAGE84_I138@MSTR_SCONN.SCONN288_H44441003(CHIPS)':
 'VSS'<11>: CDS_PINID='VSS(11)';
NODE_NAME     J9M1 257
 '@BASEBOARD_FAB2_LIB.BASEBOARD_FAB2(SCH_1):PAGE84_I138@MSTR_SCONN.SCONN288_H44441003(CHIPS)':
 'VSS'<12>: CDS_PINID='VSS(12)';
NODE_NAME     J9M1 254
 '@BASEBOARD_FAB2_LIB.BASEBOARD_FAB2(SCH_1):PAGE84_I138@MSTR_SCONN.SCONN288_H44441003(CHIPS)':
 'VSS'<13>: CDS_PINID='VSS(13)';
NODE_NAME     J9M1 252
 '@BASEBOARD_FAB2_LIB.BASEBOARD_FAB2(SCH_1):PAGE84_I138@MSTR_SCONN.SCONN288_H44441003(CHIPS)':
 'VSS'<14>: CDS_PINID='VSS(14)';
NODE_NAME     J9M1 250
 '@BASEBOARD_FAB2_LIB.BASEBOARD_FAB2(SCH_1):PAGE84_I138@MSTR_SCONN.SCONN288_H44441003(CHIPS)':
 'VSS'<15>: CDS_PINID='VSS(15)';
NODE_NAME     J9M1 248
 '@BASEBOARD_FAB2_LIB.BASEBOARD_FAB2(SCH_1):PAGE84_I138@MSTR_SCONN.SCONN288_H44441003(CHIPS)':
 'VSS'<16>: CDS_PINID='VSS(16)';
NODE_NAME     J9M1 246
 '@BASEBOARD_FAB2_LIB.BASEBOARD_FAB2(SCH_1):PAGE84_I138@MSTR_SCONN.SCONN288_H44441003(CHIPS)':
 'VSS'<17>: CDS_PINID='VSS(17)';
NODE_NAME     J9M1 243
 '@BASEBOARD_FAB2_LIB.BASEBOARD_FAB2(SCH_1):PAGE84_I138@MSTR_SCONN.SCONN288_H44441003(CHIPS)':
 'VSS'<18>: CDS_PINID='VSS(18)';
NODE_NAME     J9M1 241
 '@BASEBOARD_FAB2_LIB.BASEBOARD_FAB2(SCH_1):PAGE84_I138@MSTR_SCONN.SCONN288_H44441003(CHIPS)':
 'VSS'<19>: CDS_PINID='VSS(19)';
NODE_NAME     J9M1 239
 '@BASEBOARD_FAB2_LIB.BASEBOARD_FAB2(SCH_1):PAGE84_I138@MSTR_SCONN.SCONN288_H44441003(CHIPS)':
 'VSS'<20>: CDS_PINID='VSS(20)';
NODE_NAME     J9M1 202
 '@BASEBOARD_FAB2_LIB.BASEBOARD_FAB2(SCH_1):PAGE84_I138@MSTR_SCONN.SCONN288_H44441003(CHIPS)':
 'VSS'<21>: CDS_PINID='VSS(21)';
NODE_NAME     J9M1 200
 '@BASEBOARD_FAB2_LIB.BASEBOARD_FAB2(SCH_1):PAGE84_I138@MSTR_SCONN.SCONN288_H44441003(CHIPS)':
 'VSS'<22>: CDS_PINID='VSS(22)';
NODE_NAME     J9M1 198
 '@BASEBOARD_FAB2_LIB.BASEBOARD_FAB2(SCH_1):PAGE84_I138@MSTR_SCONN.SCONN288_H44441003(CHIPS)':
 'VSS'<23>: CDS_PINID='VSS(23)';
NODE_NAME     J9M1 195
 '@BASEBOARD_FAB2_LIB.BASEBOARD_FAB2(SCH_1):PAGE84_I138@MSTR_SCONN.SCONN288_H44441003(CHIPS)':
 'VSS'<24>: CDS_PINID='VSS(24)';
NODE_NAME     J9M1 193
 '@BASEBOARD_FAB2_LIB.BASEBOARD_FAB2(SCH_1):PAGE84_I138@MSTR_SCONN.SCONN288_H44441003(CHIPS)':
 'VSS'<25>: CDS_PINID='VSS(25)';
NODE_NAME     J9M1 191
 '@BASEBOARD_FAB2_LIB.BASEBOARD_FAB2(SCH_1):PAGE84_I138@MSTR_SCONN.SCONN288_H44441003(CHIPS)':
 'VSS'<26>: CDS_PINID='VSS(26)';
NODE_NAME     J9M1 189
 '@BASEBOARD_FAB2_LIB.BASEBOARD_FAB2(SCH_1):PAGE84_I138@MSTR_SCONN.SCONN288_H44441003(CHIPS)':
 'VSS'<27>: CDS_PINID='VSS(27)';
NODE_NAME     J9M1 187
 '@BASEBOARD_FAB2_LIB.BASEBOARD_FAB2(SCH_1):PAGE84_I138@MSTR_SCONN.SCONN288_H44441003(CHIPS)':
 'VSS'<28>: CDS_PINID='VSS(28)';
NODE_NAME     J9M1 184
 '@BASEBOARD_FAB2_LIB.BASEBOARD_FAB2(SCH_1):PAGE84_I138@MSTR_SCONN.SCONN288_H44441003(CHIPS)':
 'VSS'<29>: CDS_PINID='VSS(29)';
NODE_NAME     J9M1 182
 '@BASEBOARD_FAB2_LIB.BASEBOARD_FAB2(SCH_1):PAGE84_I138@MSTR_SCONN.SCONN288_H44441003(CHIPS)':
 'VSS'<30>: CDS_PINID='VSS(30)';
NODE_NAME     J9M1 180
 '@BASEBOARD_FAB2_LIB.BASEBOARD_FAB2(SCH_1):PAGE84_I138@MSTR_SCONN.SCONN288_H44441003(CHIPS)':
 'VSS'<31>: CDS_PINID='VSS(31)';
NODE_NAME     J9M1 178
 '@BASEBOARD_FAB2_LIB.BASEBOARD_FAB2(SCH_1):PAGE84_I138@MSTR_SCONN.SCONN288_H44441003(CHIPS)':
 'VSS'<32>: CDS_PINID='VSS(32)';
NODE_NAME     J9M1 176
 '@BASEBOARD_FAB2_LIB.BASEBOARD_FAB2(SCH_1):PAGE84_I138@MSTR_SCONN.SCONN288_H44441003(CHIPS)':
 'VSS'<33>: CDS_PINID='VSS(33)';
NODE_NAME     J9M1 173
 '@BASEBOARD_FAB2_LIB.BASEBOARD_FAB2(SCH_1):PAGE84_I138@MSTR_SCONN.SCONN288_H44441003(CHIPS)':
 'VSS'<34>: CDS_PINID='VSS(34)';
NODE_NAME     J9M1 171
 '@BASEBOARD_FAB2_LIB.BASEBOARD_FAB2(SCH_1):PAGE84_I138@MSTR_SCONN.SCONN288_H44441003(CHIPS)':
 'VSS'<35>: CDS_PINID='VSS(35)';
NODE_NAME     J9M1 169
 '@BASEBOARD_FAB2_LIB.BASEBOARD_FAB2(SCH_1):PAGE84_I138@MSTR_SCONN.SCONN288_H44441003(CHIPS)':
 'VSS'<36>: CDS_PINID='VSS(36)';
NODE_NAME     J9M1 167
 '@BASEBOARD_FAB2_LIB.BASEBOARD_FAB2(SCH_1):PAGE84_I138@MSTR_SCONN.SCONN288_H44441003(CHIPS)':
 'VSS'<37>: CDS_PINID='VSS(37)';
NODE_NAME     J9M1 165
 '@BASEBOARD_FAB2_LIB.BASEBOARD_FAB2(SCH_1):PAGE84_I138@MSTR_SCONN.SCONN288_H44441003(CHIPS)':
 'VSS'<38>: CDS_PINID='VSS(38)';
NODE_NAME     J9M1 162
 '@BASEBOARD_FAB2_LIB.BASEBOARD_FAB2(SCH_1):PAGE84_I138@MSTR_SCONN.SCONN288_H44441003(CHIPS)':
 'VSS'<39>: CDS_PINID='VSS(39)';
NODE_NAME     J9M1 160
 '@BASEBOARD_FAB2_LIB.BASEBOARD_FAB2(SCH_1):PAGE84_I138@MSTR_SCONN.SCONN288_H44441003(CHIPS)':
 'VSS'<40>: CDS_PINID='VSS(40)';
NODE_NAME     J9M1 158
 '@BASEBOARD_FAB2_LIB.BASEBOARD_FAB2(SCH_1):PAGE84_I138@MSTR_SCONN.SCONN288_H44441003(CHIPS)':
 'VSS'<41>: CDS_PINID='VSS(41)';
NODE_NAME     J9M1 156
 '@BASEBOARD_FAB2_LIB.BASEBOARD_FAB2(SCH_1):PAGE84_I138@MSTR_SCONN.SCONN288_H44441003(CHIPS)':
 'VSS'<42>: CDS_PINID='VSS(42)';
NODE_NAME     J9M1 154
 '@BASEBOARD_FAB2_LIB.BASEBOARD_FAB2(SCH_1):PAGE84_I138@MSTR_SCONN.SCONN288_H44441003(CHIPS)':
 'VSS'<43>: CDS_PINID='VSS(43)';
NODE_NAME     J9M1 151
 '@BASEBOARD_FAB2_LIB.BASEBOARD_FAB2(SCH_1):PAGE84_I138@MSTR_SCONN.SCONN288_H44441003(CHIPS)':
 'VSS'<44>: CDS_PINID='VSS(44)';
NODE_NAME     J9M1 149
 '@BASEBOARD_FAB2_LIB.BASEBOARD_FAB2(SCH_1):PAGE84_I138@MSTR_SCONN.SCONN288_H44441003(CHIPS)':
 'VSS'<45>: CDS_PINID='VSS(45)';
NODE_NAME     J9M1 147
 '@BASEBOARD_FAB2_LIB.BASEBOARD_FAB2(SCH_1):PAGE84_I138@MSTR_SCONN.SCONN288_H44441003(CHIPS)':
 'VSS'<46>: CDS_PINID='VSS(46)';
NODE_NAME     J9M1 138
 '@BASEBOARD_FAB2_LIB.BASEBOARD_FAB2(SCH_1):PAGE84_I138@MSTR_SCONN.SCONN288_H44441003(CHIPS)':
 'VSS'<47>: CDS_PINID='VSS(47)';
NODE_NAME     J9M1 136
 '@BASEBOARD_FAB2_LIB.BASEBOARD_FAB2(SCH_1):PAGE84_I138@MSTR_SCONN.SCONN288_H44441003(CHIPS)':
 'VSS'<48>: CDS_PINID='VSS(48)';
NODE_NAME     J9M1 134
 '@BASEBOARD_FAB2_LIB.BASEBOARD_FAB2(SCH_1):PAGE84_I138@MSTR_SCONN.SCONN288_H44441003(CHIPS)':
 'VSS'<49>: CDS_PINID='VSS(49)';
NODE_NAME     J9M1 131
 '@BASEBOARD_FAB2_LIB.BASEBOARD_FAB2(SCH_1):PAGE84_I138@MSTR_SCONN.SCONN288_H44441003(CHIPS)':
 'VSS'<50>: CDS_PINID='VSS(50)';
NODE_NAME     J9M1 129
 '@BASEBOARD_FAB2_LIB.BASEBOARD_FAB2(SCH_1):PAGE84_I138@MSTR_SCONN.SCONN288_H44441003(CHIPS)':
 'VSS'<51>: CDS_PINID='VSS(51)';
NODE_NAME     J9M1 127
 '@BASEBOARD_FAB2_LIB.BASEBOARD_FAB2(SCH_1):PAGE84_I138@MSTR_SCONN.SCONN288_H44441003(CHIPS)':
 'VSS'<52>: CDS_PINID='VSS(52)';
NODE_NAME     J9M1 125
 '@BASEBOARD_FAB2_LIB.BASEBOARD_FAB2(SCH_1):PAGE84_I138@MSTR_SCONN.SCONN288_H44441003(CHIPS)':
 'VSS'<53>: CDS_PINID='VSS(53)';
NODE_NAME     J9M1 123
 '@BASEBOARD_FAB2_LIB.BASEBOARD_FAB2(SCH_1):PAGE84_I138@MSTR_SCONN.SCONN288_H44441003(CHIPS)':
 'VSS'<54>: CDS_PINID='VSS(54)';
NODE_NAME     J9M1 120
 '@BASEBOARD_FAB2_LIB.BASEBOARD_FAB2(SCH_1):PAGE84_I138@MSTR_SCONN.SCONN288_H44441003(CHIPS)':
 'VSS'<55>: CDS_PINID='VSS(55)';
NODE_NAME     J9M1 118
 '@BASEBOARD_FAB2_LIB.BASEBOARD_FAB2(SCH_1):PAGE84_I138@MSTR_SCONN.SCONN288_H44441003(CHIPS)':
 'VSS'<56>: CDS_PINID='VSS(56)';
NODE_NAME     J9M1 116
 '@BASEBOARD_FAB2_LIB.BASEBOARD_FAB2(SCH_1):PAGE84_I138@MSTR_SCONN.SCONN288_H44441003(CHIPS)':
 'VSS'<57>: CDS_PINID='VSS(57)';
NODE_NAME     J9M1 114
 '@BASEBOARD_FAB2_LIB.BASEBOARD_FAB2(SCH_1):PAGE84_I138@MSTR_SCONN.SCONN288_H44441003(CHIPS)':
 'VSS'<58>: CDS_PINID='VSS(58)';
NODE_NAME     J9M1 112
 '@BASEBOARD_FAB2_LIB.BASEBOARD_FAB2(SCH_1):PAGE84_I138@MSTR_SCONN.SCONN288_H44441003(CHIPS)':
 'VSS'<59>: CDS_PINID='VSS(59)';
NODE_NAME     J9M1 109
 '@BASEBOARD_FAB2_LIB.BASEBOARD_FAB2(SCH_1):PAGE84_I138@MSTR_SCONN.SCONN288_H44441003(CHIPS)':
 'VSS'<60>: CDS_PINID='VSS(60)';
NODE_NAME     J9M1 107
 '@BASEBOARD_FAB2_LIB.BASEBOARD_FAB2(SCH_1):PAGE84_I138@MSTR_SCONN.SCONN288_H44441003(CHIPS)':
 'VSS'<61>: CDS_PINID='VSS(61)';
NODE_NAME     J9M1 105
 '@BASEBOARD_FAB2_LIB.BASEBOARD_FAB2(SCH_1):PAGE84_I138@MSTR_SCONN.SCONN288_H44441003(CHIPS)':
 'VSS'<62>: CDS_PINID='VSS(62)';
NODE_NAME     J9M1 103
 '@BASEBOARD_FAB2_LIB.BASEBOARD_FAB2(SCH_1):PAGE84_I138@MSTR_SCONN.SCONN288_H44441003(CHIPS)':
 'VSS'<63>: CDS_PINID='VSS(63)';
NODE_NAME     J9M1 101
 '@BASEBOARD_FAB2_LIB.BASEBOARD_FAB2(SCH_1):PAGE84_I138@MSTR_SCONN.SCONN288_H44441003(CHIPS)':
 'VSS'<64>: CDS_PINID='VSS(64)';
NODE_NAME     J9M1 98
 '@BASEBOARD_FAB2_LIB.BASEBOARD_FAB2(SCH_1):PAGE84_I138@MSTR_SCONN.SCONN288_H44441003(CHIPS)':
 'VSS'<65>: CDS_PINID='VSS(65)';
NODE_NAME     J9M1 96
 '@BASEBOARD_FAB2_LIB.BASEBOARD_FAB2(SCH_1):PAGE84_I138@MSTR_SCONN.SCONN288_H44441003(CHIPS)':
 'VSS'<66>: CDS_PINID='VSS(66)';
NODE_NAME     J9M1 94
 '@BASEBOARD_FAB2_LIB.BASEBOARD_FAB2(SCH_1):PAGE84_I138@MSTR_SCONN.SCONN288_H44441003(CHIPS)':
 'VSS'<67>: CDS_PINID='VSS(67)';
NODE_NAME     J9M1 57
 '@BASEBOARD_FAB2_LIB.BASEBOARD_FAB2(SCH_1):PAGE84_I138@MSTR_SCONN.SCONN288_H44441003(CHIPS)':
 'VSS'<68>: CDS_PINID='VSS(68)';
NODE_NAME     J9M1 55
 '@BASEBOARD_FAB2_LIB.BASEBOARD_FAB2(SCH_1):PAGE84_I138@MSTR_SCONN.SCONN288_H44441003(CHIPS)':
 'VSS'<69>: CDS_PINID='VSS(69)';
NODE_NAME     J9M1 53
 '@BASEBOARD_FAB2_LIB.BASEBOARD_FAB2(SCH_1):PAGE84_I138@MSTR_SCONN.SCONN288_H44441003(CHIPS)':
 'VSS'<70>: CDS_PINID='VSS(70)';
NODE_NAME     J9M1 50
 '@BASEBOARD_FAB2_LIB.BASEBOARD_FAB2(SCH_1):PAGE84_I138@MSTR_SCONN.SCONN288_H44441003(CHIPS)':
 'VSS'<71>: CDS_PINID='VSS(71)';
NODE_NAME     J9M1 48
 '@BASEBOARD_FAB2_LIB.BASEBOARD_FAB2(SCH_1):PAGE84_I138@MSTR_SCONN.SCONN288_H44441003(CHIPS)':
 'VSS'<72>: CDS_PINID='VSS(72)';
NODE_NAME     J9M1 46
 '@BASEBOARD_FAB2_LIB.BASEBOARD_FAB2(SCH_1):PAGE84_I138@MSTR_SCONN.SCONN288_H44441003(CHIPS)':
 'VSS'<73>: CDS_PINID='VSS(73)';
NODE_NAME     J9M1 44
 '@BASEBOARD_FAB2_LIB.BASEBOARD_FAB2(SCH_1):PAGE84_I138@MSTR_SCONN.SCONN288_H44441003(CHIPS)':
 'VSS'<74>: CDS_PINID='VSS(74)';
NODE_NAME     J9M1 42
 '@BASEBOARD_FAB2_LIB.BASEBOARD_FAB2(SCH_1):PAGE84_I138@MSTR_SCONN.SCONN288_H44441003(CHIPS)':
 'VSS'<75>: CDS_PINID='VSS(75)';
NODE_NAME     J9M1 39
 '@BASEBOARD_FAB2_LIB.BASEBOARD_FAB2(SCH_1):PAGE84_I138@MSTR_SCONN.SCONN288_H44441003(CHIPS)':
 'VSS'<76>: CDS_PINID='VSS(76)';
NODE_NAME     J9M1 37
 '@BASEBOARD_FAB2_LIB.BASEBOARD_FAB2(SCH_1):PAGE84_I138@MSTR_SCONN.SCONN288_H44441003(CHIPS)':
 'VSS'<77>: CDS_PINID='VSS(77)';
NODE_NAME     J9M1 35
 '@BASEBOARD_FAB2_LIB.BASEBOARD_FAB2(SCH_1):PAGE84_I138@MSTR_SCONN.SCONN288_H44441003(CHIPS)':
 'VSS'<78>: CDS_PINID='VSS(78)';
NODE_NAME     J9M1 33
 '@BASEBOARD_FAB2_LIB.BASEBOARD_FAB2(SCH_1):PAGE84_I138@MSTR_SCONN.SCONN288_H44441003(CHIPS)':
 'VSS'<79>: CDS_PINID='VSS(79)';
NODE_NAME     J9M1 31
 '@BASEBOARD_FAB2_LIB.BASEBOARD_FAB2(SCH_1):PAGE84_I138@MSTR_SCONN.SCONN288_H44441003(CHIPS)':
 'VSS'<80>: CDS_PINID='VSS(80)';
NODE_NAME     J9M1 28
 '@BASEBOARD_FAB2_LIB.BASEBOARD_FAB2(SCH_1):PAGE84_I138@MSTR_SCONN.SCONN288_H44441003(CHIPS)':
 'VSS'<81>: CDS_PINID='VSS(81)';
NODE_NAME     J9M1 26
 '@BASEBOARD_FAB2_LIB.BASEBOARD_FAB2(SCH_1):PAGE84_I138@MSTR_SCONN.SCONN288_H44441003(CHIPS)':
 'VSS'<82>: CDS_PINID='VSS(82)';
NODE_NAME     J9M1 24
 '@BASEBOARD_FAB2_LIB.BASEBOARD_FAB2(SCH_1):PAGE84_I138@MSTR_SCONN.SCONN288_H44441003(CHIPS)':
 'VSS'<83>: CDS_PINID='VSS(83)';
NODE_NAME     J9M1 22
 '@BASEBOARD_FAB2_LIB.BASEBOARD_FAB2(SCH_1):PAGE84_I138@MSTR_SCONN.SCONN288_H44441003(CHIPS)':
 'VSS'<84>: CDS_PINID='VSS(84)';
NODE_NAME     J9M1 20
 '@BASEBOARD_FAB2_LIB.BASEBOARD_FAB2(SCH_1):PAGE84_I138@MSTR_SCONN.SCONN288_H44441003(CHIPS)':
 'VSS'<85>: CDS_PINID='VSS(85)';
NODE_NAME     J9M1 17
 '@BASEBOARD_FAB2_LIB.BASEBOARD_FAB2(SCH_1):PAGE84_I138@MSTR_SCONN.SCONN288_H44441003(CHIPS)':
 'VSS'<86>: CDS_PINID='VSS(86)';
NODE_NAME     J9M1 15
 '@BASEBOARD_FAB2_LIB.BASEBOARD_FAB2(SCH_1):PAGE84_I138@MSTR_SCONN.SCONN288_H44441003(CHIPS)':
 'VSS'<87>: CDS_PINID='VSS(87)';
NODE_NAME     J9M1 13
 '@BASEBOARD_FAB2_LIB.BASEBOARD_FAB2(SCH_1):PAGE84_I138@MSTR_SCONN.SCONN288_H44441003(CHIPS)':
 'VSS'<88>: CDS_PINID='VSS(88)';
NODE_NAME     J9M1 11
 '@BASEBOARD_FAB2_LIB.BASEBOARD_FAB2(SCH_1):PAGE84_I138@MSTR_SCONN.SCONN288_H44441003(CHIPS)':
 'VSS'<89>: CDS_PINID='VSS(89)';
NODE_NAME     J9M1 9
 '@BASEBOARD_FAB2_LIB.BASEBOARD_FAB2(SCH_1):PAGE84_I138@MSTR_SCONN.SCONN288_H44441003(CHIPS)':
 'VSS'<90>: CDS_PINID='VSS(90)';
NODE_NAME     J9M1 6
 '@BASEBOARD_FAB2_LIB.BASEBOARD_FAB2(SCH_1):PAGE84_I138@MSTR_SCONN.SCONN288_H44441003(CHIPS)':
 'VSS'<91>: CDS_PINID='VSS(91)';
NODE_NAME     J9M1 4
 '@BASEBOARD_FAB2_LIB.BASEBOARD_FAB2(SCH_1):PAGE84_I138@MSTR_SCONN.SCONN288_H44441003(CHIPS)':
 'VSS'<92>: CDS_PINID='VSS(92)';
NODE_NAME     J9M1 2
 '@BASEBOARD_FAB2_LIB.BASEBOARD_FAB2(SCH_1):PAGE84_I138@MSTR_SCONN.SCONN288_H44441003(CHIPS)':
 'VSS'<93>: CDS_PINID='VSS(93)';
NODE_NAME     J1A2 283
 '@BASEBOARD_FAB2_LIB.BASEBOARD_FAB2(SCH_1):PAGE85_I43@MSTR_SCONN.SCONN288_H44441004(CHIPS)':
 'VSS'<0>: CDS_PINID='VSS(0)';
NODE_NAME     J1A2 281
 '@BASEBOARD_FAB2_LIB.BASEBOARD_FAB2(SCH_1):PAGE85_I43@MSTR_SCONN.SCONN288_H44441004(CHIPS)':
 'VSS'<1>: CDS_PINID='VSS(1)';
NODE_NAME     J1A2 279
 '@BASEBOARD_FAB2_LIB.BASEBOARD_FAB2(SCH_1):PAGE85_I43@MSTR_SCONN.SCONN288_H44441004(CHIPS)':
 'VSS'<2>: CDS_PINID='VSS(2)';
NODE_NAME     J1A2 276
 '@BASEBOARD_FAB2_LIB.BASEBOARD_FAB2(SCH_1):PAGE85_I43@MSTR_SCONN.SCONN288_H44441004(CHIPS)':
 'VSS'<3>: CDS_PINID='VSS(3)';
NODE_NAME     J1A2 274
 '@BASEBOARD_FAB2_LIB.BASEBOARD_FAB2(SCH_1):PAGE85_I43@MSTR_SCONN.SCONN288_H44441004(CHIPS)':
 'VSS'<4>: CDS_PINID='VSS(4)';
NODE_NAME     J1A2 272
 '@BASEBOARD_FAB2_LIB.BASEBOARD_FAB2(SCH_1):PAGE85_I43@MSTR_SCONN.SCONN288_H44441004(CHIPS)':
 'VSS'<5>: CDS_PINID='VSS(5)';
NODE_NAME     J1A2 270
 '@BASEBOARD_FAB2_LIB.BASEBOARD_FAB2(SCH_1):PAGE85_I43@MSTR_SCONN.SCONN288_H44441004(CHIPS)':
 'VSS'<6>: CDS_PINID='VSS(6)';
NODE_NAME     J1A2 268
 '@BASEBOARD_FAB2_LIB.BASEBOARD_FAB2(SCH_1):PAGE85_I43@MSTR_SCONN.SCONN288_H44441004(CHIPS)':
 'VSS'<7>: CDS_PINID='VSS(7)';
NODE_NAME     J1A2 265
 '@BASEBOARD_FAB2_LIB.BASEBOARD_FAB2(SCH_1):PAGE85_I43@MSTR_SCONN.SCONN288_H44441004(CHIPS)':
 'VSS'<8>: CDS_PINID='VSS(8)';
NODE_NAME     J1A2 263
 '@BASEBOARD_FAB2_LIB.BASEBOARD_FAB2(SCH_1):PAGE85_I43@MSTR_SCONN.SCONN288_H44441004(CHIPS)':
 'VSS'<9>: CDS_PINID='VSS(9)';
NODE_NAME     J1A2 261
 '@BASEBOARD_FAB2_LIB.BASEBOARD_FAB2(SCH_1):PAGE85_I43@MSTR_SCONN.SCONN288_H44441004(CHIPS)':
 'VSS'<10>: CDS_PINID='VSS(10)';
NODE_NAME     J1A2 259
 '@BASEBOARD_FAB2_LIB.BASEBOARD_FAB2(SCH_1):PAGE85_I43@MSTR_SCONN.SCONN288_H44441004(CHIPS)':
 'VSS'<11>: CDS_PINID='VSS(11)';
NODE_NAME     J1A2 257
 '@BASEBOARD_FAB2_LIB.BASEBOARD_FAB2(SCH_1):PAGE85_I43@MSTR_SCONN.SCONN288_H44441004(CHIPS)':
 'VSS'<12>: CDS_PINID='VSS(12)';
NODE_NAME     J1A2 254
 '@BASEBOARD_FAB2_LIB.BASEBOARD_FAB2(SCH_1):PAGE85_I43@MSTR_SCONN.SCONN288_H44441004(CHIPS)':
 'VSS'<13>: CDS_PINID='VSS(13)';
NODE_NAME     J1A2 252
 '@BASEBOARD_FAB2_LIB.BASEBOARD_FAB2(SCH_1):PAGE85_I43@MSTR_SCONN.SCONN288_H44441004(CHIPS)':
 'VSS'<14>: CDS_PINID='VSS(14)';
NODE_NAME     J1A2 250
 '@BASEBOARD_FAB2_LIB.BASEBOARD_FAB2(SCH_1):PAGE85_I43@MSTR_SCONN.SCONN288_H44441004(CHIPS)':
 'VSS'<15>: CDS_PINID='VSS(15)';
NODE_NAME     J1A2 248
 '@BASEBOARD_FAB2_LIB.BASEBOARD_FAB2(SCH_1):PAGE85_I43@MSTR_SCONN.SCONN288_H44441004(CHIPS)':
 'VSS'<16>: CDS_PINID='VSS(16)';
NODE_NAME     J1A2 246
 '@BASEBOARD_FAB2_LIB.BASEBOARD_FAB2(SCH_1):PAGE85_I43@MSTR_SCONN.SCONN288_H44441004(CHIPS)':
 'VSS'<17>: CDS_PINID='VSS(17)';
NODE_NAME     J1A2 243
 '@BASEBOARD_FAB2_LIB.BASEBOARD_FAB2(SCH_1):PAGE85_I43@MSTR_SCONN.SCONN288_H44441004(CHIPS)':
 'VSS'<18>: CDS_PINID='VSS(18)';
NODE_NAME     J1A2 241
 '@BASEBOARD_FAB2_LIB.BASEBOARD_FAB2(SCH_1):PAGE85_I43@MSTR_SCONN.SCONN288_H44441004(CHIPS)':
 'VSS'<19>: CDS_PINID='VSS(19)';
NODE_NAME     J1A2 239
 '@BASEBOARD_FAB2_LIB.BASEBOARD_FAB2(SCH_1):PAGE85_I43@MSTR_SCONN.SCONN288_H44441004(CHIPS)':
 'VSS'<20>: CDS_PINID='VSS(20)';
NODE_NAME     J1A2 202
 '@BASEBOARD_FAB2_LIB.BASEBOARD_FAB2(SCH_1):PAGE85_I43@MSTR_SCONN.SCONN288_H44441004(CHIPS)':
 'VSS'<21>: CDS_PINID='VSS(21)';
NODE_NAME     J1A2 200
 '@BASEBOARD_FAB2_LIB.BASEBOARD_FAB2(SCH_1):PAGE85_I43@MSTR_SCONN.SCONN288_H44441004(CHIPS)':
 'VSS'<22>: CDS_PINID='VSS(22)';
NODE_NAME     J1A2 198
 '@BASEBOARD_FAB2_LIB.BASEBOARD_FAB2(SCH_1):PAGE85_I43@MSTR_SCONN.SCONN288_H44441004(CHIPS)':
 'VSS'<23>: CDS_PINID='VSS(23)';
NODE_NAME     J1A2 195
 '@BASEBOARD_FAB2_LIB.BASEBOARD_FAB2(SCH_1):PAGE85_I43@MSTR_SCONN.SCONN288_H44441004(CHIPS)':
 'VSS'<24>: CDS_PINID='VSS(24)';
NODE_NAME     J1A2 193
 '@BASEBOARD_FAB2_LIB.BASEBOARD_FAB2(SCH_1):PAGE85_I43@MSTR_SCONN.SCONN288_H44441004(CHIPS)':
 'VSS'<25>: CDS_PINID='VSS(25)';
NODE_NAME     J1A2 191
 '@BASEBOARD_FAB2_LIB.BASEBOARD_FAB2(SCH_1):PAGE85_I43@MSTR_SCONN.SCONN288_H44441004(CHIPS)':
 'VSS'<26>: CDS_PINID='VSS(26)';
NODE_NAME     J1A2 189
 '@BASEBOARD_FAB2_LIB.BASEBOARD_FAB2(SCH_1):PAGE85_I43@MSTR_SCONN.SCONN288_H44441004(CHIPS)':
 'VSS'<27>: CDS_PINID='VSS(27)';
NODE_NAME     J1A2 187
 '@BASEBOARD_FAB2_LIB.BASEBOARD_FAB2(SCH_1):PAGE85_I43@MSTR_SCONN.SCONN288_H44441004(CHIPS)':
 'VSS'<28>: CDS_PINID='VSS(28)';
NODE_NAME     J1A2 184
 '@BASEBOARD_FAB2_LIB.BASEBOARD_FAB2(SCH_1):PAGE85_I43@MSTR_SCONN.SCONN288_H44441004(CHIPS)':
 'VSS'<29>: CDS_PINID='VSS(29)';
NODE_NAME     J1A2 182
 '@BASEBOARD_FAB2_LIB.BASEBOARD_FAB2(SCH_1):PAGE85_I43@MSTR_SCONN.SCONN288_H44441004(CHIPS)':
 'VSS'<30>: CDS_PINID='VSS(30)';
NODE_NAME     J1A2 180
 '@BASEBOARD_FAB2_LIB.BASEBOARD_FAB2(SCH_1):PAGE85_I43@MSTR_SCONN.SCONN288_H44441004(CHIPS)':
 'VSS'<31>: CDS_PINID='VSS(31)';
NODE_NAME     J1A2 178
 '@BASEBOARD_FAB2_LIB.BASEBOARD_FAB2(SCH_1):PAGE85_I43@MSTR_SCONN.SCONN288_H44441004(CHIPS)':
 'VSS'<32>: CDS_PINID='VSS(32)';
NODE_NAME     J1A2 176
 '@BASEBOARD_FAB2_LIB.BASEBOARD_FAB2(SCH_1):PAGE85_I43@MSTR_SCONN.SCONN288_H44441004(CHIPS)':
 'VSS'<33>: CDS_PINID='VSS(33)';
NODE_NAME     J1A2 173
 '@BASEBOARD_FAB2_LIB.BASEBOARD_FAB2(SCH_1):PAGE85_I43@MSTR_SCONN.SCONN288_H44441004(CHIPS)':
 'VSS'<34>: CDS_PINID='VSS(34)';
NODE_NAME     J1A2 171
 '@BASEBOARD_FAB2_LIB.BASEBOARD_FAB2(SCH_1):PAGE85_I43@MSTR_SCONN.SCONN288_H44441004(CHIPS)':
 'VSS'<35>: CDS_PINID='VSS(35)';
NODE_NAME     J1A2 169
 '@BASEBOARD_FAB2_LIB.BASEBOARD_FAB2(SCH_1):PAGE85_I43@MSTR_SCONN.SCONN288_H44441004(CHIPS)':
 'VSS'<36>: CDS_PINID='VSS(36)';
NODE_NAME     J1A2 167
 '@BASEBOARD_FAB2_LIB.BASEBOARD_FAB2(SCH_1):PAGE85_I43@MSTR_SCONN.SCONN288_H44441004(CHIPS)':
 'VSS'<37>: CDS_PINID='VSS(37)';
NODE_NAME     J1A2 165
 '@BASEBOARD_FAB2_LIB.BASEBOARD_FAB2(SCH_1):PAGE85_I43@MSTR_SCONN.SCONN288_H44441004(CHIPS)':
 'VSS'<38>: CDS_PINID='VSS(38)';
NODE_NAME     J1A2 162
 '@BASEBOARD_FAB2_LIB.BASEBOARD_FAB2(SCH_1):PAGE85_I43@MSTR_SCONN.SCONN288_H44441004(CHIPS)':
 'VSS'<39>: CDS_PINID='VSS(39)';
NODE_NAME     J1A2 160
 '@BASEBOARD_FAB2_LIB.BASEBOARD_FAB2(SCH_1):PAGE85_I43@MSTR_SCONN.SCONN288_H44441004(CHIPS)':
 'VSS'<40>: CDS_PINID='VSS(40)';
NODE_NAME     J1A2 158
 '@BASEBOARD_FAB2_LIB.BASEBOARD_FAB2(SCH_1):PAGE85_I43@MSTR_SCONN.SCONN288_H44441004(CHIPS)':
 'VSS'<41>: CDS_PINID='VSS(41)';
NODE_NAME     J1A2 156
 '@BASEBOARD_FAB2_LIB.BASEBOARD_FAB2(SCH_1):PAGE85_I43@MSTR_SCONN.SCONN288_H44441004(CHIPS)':
 'VSS'<42>: CDS_PINID='VSS(42)';
NODE_NAME     J1A2 154
 '@BASEBOARD_FAB2_LIB.BASEBOARD_FAB2(SCH_1):PAGE85_I43@MSTR_SCONN.SCONN288_H44441004(CHIPS)':
 'VSS'<43>: CDS_PINID='VSS(43)';
NODE_NAME     J1A2 151
 '@BASEBOARD_FAB2_LIB.BASEBOARD_FAB2(SCH_1):PAGE85_I43@MSTR_SCONN.SCONN288_H44441004(CHIPS)':
 'VSS'<44>: CDS_PINID='VSS(44)';
NODE_NAME     J1A2 149
 '@BASEBOARD_FAB2_LIB.BASEBOARD_FAB2(SCH_1):PAGE85_I43@MSTR_SCONN.SCONN288_H44441004(CHIPS)':
 'VSS'<45>: CDS_PINID='VSS(45)';
NODE_NAME     J1A2 147
 '@BASEBOARD_FAB2_LIB.BASEBOARD_FAB2(SCH_1):PAGE85_I43@MSTR_SCONN.SCONN288_H44441004(CHIPS)':
 'VSS'<46>: CDS_PINID='VSS(46)';
NODE_NAME     J1A2 138
 '@BASEBOARD_FAB2_LIB.BASEBOARD_FAB2(SCH_1):PAGE85_I43@MSTR_SCONN.SCONN288_H44441004(CHIPS)':
 'VSS'<47>: CDS_PINID='VSS(47)';
NODE_NAME     J1A2 136
 '@BASEBOARD_FAB2_LIB.BASEBOARD_FAB2(SCH_1):PAGE85_I43@MSTR_SCONN.SCONN288_H44441004(CHIPS)':
 'VSS'<48>: CDS_PINID='VSS(48)';
NODE_NAME     J1A2 134
 '@BASEBOARD_FAB2_LIB.BASEBOARD_FAB2(SCH_1):PAGE85_I43@MSTR_SCONN.SCONN288_H44441004(CHIPS)':
 'VSS'<49>: CDS_PINID='VSS(49)';
NODE_NAME     J1A2 131
 '@BASEBOARD_FAB2_LIB.BASEBOARD_FAB2(SCH_1):PAGE85_I43@MSTR_SCONN.SCONN288_H44441004(CHIPS)':
 'VSS'<50>: CDS_PINID='VSS(50)';
NODE_NAME     J1A2 129
 '@BASEBOARD_FAB2_LIB.BASEBOARD_FAB2(SCH_1):PAGE85_I43@MSTR_SCONN.SCONN288_H44441004(CHIPS)':
 'VSS'<51>: CDS_PINID='VSS(51)';
NODE_NAME     J1A2 127
 '@BASEBOARD_FAB2_LIB.BASEBOARD_FAB2(SCH_1):PAGE85_I43@MSTR_SCONN.SCONN288_H44441004(CHIPS)':
 'VSS'<52>: CDS_PINID='VSS(52)';
NODE_NAME     J1A2 125
 '@BASEBOARD_FAB2_LIB.BASEBOARD_FAB2(SCH_1):PAGE85_I43@MSTR_SCONN.SCONN288_H44441004(CHIPS)':
 'VSS'<53>: CDS_PINID='VSS(53)';
NODE_NAME     J1A2 123
 '@BASEBOARD_FAB2_LIB.BASEBOARD_FAB2(SCH_1):PAGE85_I43@MSTR_SCONN.SCONN288_H44441004(CHIPS)':
 'VSS'<54>: CDS_PINID='VSS(54)';
NODE_NAME     J1A2 120
 '@BASEBOARD_FAB2_LIB.BASEBOARD_FAB2(SCH_1):PAGE85_I43@MSTR_SCONN.SCONN288_H44441004(CHIPS)':
 'VSS'<55>: CDS_PINID='VSS(55)';
NODE_NAME     J1A2 118
 '@BASEBOARD_FAB2_LIB.BASEBOARD_FAB2(SCH_1):PAGE85_I43@MSTR_SCONN.SCONN288_H44441004(CHIPS)':
 'VSS'<56>: CDS_PINID='VSS(56)';
NODE_NAME     J1A2 116
 '@BASEBOARD_FAB2_LIB.BASEBOARD_FAB2(SCH_1):PAGE85_I43@MSTR_SCONN.SCONN288_H44441004(CHIPS)':
 'VSS'<57>: CDS_PINID='VSS(57)';
NODE_NAME     J1A2 114
 '@BASEBOARD_FAB2_LIB.BASEBOARD_FAB2(SCH_1):PAGE85_I43@MSTR_SCONN.SCONN288_H44441004(CHIPS)':
 'VSS'<58>: CDS_PINID='VSS(58)';
NODE_NAME     J1A2 112
 '@BASEBOARD_FAB2_LIB.BASEBOARD_FAB2(SCH_1):PAGE85_I43@MSTR_SCONN.SCONN288_H44441004(CHIPS)':
 'VSS'<59>: CDS_PINID='VSS(59)';
NODE_NAME     J1A2 109
 '@BASEBOARD_FAB2_LIB.BASEBOARD_FAB2(SCH_1):PAGE85_I43@MSTR_SCONN.SCONN288_H44441004(CHIPS)':
 'VSS'<60>: CDS_PINID='VSS(60)';
NODE_NAME     J1A2 107
 '@BASEBOARD_FAB2_LIB.BASEBOARD_FAB2(SCH_1):PAGE85_I43@MSTR_SCONN.SCONN288_H44441004(CHIPS)':
 'VSS'<61>: CDS_PINID='VSS(61)';
NODE_NAME     J1A2 105
 '@BASEBOARD_FAB2_LIB.BASEBOARD_FAB2(SCH_1):PAGE85_I43@MSTR_SCONN.SCONN288_H44441004(CHIPS)':
 'VSS'<62>: CDS_PINID='VSS(62)';
NODE_NAME     J1A2 103
 '@BASEBOARD_FAB2_LIB.BASEBOARD_FAB2(SCH_1):PAGE85_I43@MSTR_SCONN.SCONN288_H44441004(CHIPS)':
 'VSS'<63>: CDS_PINID='VSS(63)';
NODE_NAME     J1A2 101
 '@BASEBOARD_FAB2_LIB.BASEBOARD_FAB2(SCH_1):PAGE85_I43@MSTR_SCONN.SCONN288_H44441004(CHIPS)':
 'VSS'<64>: CDS_PINID='VSS(64)';
NODE_NAME     J1A2 98
 '@BASEBOARD_FAB2_LIB.BASEBOARD_FAB2(SCH_1):PAGE85_I43@MSTR_SCONN.SCONN288_H44441004(CHIPS)':
 'VSS'<65>: CDS_PINID='VSS(65)';
NODE_NAME     J1A2 96
 '@BASEBOARD_FAB2_LIB.BASEBOARD_FAB2(SCH_1):PAGE85_I43@MSTR_SCONN.SCONN288_H44441004(CHIPS)':
 'VSS'<66>: CDS_PINID='VSS(66)';
NODE_NAME     J1A2 94
 '@BASEBOARD_FAB2_LIB.BASEBOARD_FAB2(SCH_1):PAGE85_I43@MSTR_SCONN.SCONN288_H44441004(CHIPS)':
 'VSS'<67>: CDS_PINID='VSS(67)';
NODE_NAME     J1A2 57
 '@BASEBOARD_FAB2_LIB.BASEBOARD_FAB2(SCH_1):PAGE85_I43@MSTR_SCONN.SCONN288_H44441004(CHIPS)':
 'VSS'<68>: CDS_PINID='VSS(68)';
NODE_NAME     J1A2 55
 '@BASEBOARD_FAB2_LIB.BASEBOARD_FAB2(SCH_1):PAGE85_I43@MSTR_SCONN.SCONN288_H44441004(CHIPS)':
 'VSS'<69>: CDS_PINID='VSS(69)';
NODE_NAME     J1A2 53
 '@BASEBOARD_FAB2_LIB.BASEBOARD_FAB2(SCH_1):PAGE85_I43@MSTR_SCONN.SCONN288_H44441004(CHIPS)':
 'VSS'<70>: CDS_PINID='VSS(70)';
NODE_NAME     J1A2 50
 '@BASEBOARD_FAB2_LIB.BASEBOARD_FAB2(SCH_1):PAGE85_I43@MSTR_SCONN.SCONN288_H44441004(CHIPS)':
 'VSS'<71>: CDS_PINID='VSS(71)';
NODE_NAME     J1A2 48
 '@BASEBOARD_FAB2_LIB.BASEBOARD_FAB2(SCH_1):PAGE85_I43@MSTR_SCONN.SCONN288_H44441004(CHIPS)':
 'VSS'<72>: CDS_PINID='VSS(72)';
NODE_NAME     J1A2 46
 '@BASEBOARD_FAB2_LIB.BASEBOARD_FAB2(SCH_1):PAGE85_I43@MSTR_SCONN.SCONN288_H44441004(CHIPS)':
 'VSS'<73>: CDS_PINID='VSS(73)';
NODE_NAME     J1A2 44
 '@BASEBOARD_FAB2_LIB.BASEBOARD_FAB2(SCH_1):PAGE85_I43@MSTR_SCONN.SCONN288_H44441004(CHIPS)':
 'VSS'<74>: CDS_PINID='VSS(74)';
NODE_NAME     J1A2 42
 '@BASEBOARD_FAB2_LIB.BASEBOARD_FAB2(SCH_1):PAGE85_I43@MSTR_SCONN.SCONN288_H44441004(CHIPS)':
 'VSS'<75>: CDS_PINID='VSS(75)';
NODE_NAME     J1A2 39
 '@BASEBOARD_FAB2_LIB.BASEBOARD_FAB2(SCH_1):PAGE85_I43@MSTR_SCONN.SCONN288_H44441004(CHIPS)':
 'VSS'<76>: CDS_PINID='VSS(76)';
NODE_NAME     J1A2 37
 '@BASEBOARD_FAB2_LIB.BASEBOARD_FAB2(SCH_1):PAGE85_I43@MSTR_SCONN.SCONN288_H44441004(CHIPS)':
 'VSS'<77>: CDS_PINID='VSS(77)';
NODE_NAME     J1A2 35
 '@BASEBOARD_FAB2_LIB.BASEBOARD_FAB2(SCH_1):PAGE85_I43@MSTR_SCONN.SCONN288_H44441004(CHIPS)':
 'VSS'<78>: CDS_PINID='VSS(78)';
NODE_NAME     J1A2 33
 '@BASEBOARD_FAB2_LIB.BASEBOARD_FAB2(SCH_1):PAGE85_I43@MSTR_SCONN.SCONN288_H44441004(CHIPS)':
 'VSS'<79>: CDS_PINID='VSS(79)';
NODE_NAME     J1A2 31
 '@BASEBOARD_FAB2_LIB.BASEBOARD_FAB2(SCH_1):PAGE85_I43@MSTR_SCONN.SCONN288_H44441004(CHIPS)':
 'VSS'<80>: CDS_PINID='VSS(80)';
NODE_NAME     J1A2 28
 '@BASEBOARD_FAB2_LIB.BASEBOARD_FAB2(SCH_1):PAGE85_I43@MSTR_SCONN.SCONN288_H44441004(CHIPS)':
 'VSS'<81>: CDS_PINID='VSS(81)';
NODE_NAME     J1A2 26
 '@BASEBOARD_FAB2_LIB.BASEBOARD_FAB2(SCH_1):PAGE85_I43@MSTR_SCONN.SCONN288_H44441004(CHIPS)':
 'VSS'<82>: CDS_PINID='VSS(82)';
NODE_NAME     J1A2 24
 '@BASEBOARD_FAB2_LIB.BASEBOARD_FAB2(SCH_1):PAGE85_I43@MSTR_SCONN.SCONN288_H44441004(CHIPS)':
 'VSS'<83>: CDS_PINID='VSS(83)';
NODE_NAME     J1A2 22
 '@BASEBOARD_FAB2_LIB.BASEBOARD_FAB2(SCH_1):PAGE85_I43@MSTR_SCONN.SCONN288_H44441004(CHIPS)':
 'VSS'<84>: CDS_PINID='VSS(84)';
NODE_NAME     J1A2 20
 '@BASEBOARD_FAB2_LIB.BASEBOARD_FAB2(SCH_1):PAGE85_I43@MSTR_SCONN.SCONN288_H44441004(CHIPS)':
 'VSS'<85>: CDS_PINID='VSS(85)';
NODE_NAME     J1A2 17
 '@BASEBOARD_FAB2_LIB.BASEBOARD_FAB2(SCH_1):PAGE85_I43@MSTR_SCONN.SCONN288_H44441004(CHIPS)':
 'VSS'<86>: CDS_PINID='VSS(86)';
NODE_NAME     J1A2 15
 '@BASEBOARD_FAB2_LIB.BASEBOARD_FAB2(SCH_1):PAGE85_I43@MSTR_SCONN.SCONN288_H44441004(CHIPS)':
 'VSS'<87>: CDS_PINID='VSS(87)';
NODE_NAME     J1A2 13
 '@BASEBOARD_FAB2_LIB.BASEBOARD_FAB2(SCH_1):PAGE85_I43@MSTR_SCONN.SCONN288_H44441004(CHIPS)':
 'VSS'<88>: CDS_PINID='VSS(88)';
NODE_NAME     J1A2 11
 '@BASEBOARD_FAB2_LIB.BASEBOARD_FAB2(SCH_1):PAGE85_I43@MSTR_SCONN.SCONN288_H44441004(CHIPS)':
 'VSS'<89>: CDS_PINID='VSS(89)';
NODE_NAME     J1A2 9
 '@BASEBOARD_FAB2_LIB.BASEBOARD_FAB2(SCH_1):PAGE85_I43@MSTR_SCONN.SCONN288_H44441004(CHIPS)':
 'VSS'<90>: CDS_PINID='VSS(90)';
NODE_NAME     J1A2 6
 '@BASEBOARD_FAB2_LIB.BASEBOARD_FAB2(SCH_1):PAGE85_I43@MSTR_SCONN.SCONN288_H44441004(CHIPS)':
 'VSS'<91>: CDS_PINID='VSS(91)';
NODE_NAME     J1A2 4
 '@BASEBOARD_FAB2_LIB.BASEBOARD_FAB2(SCH_1):PAGE85_I43@MSTR_SCONN.SCONN288_H44441004(CHIPS)':
 'VSS'<92>: CDS_PINID='VSS(92)';
NODE_NAME     J1A2 2
 '@BASEBOARD_FAB2_LIB.BASEBOARD_FAB2(SCH_1):PAGE85_I43@MSTR_SCONN.SCONN288_H44441004(CHIPS)':
 'VSS'<93>: CDS_PINID='VSS(93)';
NODE_NAME     J1A2 139
 '@BASEBOARD_FAB2_LIB.BASEBOARD_FAB2(SCH_1):PAGE85_I111@MSTR_SCONN.SCONN288_H44441004(CHIPS)':
 'SA'<0>: CDS_PINID='SA(0)';
NODE_NAME     J1A2 238
 '@BASEBOARD_FAB2_LIB.BASEBOARD_FAB2(SCH_1):PAGE85_I111@MSTR_SCONN.SCONN288_H44441004(CHIPS)':
 'SA'<2>: CDS_PINID='SA(2)';
NODE_NAME     C9L7 2
 '@BASEBOARD_FAB2_LIB.BASEBOARD_FAB2(SCH_1):PAGE85_I181@DEV_DISCRETE.CAP_A(CHIPS)':
 'B': CDS_PINID='B';
NODE_NAME     J9L2 238
 '@BASEBOARD_FAB2_LIB.BASEBOARD_FAB2(SCH_1):PAGE86_I12@MSTR_SCONN.SCONN288_H44441003(CHIPS)':
 'SA'<2>: CDS_PINID='SA(2)';
NODE_NAME     J9L2 283
 '@BASEBOARD_FAB2_LIB.BASEBOARD_FAB2(SCH_1):PAGE86_I138@MSTR_SCONN.SCONN288_H44441003(CHIPS)':
 'VSS'<0>: CDS_PINID='VSS(0)';
NODE_NAME     J9L2 281
 '@BASEBOARD_FAB2_LIB.BASEBOARD_FAB2(SCH_1):PAGE86_I138@MSTR_SCONN.SCONN288_H44441003(CHIPS)':
 'VSS'<1>: CDS_PINID='VSS(1)';
NODE_NAME     J9L2 279
 '@BASEBOARD_FAB2_LIB.BASEBOARD_FAB2(SCH_1):PAGE86_I138@MSTR_SCONN.SCONN288_H44441003(CHIPS)':
 'VSS'<2>: CDS_PINID='VSS(2)';
NODE_NAME     J9L2 276
 '@BASEBOARD_FAB2_LIB.BASEBOARD_FAB2(SCH_1):PAGE86_I138@MSTR_SCONN.SCONN288_H44441003(CHIPS)':
 'VSS'<3>: CDS_PINID='VSS(3)';
NODE_NAME     J9L2 274
 '@BASEBOARD_FAB2_LIB.BASEBOARD_FAB2(SCH_1):PAGE86_I138@MSTR_SCONN.SCONN288_H44441003(CHIPS)':
 'VSS'<4>: CDS_PINID='VSS(4)';
NODE_NAME     J9L2 272
 '@BASEBOARD_FAB2_LIB.BASEBOARD_FAB2(SCH_1):PAGE86_I138@MSTR_SCONN.SCONN288_H44441003(CHIPS)':
 'VSS'<5>: CDS_PINID='VSS(5)';
NODE_NAME     J9L2 270
 '@BASEBOARD_FAB2_LIB.BASEBOARD_FAB2(SCH_1):PAGE86_I138@MSTR_SCONN.SCONN288_H44441003(CHIPS)':
 'VSS'<6>: CDS_PINID='VSS(6)';
NODE_NAME     J9L2 268
 '@BASEBOARD_FAB2_LIB.BASEBOARD_FAB2(SCH_1):PAGE86_I138@MSTR_SCONN.SCONN288_H44441003(CHIPS)':
 'VSS'<7>: CDS_PINID='VSS(7)';
NODE_NAME     J9L2 265
 '@BASEBOARD_FAB2_LIB.BASEBOARD_FAB2(SCH_1):PAGE86_I138@MSTR_SCONN.SCONN288_H44441003(CHIPS)':
 'VSS'<8>: CDS_PINID='VSS(8)';
NODE_NAME     J9L2 263
 '@BASEBOARD_FAB2_LIB.BASEBOARD_FAB2(SCH_1):PAGE86_I138@MSTR_SCONN.SCONN288_H44441003(CHIPS)':
 'VSS'<9>: CDS_PINID='VSS(9)';
NODE_NAME     J9L2 261
 '@BASEBOARD_FAB2_LIB.BASEBOARD_FAB2(SCH_1):PAGE86_I138@MSTR_SCONN.SCONN288_H44441003(CHIPS)':
 'VSS'<10>: CDS_PINID='VSS(10)';
NODE_NAME     J9L2 259
 '@BASEBOARD_FAB2_LIB.BASEBOARD_FAB2(SCH_1):PAGE86_I138@MSTR_SCONN.SCONN288_H44441003(CHIPS)':
 'VSS'<11>: CDS_PINID='VSS(11)';
NODE_NAME     J9L2 257
 '@BASEBOARD_FAB2_LIB.BASEBOARD_FAB2(SCH_1):PAGE86_I138@MSTR_SCONN.SCONN288_H44441003(CHIPS)':
 'VSS'<12>: CDS_PINID='VSS(12)';
NODE_NAME     J9L2 254
 '@BASEBOARD_FAB2_LIB.BASEBOARD_FAB2(SCH_1):PAGE86_I138@MSTR_SCONN.SCONN288_H44441003(CHIPS)':
 'VSS'<13>: CDS_PINID='VSS(13)';
NODE_NAME     J9L2 252
 '@BASEBOARD_FAB2_LIB.BASEBOARD_FAB2(SCH_1):PAGE86_I138@MSTR_SCONN.SCONN288_H44441003(CHIPS)':
 'VSS'<14>: CDS_PINID='VSS(14)';
NODE_NAME     J9L2 250
 '@BASEBOARD_FAB2_LIB.BASEBOARD_FAB2(SCH_1):PAGE86_I138@MSTR_SCONN.SCONN288_H44441003(CHIPS)':
 'VSS'<15>: CDS_PINID='VSS(15)';
NODE_NAME     J9L2 248
 '@BASEBOARD_FAB2_LIB.BASEBOARD_FAB2(SCH_1):PAGE86_I138@MSTR_SCONN.SCONN288_H44441003(CHIPS)':
 'VSS'<16>: CDS_PINID='VSS(16)';
NODE_NAME     J9L2 246
 '@BASEBOARD_FAB2_LIB.BASEBOARD_FAB2(SCH_1):PAGE86_I138@MSTR_SCONN.SCONN288_H44441003(CHIPS)':
 'VSS'<17>: CDS_PINID='VSS(17)';
NODE_NAME     J9L2 243
 '@BASEBOARD_FAB2_LIB.BASEBOARD_FAB2(SCH_1):PAGE86_I138@MSTR_SCONN.SCONN288_H44441003(CHIPS)':
 'VSS'<18>: CDS_PINID='VSS(18)';
NODE_NAME     J9L2 241
 '@BASEBOARD_FAB2_LIB.BASEBOARD_FAB2(SCH_1):PAGE86_I138@MSTR_SCONN.SCONN288_H44441003(CHIPS)':
 'VSS'<19>: CDS_PINID='VSS(19)';
NODE_NAME     J9L2 239
 '@BASEBOARD_FAB2_LIB.BASEBOARD_FAB2(SCH_1):PAGE86_I138@MSTR_SCONN.SCONN288_H44441003(CHIPS)':
 'VSS'<20>: CDS_PINID='VSS(20)';
NODE_NAME     J9L2 202
 '@BASEBOARD_FAB2_LIB.BASEBOARD_FAB2(SCH_1):PAGE86_I138@MSTR_SCONN.SCONN288_H44441003(CHIPS)':
 'VSS'<21>: CDS_PINID='VSS(21)';
NODE_NAME     J9L2 200
 '@BASEBOARD_FAB2_LIB.BASEBOARD_FAB2(SCH_1):PAGE86_I138@MSTR_SCONN.SCONN288_H44441003(CHIPS)':
 'VSS'<22>: CDS_PINID='VSS(22)';
NODE_NAME     J9L2 198
 '@BASEBOARD_FAB2_LIB.BASEBOARD_FAB2(SCH_1):PAGE86_I138@MSTR_SCONN.SCONN288_H44441003(CHIPS)':
 'VSS'<23>: CDS_PINID='VSS(23)';
NODE_NAME     J9L2 195
 '@BASEBOARD_FAB2_LIB.BASEBOARD_FAB2(SCH_1):PAGE86_I138@MSTR_SCONN.SCONN288_H44441003(CHIPS)':
 'VSS'<24>: CDS_PINID='VSS(24)';
NODE_NAME     J9L2 193
 '@BASEBOARD_FAB2_LIB.BASEBOARD_FAB2(SCH_1):PAGE86_I138@MSTR_SCONN.SCONN288_H44441003(CHIPS)':
 'VSS'<25>: CDS_PINID='VSS(25)';
NODE_NAME     J9L2 191
 '@BASEBOARD_FAB2_LIB.BASEBOARD_FAB2(SCH_1):PAGE86_I138@MSTR_SCONN.SCONN288_H44441003(CHIPS)':
 'VSS'<26>: CDS_PINID='VSS(26)';
NODE_NAME     J9L2 189
 '@BASEBOARD_FAB2_LIB.BASEBOARD_FAB2(SCH_1):PAGE86_I138@MSTR_SCONN.SCONN288_H44441003(CHIPS)':
 'VSS'<27>: CDS_PINID='VSS(27)';
NODE_NAME     J9L2 187
 '@BASEBOARD_FAB2_LIB.BASEBOARD_FAB2(SCH_1):PAGE86_I138@MSTR_SCONN.SCONN288_H44441003(CHIPS)':
 'VSS'<28>: CDS_PINID='VSS(28)';
NODE_NAME     J9L2 184
 '@BASEBOARD_FAB2_LIB.BASEBOARD_FAB2(SCH_1):PAGE86_I138@MSTR_SCONN.SCONN288_H44441003(CHIPS)':
 'VSS'<29>: CDS_PINID='VSS(29)';
NODE_NAME     J9L2 182
 '@BASEBOARD_FAB2_LIB.BASEBOARD_FAB2(SCH_1):PAGE86_I138@MSTR_SCONN.SCONN288_H44441003(CHIPS)':
 'VSS'<30>: CDS_PINID='VSS(30)';
NODE_NAME     J9L2 180
 '@BASEBOARD_FAB2_LIB.BASEBOARD_FAB2(SCH_1):PAGE86_I138@MSTR_SCONN.SCONN288_H44441003(CHIPS)':
 'VSS'<31>: CDS_PINID='VSS(31)';
NODE_NAME     J9L2 178
 '@BASEBOARD_FAB2_LIB.BASEBOARD_FAB2(SCH_1):PAGE86_I138@MSTR_SCONN.SCONN288_H44441003(CHIPS)':
 'VSS'<32>: CDS_PINID='VSS(32)';
NODE_NAME     J9L2 176
 '@BASEBOARD_FAB2_LIB.BASEBOARD_FAB2(SCH_1):PAGE86_I138@MSTR_SCONN.SCONN288_H44441003(CHIPS)':
 'VSS'<33>: CDS_PINID='VSS(33)';
NODE_NAME     J9L2 173
 '@BASEBOARD_FAB2_LIB.BASEBOARD_FAB2(SCH_1):PAGE86_I138@MSTR_SCONN.SCONN288_H44441003(CHIPS)':
 'VSS'<34>: CDS_PINID='VSS(34)';
NODE_NAME     J9L2 171
 '@BASEBOARD_FAB2_LIB.BASEBOARD_FAB2(SCH_1):PAGE86_I138@MSTR_SCONN.SCONN288_H44441003(CHIPS)':
 'VSS'<35>: CDS_PINID='VSS(35)';
NODE_NAME     J9L2 169
 '@BASEBOARD_FAB2_LIB.BASEBOARD_FAB2(SCH_1):PAGE86_I138@MSTR_SCONN.SCONN288_H44441003(CHIPS)':
 'VSS'<36>: CDS_PINID='VSS(36)';
NODE_NAME     J9L2 167
 '@BASEBOARD_FAB2_LIB.BASEBOARD_FAB2(SCH_1):PAGE86_I138@MSTR_SCONN.SCONN288_H44441003(CHIPS)':
 'VSS'<37>: CDS_PINID='VSS(37)';
NODE_NAME     J9L2 165
 '@BASEBOARD_FAB2_LIB.BASEBOARD_FAB2(SCH_1):PAGE86_I138@MSTR_SCONN.SCONN288_H44441003(CHIPS)':
 'VSS'<38>: CDS_PINID='VSS(38)';
NODE_NAME     J9L2 162
 '@BASEBOARD_FAB2_LIB.BASEBOARD_FAB2(SCH_1):PAGE86_I138@MSTR_SCONN.SCONN288_H44441003(CHIPS)':
 'VSS'<39>: CDS_PINID='VSS(39)';
NODE_NAME     J9L2 160
 '@BASEBOARD_FAB2_LIB.BASEBOARD_FAB2(SCH_1):PAGE86_I138@MSTR_SCONN.SCONN288_H44441003(CHIPS)':
 'VSS'<40>: CDS_PINID='VSS(40)';
NODE_NAME     J9L2 158
 '@BASEBOARD_FAB2_LIB.BASEBOARD_FAB2(SCH_1):PAGE86_I138@MSTR_SCONN.SCONN288_H44441003(CHIPS)':
 'VSS'<41>: CDS_PINID='VSS(41)';
NODE_NAME     J9L2 156
 '@BASEBOARD_FAB2_LIB.BASEBOARD_FAB2(SCH_1):PAGE86_I138@MSTR_SCONN.SCONN288_H44441003(CHIPS)':
 'VSS'<42>: CDS_PINID='VSS(42)';
NODE_NAME     J9L2 154
 '@BASEBOARD_FAB2_LIB.BASEBOARD_FAB2(SCH_1):PAGE86_I138@MSTR_SCONN.SCONN288_H44441003(CHIPS)':
 'VSS'<43>: CDS_PINID='VSS(43)';
NODE_NAME     J9L2 151
 '@BASEBOARD_FAB2_LIB.BASEBOARD_FAB2(SCH_1):PAGE86_I138@MSTR_SCONN.SCONN288_H44441003(CHIPS)':
 'VSS'<44>: CDS_PINID='VSS(44)';
NODE_NAME     J9L2 149
 '@BASEBOARD_FAB2_LIB.BASEBOARD_FAB2(SCH_1):PAGE86_I138@MSTR_SCONN.SCONN288_H44441003(CHIPS)':
 'VSS'<45>: CDS_PINID='VSS(45)';
NODE_NAME     J9L2 147
 '@BASEBOARD_FAB2_LIB.BASEBOARD_FAB2(SCH_1):PAGE86_I138@MSTR_SCONN.SCONN288_H44441003(CHIPS)':
 'VSS'<46>: CDS_PINID='VSS(46)';
NODE_NAME     J9L2 138
 '@BASEBOARD_FAB2_LIB.BASEBOARD_FAB2(SCH_1):PAGE86_I138@MSTR_SCONN.SCONN288_H44441003(CHIPS)':
 'VSS'<47>: CDS_PINID='VSS(47)';
NODE_NAME     J9L2 136
 '@BASEBOARD_FAB2_LIB.BASEBOARD_FAB2(SCH_1):PAGE86_I138@MSTR_SCONN.SCONN288_H44441003(CHIPS)':
 'VSS'<48>: CDS_PINID='VSS(48)';
NODE_NAME     J9L2 134
 '@BASEBOARD_FAB2_LIB.BASEBOARD_FAB2(SCH_1):PAGE86_I138@MSTR_SCONN.SCONN288_H44441003(CHIPS)':
 'VSS'<49>: CDS_PINID='VSS(49)';
NODE_NAME     J9L2 131
 '@BASEBOARD_FAB2_LIB.BASEBOARD_FAB2(SCH_1):PAGE86_I138@MSTR_SCONN.SCONN288_H44441003(CHIPS)':
 'VSS'<50>: CDS_PINID='VSS(50)';
NODE_NAME     J9L2 129
 '@BASEBOARD_FAB2_LIB.BASEBOARD_FAB2(SCH_1):PAGE86_I138@MSTR_SCONN.SCONN288_H44441003(CHIPS)':
 'VSS'<51>: CDS_PINID='VSS(51)';
NODE_NAME     J9L2 127
 '@BASEBOARD_FAB2_LIB.BASEBOARD_FAB2(SCH_1):PAGE86_I138@MSTR_SCONN.SCONN288_H44441003(CHIPS)':
 'VSS'<52>: CDS_PINID='VSS(52)';
NODE_NAME     J9L2 125
 '@BASEBOARD_FAB2_LIB.BASEBOARD_FAB2(SCH_1):PAGE86_I138@MSTR_SCONN.SCONN288_H44441003(CHIPS)':
 'VSS'<53>: CDS_PINID='VSS(53)';
NODE_NAME     J9L2 123
 '@BASEBOARD_FAB2_LIB.BASEBOARD_FAB2(SCH_1):PAGE86_I138@MSTR_SCONN.SCONN288_H44441003(CHIPS)':
 'VSS'<54>: CDS_PINID='VSS(54)';
NODE_NAME     J9L2 120
 '@BASEBOARD_FAB2_LIB.BASEBOARD_FAB2(SCH_1):PAGE86_I138@MSTR_SCONN.SCONN288_H44441003(CHIPS)':
 'VSS'<55>: CDS_PINID='VSS(55)';
NODE_NAME     J9L2 118
 '@BASEBOARD_FAB2_LIB.BASEBOARD_FAB2(SCH_1):PAGE86_I138@MSTR_SCONN.SCONN288_H44441003(CHIPS)':
 'VSS'<56>: CDS_PINID='VSS(56)';
NODE_NAME     J9L2 116
 '@BASEBOARD_FAB2_LIB.BASEBOARD_FAB2(SCH_1):PAGE86_I138@MSTR_SCONN.SCONN288_H44441003(CHIPS)':
 'VSS'<57>: CDS_PINID='VSS(57)';
NODE_NAME     J9L2 114
 '@BASEBOARD_FAB2_LIB.BASEBOARD_FAB2(SCH_1):PAGE86_I138@MSTR_SCONN.SCONN288_H44441003(CHIPS)':
 'VSS'<58>: CDS_PINID='VSS(58)';
NODE_NAME     J9L2 112
 '@BASEBOARD_FAB2_LIB.BASEBOARD_FAB2(SCH_1):PAGE86_I138@MSTR_SCONN.SCONN288_H44441003(CHIPS)':
 'VSS'<59>: CDS_PINID='VSS(59)';
NODE_NAME     J9L2 109
 '@BASEBOARD_FAB2_LIB.BASEBOARD_FAB2(SCH_1):PAGE86_I138@MSTR_SCONN.SCONN288_H44441003(CHIPS)':
 'VSS'<60>: CDS_PINID='VSS(60)';
NODE_NAME     J9L2 107
 '@BASEBOARD_FAB2_LIB.BASEBOARD_FAB2(SCH_1):PAGE86_I138@MSTR_SCONN.SCONN288_H44441003(CHIPS)':
 'VSS'<61>: CDS_PINID='VSS(61)';
NODE_NAME     J9L2 105
 '@BASEBOARD_FAB2_LIB.BASEBOARD_FAB2(SCH_1):PAGE86_I138@MSTR_SCONN.SCONN288_H44441003(CHIPS)':
 'VSS'<62>: CDS_PINID='VSS(62)';
NODE_NAME     J9L2 103
 '@BASEBOARD_FAB2_LIB.BASEBOARD_FAB2(SCH_1):PAGE86_I138@MSTR_SCONN.SCONN288_H44441003(CHIPS)':
 'VSS'<63>: CDS_PINID='VSS(63)';
NODE_NAME     J9L2 101
 '@BASEBOARD_FAB2_LIB.BASEBOARD_FAB2(SCH_1):PAGE86_I138@MSTR_SCONN.SCONN288_H44441003(CHIPS)':
 'VSS'<64>: CDS_PINID='VSS(64)';
NODE_NAME     J9L2 98
 '@BASEBOARD_FAB2_LIB.BASEBOARD_FAB2(SCH_1):PAGE86_I138@MSTR_SCONN.SCONN288_H44441003(CHIPS)':
 'VSS'<65>: CDS_PINID='VSS(65)';
NODE_NAME     J9L2 96
 '@BASEBOARD_FAB2_LIB.BASEBOARD_FAB2(SCH_1):PAGE86_I138@MSTR_SCONN.SCONN288_H44441003(CHIPS)':
 'VSS'<66>: CDS_PINID='VSS(66)';
NODE_NAME     J9L2 94
 '@BASEBOARD_FAB2_LIB.BASEBOARD_FAB2(SCH_1):PAGE86_I138@MSTR_SCONN.SCONN288_H44441003(CHIPS)':
 'VSS'<67>: CDS_PINID='VSS(67)';
NODE_NAME     J9L2 57
 '@BASEBOARD_FAB2_LIB.BASEBOARD_FAB2(SCH_1):PAGE86_I138@MSTR_SCONN.SCONN288_H44441003(CHIPS)':
 'VSS'<68>: CDS_PINID='VSS(68)';
NODE_NAME     J9L2 55
 '@BASEBOARD_FAB2_LIB.BASEBOARD_FAB2(SCH_1):PAGE86_I138@MSTR_SCONN.SCONN288_H44441003(CHIPS)':
 'VSS'<69>: CDS_PINID='VSS(69)';
NODE_NAME     J9L2 53
 '@BASEBOARD_FAB2_LIB.BASEBOARD_FAB2(SCH_1):PAGE86_I138@MSTR_SCONN.SCONN288_H44441003(CHIPS)':
 'VSS'<70>: CDS_PINID='VSS(70)';
NODE_NAME     J9L2 50
 '@BASEBOARD_FAB2_LIB.BASEBOARD_FAB2(SCH_1):PAGE86_I138@MSTR_SCONN.SCONN288_H44441003(CHIPS)':
 'VSS'<71>: CDS_PINID='VSS(71)';
NODE_NAME     J9L2 48
 '@BASEBOARD_FAB2_LIB.BASEBOARD_FAB2(SCH_1):PAGE86_I138@MSTR_SCONN.SCONN288_H44441003(CHIPS)':
 'VSS'<72>: CDS_PINID='VSS(72)';
NODE_NAME     J9L2 46
 '@BASEBOARD_FAB2_LIB.BASEBOARD_FAB2(SCH_1):PAGE86_I138@MSTR_SCONN.SCONN288_H44441003(CHIPS)':
 'VSS'<73>: CDS_PINID='VSS(73)';
NODE_NAME     J9L2 44
 '@BASEBOARD_FAB2_LIB.BASEBOARD_FAB2(SCH_1):PAGE86_I138@MSTR_SCONN.SCONN288_H44441003(CHIPS)':
 'VSS'<74>: CDS_PINID='VSS(74)';
NODE_NAME     J9L2 42
 '@BASEBOARD_FAB2_LIB.BASEBOARD_FAB2(SCH_1):PAGE86_I138@MSTR_SCONN.SCONN288_H44441003(CHIPS)':
 'VSS'<75>: CDS_PINID='VSS(75)';
NODE_NAME     J9L2 39
 '@BASEBOARD_FAB2_LIB.BASEBOARD_FAB2(SCH_1):PAGE86_I138@MSTR_SCONN.SCONN288_H44441003(CHIPS)':
 'VSS'<76>: CDS_PINID='VSS(76)';
NODE_NAME     J9L2 37
 '@BASEBOARD_FAB2_LIB.BASEBOARD_FAB2(SCH_1):PAGE86_I138@MSTR_SCONN.SCONN288_H44441003(CHIPS)':
 'VSS'<77>: CDS_PINID='VSS(77)';
NODE_NAME     J9L2 35
 '@BASEBOARD_FAB2_LIB.BASEBOARD_FAB2(SCH_1):PAGE86_I138@MSTR_SCONN.SCONN288_H44441003(CHIPS)':
 'VSS'<78>: CDS_PINID='VSS(78)';
NODE_NAME     J9L2 33
 '@BASEBOARD_FAB2_LIB.BASEBOARD_FAB2(SCH_1):PAGE86_I138@MSTR_SCONN.SCONN288_H44441003(CHIPS)':
 'VSS'<79>: CDS_PINID='VSS(79)';
NODE_NAME     J9L2 31
 '@BASEBOARD_FAB2_LIB.BASEBOARD_FAB2(SCH_1):PAGE86_I138@MSTR_SCONN.SCONN288_H44441003(CHIPS)':
 'VSS'<80>: CDS_PINID='VSS(80)';
NODE_NAME     J9L2 28
 '@BASEBOARD_FAB2_LIB.BASEBOARD_FAB2(SCH_1):PAGE86_I138@MSTR_SCONN.SCONN288_H44441003(CHIPS)':
 'VSS'<81>: CDS_PINID='VSS(81)';
NODE_NAME     J9L2 26
 '@BASEBOARD_FAB2_LIB.BASEBOARD_FAB2(SCH_1):PAGE86_I138@MSTR_SCONN.SCONN288_H44441003(CHIPS)':
 'VSS'<82>: CDS_PINID='VSS(82)';
NODE_NAME     J9L2 24
 '@BASEBOARD_FAB2_LIB.BASEBOARD_FAB2(SCH_1):PAGE86_I138@MSTR_SCONN.SCONN288_H44441003(CHIPS)':
 'VSS'<83>: CDS_PINID='VSS(83)';
NODE_NAME     J9L2 22
 '@BASEBOARD_FAB2_LIB.BASEBOARD_FAB2(SCH_1):PAGE86_I138@MSTR_SCONN.SCONN288_H44441003(CHIPS)':
 'VSS'<84>: CDS_PINID='VSS(84)';
NODE_NAME     J9L2 20
 '@BASEBOARD_FAB2_LIB.BASEBOARD_FAB2(SCH_1):PAGE86_I138@MSTR_SCONN.SCONN288_H44441003(CHIPS)':
 'VSS'<85>: CDS_PINID='VSS(85)';
NODE_NAME     J9L2 17
 '@BASEBOARD_FAB2_LIB.BASEBOARD_FAB2(SCH_1):PAGE86_I138@MSTR_SCONN.SCONN288_H44441003(CHIPS)':
 'VSS'<86>: CDS_PINID='VSS(86)';
NODE_NAME     J9L2 15
 '@BASEBOARD_FAB2_LIB.BASEBOARD_FAB2(SCH_1):PAGE86_I138@MSTR_SCONN.SCONN288_H44441003(CHIPS)':
 'VSS'<87>: CDS_PINID='VSS(87)';
NODE_NAME     J9L2 13
 '@BASEBOARD_FAB2_LIB.BASEBOARD_FAB2(SCH_1):PAGE86_I138@MSTR_SCONN.SCONN288_H44441003(CHIPS)':
 'VSS'<88>: CDS_PINID='VSS(88)';
NODE_NAME     J9L2 11
 '@BASEBOARD_FAB2_LIB.BASEBOARD_FAB2(SCH_1):PAGE86_I138@MSTR_SCONN.SCONN288_H44441003(CHIPS)':
 'VSS'<89>: CDS_PINID='VSS(89)';
NODE_NAME     J9L2 9
 '@BASEBOARD_FAB2_LIB.BASEBOARD_FAB2(SCH_1):PAGE86_I138@MSTR_SCONN.SCONN288_H44441003(CHIPS)':
 'VSS'<90>: CDS_PINID='VSS(90)';
NODE_NAME     J9L2 6
 '@BASEBOARD_FAB2_LIB.BASEBOARD_FAB2(SCH_1):PAGE86_I138@MSTR_SCONN.SCONN288_H44441003(CHIPS)':
 'VSS'<91>: CDS_PINID='VSS(91)';
NODE_NAME     J9L2 4
 '@BASEBOARD_FAB2_LIB.BASEBOARD_FAB2(SCH_1):PAGE86_I138@MSTR_SCONN.SCONN288_H44441003(CHIPS)':
 'VSS'<92>: CDS_PINID='VSS(92)';
NODE_NAME     J9L2 2
 '@BASEBOARD_FAB2_LIB.BASEBOARD_FAB2(SCH_1):PAGE86_I138@MSTR_SCONN.SCONN288_H44441003(CHIPS)':
 'VSS'<93>: CDS_PINID='VSS(93)';
NODE_NAME     C1A17 2
 '@BASEBOARD_FAB2_LIB.BASEBOARD_FAB2(SCH_1):PAGE86_I182@DEV_DISCRETE.CAP_A(CHIPS)':
 'B': CDS_PINID='B';
NODE_NAME     C1A5 2
 '@BASEBOARD_FAB2_LIB.BASEBOARD_FAB2(SCH_1):PAGE87_I178@DEV_DISCRETE.CAP_A(CHIPS)':
 'B': CDS_PINID='B';
NODE_NAME     J1A1 283
 '@BASEBOARD_FAB2_LIB.BASEBOARD_FAB2(SCH_1):PAGE87_I185@MSTR_SCONN.SCONN288_H44441004(CHIPS)':
 'VSS'<0>: CDS_PINID='VSS(0)';
NODE_NAME     J1A1 281
 '@BASEBOARD_FAB2_LIB.BASEBOARD_FAB2(SCH_1):PAGE87_I185@MSTR_SCONN.SCONN288_H44441004(CHIPS)':
 'VSS'<1>: CDS_PINID='VSS(1)';
NODE_NAME     J1A1 279
 '@BASEBOARD_FAB2_LIB.BASEBOARD_FAB2(SCH_1):PAGE87_I185@MSTR_SCONN.SCONN288_H44441004(CHIPS)':
 'VSS'<2>: CDS_PINID='VSS(2)';
NODE_NAME     J1A1 276
 '@BASEBOARD_FAB2_LIB.BASEBOARD_FAB2(SCH_1):PAGE87_I185@MSTR_SCONN.SCONN288_H44441004(CHIPS)':
 'VSS'<3>: CDS_PINID='VSS(3)';
NODE_NAME     J1A1 274
 '@BASEBOARD_FAB2_LIB.BASEBOARD_FAB2(SCH_1):PAGE87_I185@MSTR_SCONN.SCONN288_H44441004(CHIPS)':
 'VSS'<4>: CDS_PINID='VSS(4)';
NODE_NAME     J1A1 272
 '@BASEBOARD_FAB2_LIB.BASEBOARD_FAB2(SCH_1):PAGE87_I185@MSTR_SCONN.SCONN288_H44441004(CHIPS)':
 'VSS'<5>: CDS_PINID='VSS(5)';
NODE_NAME     J1A1 270
 '@BASEBOARD_FAB2_LIB.BASEBOARD_FAB2(SCH_1):PAGE87_I185@MSTR_SCONN.SCONN288_H44441004(CHIPS)':
 'VSS'<6>: CDS_PINID='VSS(6)';
NODE_NAME     J1A1 268
 '@BASEBOARD_FAB2_LIB.BASEBOARD_FAB2(SCH_1):PAGE87_I185@MSTR_SCONN.SCONN288_H44441004(CHIPS)':
 'VSS'<7>: CDS_PINID='VSS(7)';
NODE_NAME     J1A1 265
 '@BASEBOARD_FAB2_LIB.BASEBOARD_FAB2(SCH_1):PAGE87_I185@MSTR_SCONN.SCONN288_H44441004(CHIPS)':
 'VSS'<8>: CDS_PINID='VSS(8)';
NODE_NAME     J1A1 263
 '@BASEBOARD_FAB2_LIB.BASEBOARD_FAB2(SCH_1):PAGE87_I185@MSTR_SCONN.SCONN288_H44441004(CHIPS)':
 'VSS'<9>: CDS_PINID='VSS(9)';
NODE_NAME     J1A1 261
 '@BASEBOARD_FAB2_LIB.BASEBOARD_FAB2(SCH_1):PAGE87_I185@MSTR_SCONN.SCONN288_H44441004(CHIPS)':
 'VSS'<10>: CDS_PINID='VSS(10)';
NODE_NAME     J1A1 259
 '@BASEBOARD_FAB2_LIB.BASEBOARD_FAB2(SCH_1):PAGE87_I185@MSTR_SCONN.SCONN288_H44441004(CHIPS)':
 'VSS'<11>: CDS_PINID='VSS(11)';
NODE_NAME     J1A1 257
 '@BASEBOARD_FAB2_LIB.BASEBOARD_FAB2(SCH_1):PAGE87_I185@MSTR_SCONN.SCONN288_H44441004(CHIPS)':
 'VSS'<12>: CDS_PINID='VSS(12)';
NODE_NAME     J1A1 254
 '@BASEBOARD_FAB2_LIB.BASEBOARD_FAB2(SCH_1):PAGE87_I185@MSTR_SCONN.SCONN288_H44441004(CHIPS)':
 'VSS'<13>: CDS_PINID='VSS(13)';
NODE_NAME     J1A1 252
 '@BASEBOARD_FAB2_LIB.BASEBOARD_FAB2(SCH_1):PAGE87_I185@MSTR_SCONN.SCONN288_H44441004(CHIPS)':
 'VSS'<14>: CDS_PINID='VSS(14)';
NODE_NAME     J1A1 250
 '@BASEBOARD_FAB2_LIB.BASEBOARD_FAB2(SCH_1):PAGE87_I185@MSTR_SCONN.SCONN288_H44441004(CHIPS)':
 'VSS'<15>: CDS_PINID='VSS(15)';
NODE_NAME     J1A1 248
 '@BASEBOARD_FAB2_LIB.BASEBOARD_FAB2(SCH_1):PAGE87_I185@MSTR_SCONN.SCONN288_H44441004(CHIPS)':
 'VSS'<16>: CDS_PINID='VSS(16)';
NODE_NAME     J1A1 246
 '@BASEBOARD_FAB2_LIB.BASEBOARD_FAB2(SCH_1):PAGE87_I185@MSTR_SCONN.SCONN288_H44441004(CHIPS)':
 'VSS'<17>: CDS_PINID='VSS(17)';
NODE_NAME     J1A1 243
 '@BASEBOARD_FAB2_LIB.BASEBOARD_FAB2(SCH_1):PAGE87_I185@MSTR_SCONN.SCONN288_H44441004(CHIPS)':
 'VSS'<18>: CDS_PINID='VSS(18)';
NODE_NAME     J1A1 241
 '@BASEBOARD_FAB2_LIB.BASEBOARD_FAB2(SCH_1):PAGE87_I185@MSTR_SCONN.SCONN288_H44441004(CHIPS)':
 'VSS'<19>: CDS_PINID='VSS(19)';
NODE_NAME     J1A1 239
 '@BASEBOARD_FAB2_LIB.BASEBOARD_FAB2(SCH_1):PAGE87_I185@MSTR_SCONN.SCONN288_H44441004(CHIPS)':
 'VSS'<20>: CDS_PINID='VSS(20)';
NODE_NAME     J1A1 202
 '@BASEBOARD_FAB2_LIB.BASEBOARD_FAB2(SCH_1):PAGE87_I185@MSTR_SCONN.SCONN288_H44441004(CHIPS)':
 'VSS'<21>: CDS_PINID='VSS(21)';
NODE_NAME     J1A1 200
 '@BASEBOARD_FAB2_LIB.BASEBOARD_FAB2(SCH_1):PAGE87_I185@MSTR_SCONN.SCONN288_H44441004(CHIPS)':
 'VSS'<22>: CDS_PINID='VSS(22)';
NODE_NAME     J1A1 198
 '@BASEBOARD_FAB2_LIB.BASEBOARD_FAB2(SCH_1):PAGE87_I185@MSTR_SCONN.SCONN288_H44441004(CHIPS)':
 'VSS'<23>: CDS_PINID='VSS(23)';
NODE_NAME     J1A1 195
 '@BASEBOARD_FAB2_LIB.BASEBOARD_FAB2(SCH_1):PAGE87_I185@MSTR_SCONN.SCONN288_H44441004(CHIPS)':
 'VSS'<24>: CDS_PINID='VSS(24)';
NODE_NAME     J1A1 193
 '@BASEBOARD_FAB2_LIB.BASEBOARD_FAB2(SCH_1):PAGE87_I185@MSTR_SCONN.SCONN288_H44441004(CHIPS)':
 'VSS'<25>: CDS_PINID='VSS(25)';
NODE_NAME     J1A1 191
 '@BASEBOARD_FAB2_LIB.BASEBOARD_FAB2(SCH_1):PAGE87_I185@MSTR_SCONN.SCONN288_H44441004(CHIPS)':
 'VSS'<26>: CDS_PINID='VSS(26)';
NODE_NAME     J1A1 189
 '@BASEBOARD_FAB2_LIB.BASEBOARD_FAB2(SCH_1):PAGE87_I185@MSTR_SCONN.SCONN288_H44441004(CHIPS)':
 'VSS'<27>: CDS_PINID='VSS(27)';
NODE_NAME     J1A1 187
 '@BASEBOARD_FAB2_LIB.BASEBOARD_FAB2(SCH_1):PAGE87_I185@MSTR_SCONN.SCONN288_H44441004(CHIPS)':
 'VSS'<28>: CDS_PINID='VSS(28)';
NODE_NAME     J1A1 184
 '@BASEBOARD_FAB2_LIB.BASEBOARD_FAB2(SCH_1):PAGE87_I185@MSTR_SCONN.SCONN288_H44441004(CHIPS)':
 'VSS'<29>: CDS_PINID='VSS(29)';
NODE_NAME     J1A1 182
 '@BASEBOARD_FAB2_LIB.BASEBOARD_FAB2(SCH_1):PAGE87_I185@MSTR_SCONN.SCONN288_H44441004(CHIPS)':
 'VSS'<30>: CDS_PINID='VSS(30)';
NODE_NAME     J1A1 180
 '@BASEBOARD_FAB2_LIB.BASEBOARD_FAB2(SCH_1):PAGE87_I185@MSTR_SCONN.SCONN288_H44441004(CHIPS)':
 'VSS'<31>: CDS_PINID='VSS(31)';
NODE_NAME     J1A1 178
 '@BASEBOARD_FAB2_LIB.BASEBOARD_FAB2(SCH_1):PAGE87_I185@MSTR_SCONN.SCONN288_H44441004(CHIPS)':
 'VSS'<32>: CDS_PINID='VSS(32)';
NODE_NAME     J1A1 176
 '@BASEBOARD_FAB2_LIB.BASEBOARD_FAB2(SCH_1):PAGE87_I185@MSTR_SCONN.SCONN288_H44441004(CHIPS)':
 'VSS'<33>: CDS_PINID='VSS(33)';
NODE_NAME     J1A1 173
 '@BASEBOARD_FAB2_LIB.BASEBOARD_FAB2(SCH_1):PAGE87_I185@MSTR_SCONN.SCONN288_H44441004(CHIPS)':
 'VSS'<34>: CDS_PINID='VSS(34)';
NODE_NAME     J1A1 171
 '@BASEBOARD_FAB2_LIB.BASEBOARD_FAB2(SCH_1):PAGE87_I185@MSTR_SCONN.SCONN288_H44441004(CHIPS)':
 'VSS'<35>: CDS_PINID='VSS(35)';
NODE_NAME     J1A1 169
 '@BASEBOARD_FAB2_LIB.BASEBOARD_FAB2(SCH_1):PAGE87_I185@MSTR_SCONN.SCONN288_H44441004(CHIPS)':
 'VSS'<36>: CDS_PINID='VSS(36)';
NODE_NAME     J1A1 167
 '@BASEBOARD_FAB2_LIB.BASEBOARD_FAB2(SCH_1):PAGE87_I185@MSTR_SCONN.SCONN288_H44441004(CHIPS)':
 'VSS'<37>: CDS_PINID='VSS(37)';
NODE_NAME     J1A1 165
 '@BASEBOARD_FAB2_LIB.BASEBOARD_FAB2(SCH_1):PAGE87_I185@MSTR_SCONN.SCONN288_H44441004(CHIPS)':
 'VSS'<38>: CDS_PINID='VSS(38)';
NODE_NAME     J1A1 162
 '@BASEBOARD_FAB2_LIB.BASEBOARD_FAB2(SCH_1):PAGE87_I185@MSTR_SCONN.SCONN288_H44441004(CHIPS)':
 'VSS'<39>: CDS_PINID='VSS(39)';
NODE_NAME     J1A1 160
 '@BASEBOARD_FAB2_LIB.BASEBOARD_FAB2(SCH_1):PAGE87_I185@MSTR_SCONN.SCONN288_H44441004(CHIPS)':
 'VSS'<40>: CDS_PINID='VSS(40)';
NODE_NAME     J1A1 158
 '@BASEBOARD_FAB2_LIB.BASEBOARD_FAB2(SCH_1):PAGE87_I185@MSTR_SCONN.SCONN288_H44441004(CHIPS)':
 'VSS'<41>: CDS_PINID='VSS(41)';
NODE_NAME     J1A1 156
 '@BASEBOARD_FAB2_LIB.BASEBOARD_FAB2(SCH_1):PAGE87_I185@MSTR_SCONN.SCONN288_H44441004(CHIPS)':
 'VSS'<42>: CDS_PINID='VSS(42)';
NODE_NAME     J1A1 154
 '@BASEBOARD_FAB2_LIB.BASEBOARD_FAB2(SCH_1):PAGE87_I185@MSTR_SCONN.SCONN288_H44441004(CHIPS)':
 'VSS'<43>: CDS_PINID='VSS(43)';
NODE_NAME     J1A1 151
 '@BASEBOARD_FAB2_LIB.BASEBOARD_FAB2(SCH_1):PAGE87_I185@MSTR_SCONN.SCONN288_H44441004(CHIPS)':
 'VSS'<44>: CDS_PINID='VSS(44)';
NODE_NAME     J1A1 149
 '@BASEBOARD_FAB2_LIB.BASEBOARD_FAB2(SCH_1):PAGE87_I185@MSTR_SCONN.SCONN288_H44441004(CHIPS)':
 'VSS'<45>: CDS_PINID='VSS(45)';
NODE_NAME     J1A1 147
 '@BASEBOARD_FAB2_LIB.BASEBOARD_FAB2(SCH_1):PAGE87_I185@MSTR_SCONN.SCONN288_H44441004(CHIPS)':
 'VSS'<46>: CDS_PINID='VSS(46)';
NODE_NAME     J1A1 138
 '@BASEBOARD_FAB2_LIB.BASEBOARD_FAB2(SCH_1):PAGE87_I185@MSTR_SCONN.SCONN288_H44441004(CHIPS)':
 'VSS'<47>: CDS_PINID='VSS(47)';
NODE_NAME     J1A1 136
 '@BASEBOARD_FAB2_LIB.BASEBOARD_FAB2(SCH_1):PAGE87_I185@MSTR_SCONN.SCONN288_H44441004(CHIPS)':
 'VSS'<48>: CDS_PINID='VSS(48)';
NODE_NAME     J1A1 134
 '@BASEBOARD_FAB2_LIB.BASEBOARD_FAB2(SCH_1):PAGE87_I185@MSTR_SCONN.SCONN288_H44441004(CHIPS)':
 'VSS'<49>: CDS_PINID='VSS(49)';
NODE_NAME     J1A1 131
 '@BASEBOARD_FAB2_LIB.BASEBOARD_FAB2(SCH_1):PAGE87_I185@MSTR_SCONN.SCONN288_H44441004(CHIPS)':
 'VSS'<50>: CDS_PINID='VSS(50)';
NODE_NAME     J1A1 129
 '@BASEBOARD_FAB2_LIB.BASEBOARD_FAB2(SCH_1):PAGE87_I185@MSTR_SCONN.SCONN288_H44441004(CHIPS)':
 'VSS'<51>: CDS_PINID='VSS(51)';
NODE_NAME     J1A1 127
 '@BASEBOARD_FAB2_LIB.BASEBOARD_FAB2(SCH_1):PAGE87_I185@MSTR_SCONN.SCONN288_H44441004(CHIPS)':
 'VSS'<52>: CDS_PINID='VSS(52)';
NODE_NAME     J1A1 125
 '@BASEBOARD_FAB2_LIB.BASEBOARD_FAB2(SCH_1):PAGE87_I185@MSTR_SCONN.SCONN288_H44441004(CHIPS)':
 'VSS'<53>: CDS_PINID='VSS(53)';
NODE_NAME     J1A1 123
 '@BASEBOARD_FAB2_LIB.BASEBOARD_FAB2(SCH_1):PAGE87_I185@MSTR_SCONN.SCONN288_H44441004(CHIPS)':
 'VSS'<54>: CDS_PINID='VSS(54)';
NODE_NAME     J1A1 120
 '@BASEBOARD_FAB2_LIB.BASEBOARD_FAB2(SCH_1):PAGE87_I185@MSTR_SCONN.SCONN288_H44441004(CHIPS)':
 'VSS'<55>: CDS_PINID='VSS(55)';
NODE_NAME     J1A1 118
 '@BASEBOARD_FAB2_LIB.BASEBOARD_FAB2(SCH_1):PAGE87_I185@MSTR_SCONN.SCONN288_H44441004(CHIPS)':
 'VSS'<56>: CDS_PINID='VSS(56)';
NODE_NAME     J1A1 116
 '@BASEBOARD_FAB2_LIB.BASEBOARD_FAB2(SCH_1):PAGE87_I185@MSTR_SCONN.SCONN288_H44441004(CHIPS)':
 'VSS'<57>: CDS_PINID='VSS(57)';
NODE_NAME     J1A1 114
 '@BASEBOARD_FAB2_LIB.BASEBOARD_FAB2(SCH_1):PAGE87_I185@MSTR_SCONN.SCONN288_H44441004(CHIPS)':
 'VSS'<58>: CDS_PINID='VSS(58)';
NODE_NAME     J1A1 112
 '@BASEBOARD_FAB2_LIB.BASEBOARD_FAB2(SCH_1):PAGE87_I185@MSTR_SCONN.SCONN288_H44441004(CHIPS)':
 'VSS'<59>: CDS_PINID='VSS(59)';
NODE_NAME     J1A1 109
 '@BASEBOARD_FAB2_LIB.BASEBOARD_FAB2(SCH_1):PAGE87_I185@MSTR_SCONN.SCONN288_H44441004(CHIPS)':
 'VSS'<60>: CDS_PINID='VSS(60)';
NODE_NAME     J1A1 107
 '@BASEBOARD_FAB2_LIB.BASEBOARD_FAB2(SCH_1):PAGE87_I185@MSTR_SCONN.SCONN288_H44441004(CHIPS)':
 'VSS'<61>: CDS_PINID='VSS(61)';
NODE_NAME     J1A1 105
 '@BASEBOARD_FAB2_LIB.BASEBOARD_FAB2(SCH_1):PAGE87_I185@MSTR_SCONN.SCONN288_H44441004(CHIPS)':
 'VSS'<62>: CDS_PINID='VSS(62)';
NODE_NAME     J1A1 103
 '@BASEBOARD_FAB2_LIB.BASEBOARD_FAB2(SCH_1):PAGE87_I185@MSTR_SCONN.SCONN288_H44441004(CHIPS)':
 'VSS'<63>: CDS_PINID='VSS(63)';
NODE_NAME     J1A1 101
 '@BASEBOARD_FAB2_LIB.BASEBOARD_FAB2(SCH_1):PAGE87_I185@MSTR_SCONN.SCONN288_H44441004(CHIPS)':
 'VSS'<64>: CDS_PINID='VSS(64)';
NODE_NAME     J1A1 98
 '@BASEBOARD_FAB2_LIB.BASEBOARD_FAB2(SCH_1):PAGE87_I185@MSTR_SCONN.SCONN288_H44441004(CHIPS)':
 'VSS'<65>: CDS_PINID='VSS(65)';
NODE_NAME     J1A1 96
 '@BASEBOARD_FAB2_LIB.BASEBOARD_FAB2(SCH_1):PAGE87_I185@MSTR_SCONN.SCONN288_H44441004(CHIPS)':
 'VSS'<66>: CDS_PINID='VSS(66)';
NODE_NAME     J1A1 94
 '@BASEBOARD_FAB2_LIB.BASEBOARD_FAB2(SCH_1):PAGE87_I185@MSTR_SCONN.SCONN288_H44441004(CHIPS)':
 'VSS'<67>: CDS_PINID='VSS(67)';
NODE_NAME     J1A1 57
 '@BASEBOARD_FAB2_LIB.BASEBOARD_FAB2(SCH_1):PAGE87_I185@MSTR_SCONN.SCONN288_H44441004(CHIPS)':
 'VSS'<68>: CDS_PINID='VSS(68)';
NODE_NAME     J1A1 55
 '@BASEBOARD_FAB2_LIB.BASEBOARD_FAB2(SCH_1):PAGE87_I185@MSTR_SCONN.SCONN288_H44441004(CHIPS)':
 'VSS'<69>: CDS_PINID='VSS(69)';
NODE_NAME     J1A1 53
 '@BASEBOARD_FAB2_LIB.BASEBOARD_FAB2(SCH_1):PAGE87_I185@MSTR_SCONN.SCONN288_H44441004(CHIPS)':
 'VSS'<70>: CDS_PINID='VSS(70)';
NODE_NAME     J1A1 50
 '@BASEBOARD_FAB2_LIB.BASEBOARD_FAB2(SCH_1):PAGE87_I185@MSTR_SCONN.SCONN288_H44441004(CHIPS)':
 'VSS'<71>: CDS_PINID='VSS(71)';
NODE_NAME     J1A1 48
 '@BASEBOARD_FAB2_LIB.BASEBOARD_FAB2(SCH_1):PAGE87_I185@MSTR_SCONN.SCONN288_H44441004(CHIPS)':
 'VSS'<72>: CDS_PINID='VSS(72)';
NODE_NAME     J1A1 46
 '@BASEBOARD_FAB2_LIB.BASEBOARD_FAB2(SCH_1):PAGE87_I185@MSTR_SCONN.SCONN288_H44441004(CHIPS)':
 'VSS'<73>: CDS_PINID='VSS(73)';
NODE_NAME     J1A1 44
 '@BASEBOARD_FAB2_LIB.BASEBOARD_FAB2(SCH_1):PAGE87_I185@MSTR_SCONN.SCONN288_H44441004(CHIPS)':
 'VSS'<74>: CDS_PINID='VSS(74)';
NODE_NAME     J1A1 42
 '@BASEBOARD_FAB2_LIB.BASEBOARD_FAB2(SCH_1):PAGE87_I185@MSTR_SCONN.SCONN288_H44441004(CHIPS)':
 'VSS'<75>: CDS_PINID='VSS(75)';
NODE_NAME     J1A1 39
 '@BASEBOARD_FAB2_LIB.BASEBOARD_FAB2(SCH_1):PAGE87_I185@MSTR_SCONN.SCONN288_H44441004(CHIPS)':
 'VSS'<76>: CDS_PINID='VSS(76)';
NODE_NAME     J1A1 37
 '@BASEBOARD_FAB2_LIB.BASEBOARD_FAB2(SCH_1):PAGE87_I185@MSTR_SCONN.SCONN288_H44441004(CHIPS)':
 'VSS'<77>: CDS_PINID='VSS(77)';
NODE_NAME     J1A1 35
 '@BASEBOARD_FAB2_LIB.BASEBOARD_FAB2(SCH_1):PAGE87_I185@MSTR_SCONN.SCONN288_H44441004(CHIPS)':
 'VSS'<78>: CDS_PINID='VSS(78)';
NODE_NAME     J1A1 33
 '@BASEBOARD_FAB2_LIB.BASEBOARD_FAB2(SCH_1):PAGE87_I185@MSTR_SCONN.SCONN288_H44441004(CHIPS)':
 'VSS'<79>: CDS_PINID='VSS(79)';
NODE_NAME     J1A1 31
 '@BASEBOARD_FAB2_LIB.BASEBOARD_FAB2(SCH_1):PAGE87_I185@MSTR_SCONN.SCONN288_H44441004(CHIPS)':
 'VSS'<80>: CDS_PINID='VSS(80)';
NODE_NAME     J1A1 28
 '@BASEBOARD_FAB2_LIB.BASEBOARD_FAB2(SCH_1):PAGE87_I185@MSTR_SCONN.SCONN288_H44441004(CHIPS)':
 'VSS'<81>: CDS_PINID='VSS(81)';
NODE_NAME     J1A1 26
 '@BASEBOARD_FAB2_LIB.BASEBOARD_FAB2(SCH_1):PAGE87_I185@MSTR_SCONN.SCONN288_H44441004(CHIPS)':
 'VSS'<82>: CDS_PINID='VSS(82)';
NODE_NAME     J1A1 24
 '@BASEBOARD_FAB2_LIB.BASEBOARD_FAB2(SCH_1):PAGE87_I185@MSTR_SCONN.SCONN288_H44441004(CHIPS)':
 'VSS'<83>: CDS_PINID='VSS(83)';
NODE_NAME     J1A1 22
 '@BASEBOARD_FAB2_LIB.BASEBOARD_FAB2(SCH_1):PAGE87_I185@MSTR_SCONN.SCONN288_H44441004(CHIPS)':
 'VSS'<84>: CDS_PINID='VSS(84)';
NODE_NAME     J1A1 20
 '@BASEBOARD_FAB2_LIB.BASEBOARD_FAB2(SCH_1):PAGE87_I185@MSTR_SCONN.SCONN288_H44441004(CHIPS)':
 'VSS'<85>: CDS_PINID='VSS(85)';
NODE_NAME     J1A1 17
 '@BASEBOARD_FAB2_LIB.BASEBOARD_FAB2(SCH_1):PAGE87_I185@MSTR_SCONN.SCONN288_H44441004(CHIPS)':
 'VSS'<86>: CDS_PINID='VSS(86)';
NODE_NAME     J1A1 15
 '@BASEBOARD_FAB2_LIB.BASEBOARD_FAB2(SCH_1):PAGE87_I185@MSTR_SCONN.SCONN288_H44441004(CHIPS)':
 'VSS'<87>: CDS_PINID='VSS(87)';
NODE_NAME     J1A1 13
 '@BASEBOARD_FAB2_LIB.BASEBOARD_FAB2(SCH_1):PAGE87_I185@MSTR_SCONN.SCONN288_H44441004(CHIPS)':
 'VSS'<88>: CDS_PINID='VSS(88)';
NODE_NAME     J1A1 11
 '@BASEBOARD_FAB2_LIB.BASEBOARD_FAB2(SCH_1):PAGE87_I185@MSTR_SCONN.SCONN288_H44441004(CHIPS)':
 'VSS'<89>: CDS_PINID='VSS(89)';
NODE_NAME     J1A1 9
 '@BASEBOARD_FAB2_LIB.BASEBOARD_FAB2(SCH_1):PAGE87_I185@MSTR_SCONN.SCONN288_H44441004(CHIPS)':
 'VSS'<90>: CDS_PINID='VSS(90)';
NODE_NAME     J1A1 6
 '@BASEBOARD_FAB2_LIB.BASEBOARD_FAB2(SCH_1):PAGE87_I185@MSTR_SCONN.SCONN288_H44441004(CHIPS)':
 'VSS'<91>: CDS_PINID='VSS(91)';
NODE_NAME     J1A1 4
 '@BASEBOARD_FAB2_LIB.BASEBOARD_FAB2(SCH_1):PAGE87_I185@MSTR_SCONN.SCONN288_H44441004(CHIPS)':
 'VSS'<92>: CDS_PINID='VSS(92)';
NODE_NAME     J1A1 2
 '@BASEBOARD_FAB2_LIB.BASEBOARD_FAB2(SCH_1):PAGE87_I185@MSTR_SCONN.SCONN288_H44441004(CHIPS)':
 'VSS'<93>: CDS_PINID='VSS(93)';
NODE_NAME     J1A1 139
 '@BASEBOARD_FAB2_LIB.BASEBOARD_FAB2(SCH_1):PAGE87_I186@MSTR_SCONN.SCONN288_H44441004(CHIPS)':
 'SA'<0>: CDS_PINID='SA(0)';
NODE_NAME     J1A1 140
 '@BASEBOARD_FAB2_LIB.BASEBOARD_FAB2(SCH_1):PAGE87_I186@MSTR_SCONN.SCONN288_H44441004(CHIPS)':
 'SA'<1>: CDS_PINID='SA(1)';
NODE_NAME     J9L1 283
 '@BASEBOARD_FAB2_LIB.BASEBOARD_FAB2(SCH_1):PAGE88_I25@MSTR_SCONN.SCONN288_H44441003(CHIPS)':
 'VSS'<0>: CDS_PINID='VSS(0)';
NODE_NAME     J9L1 281
 '@BASEBOARD_FAB2_LIB.BASEBOARD_FAB2(SCH_1):PAGE88_I25@MSTR_SCONN.SCONN288_H44441003(CHIPS)':
 'VSS'<1>: CDS_PINID='VSS(1)';
NODE_NAME     J9L1 279
 '@BASEBOARD_FAB2_LIB.BASEBOARD_FAB2(SCH_1):PAGE88_I25@MSTR_SCONN.SCONN288_H44441003(CHIPS)':
 'VSS'<2>: CDS_PINID='VSS(2)';
NODE_NAME     J9L1 276
 '@BASEBOARD_FAB2_LIB.BASEBOARD_FAB2(SCH_1):PAGE88_I25@MSTR_SCONN.SCONN288_H44441003(CHIPS)':
 'VSS'<3>: CDS_PINID='VSS(3)';
NODE_NAME     J9L1 274
 '@BASEBOARD_FAB2_LIB.BASEBOARD_FAB2(SCH_1):PAGE88_I25@MSTR_SCONN.SCONN288_H44441003(CHIPS)':
 'VSS'<4>: CDS_PINID='VSS(4)';
NODE_NAME     J9L1 272
 '@BASEBOARD_FAB2_LIB.BASEBOARD_FAB2(SCH_1):PAGE88_I25@MSTR_SCONN.SCONN288_H44441003(CHIPS)':
 'VSS'<5>: CDS_PINID='VSS(5)';
NODE_NAME     J9L1 270
 '@BASEBOARD_FAB2_LIB.BASEBOARD_FAB2(SCH_1):PAGE88_I25@MSTR_SCONN.SCONN288_H44441003(CHIPS)':
 'VSS'<6>: CDS_PINID='VSS(6)';
NODE_NAME     J9L1 268
 '@BASEBOARD_FAB2_LIB.BASEBOARD_FAB2(SCH_1):PAGE88_I25@MSTR_SCONN.SCONN288_H44441003(CHIPS)':
 'VSS'<7>: CDS_PINID='VSS(7)';
NODE_NAME     J9L1 265
 '@BASEBOARD_FAB2_LIB.BASEBOARD_FAB2(SCH_1):PAGE88_I25@MSTR_SCONN.SCONN288_H44441003(CHIPS)':
 'VSS'<8>: CDS_PINID='VSS(8)';
NODE_NAME     J9L1 263
 '@BASEBOARD_FAB2_LIB.BASEBOARD_FAB2(SCH_1):PAGE88_I25@MSTR_SCONN.SCONN288_H44441003(CHIPS)':
 'VSS'<9>: CDS_PINID='VSS(9)';
NODE_NAME     J9L1 261
 '@BASEBOARD_FAB2_LIB.BASEBOARD_FAB2(SCH_1):PAGE88_I25@MSTR_SCONN.SCONN288_H44441003(CHIPS)':
 'VSS'<10>: CDS_PINID='VSS(10)';
NODE_NAME     J9L1 259
 '@BASEBOARD_FAB2_LIB.BASEBOARD_FAB2(SCH_1):PAGE88_I25@MSTR_SCONN.SCONN288_H44441003(CHIPS)':
 'VSS'<11>: CDS_PINID='VSS(11)';
NODE_NAME     J9L1 257
 '@BASEBOARD_FAB2_LIB.BASEBOARD_FAB2(SCH_1):PAGE88_I25@MSTR_SCONN.SCONN288_H44441003(CHIPS)':
 'VSS'<12>: CDS_PINID='VSS(12)';
NODE_NAME     J9L1 254
 '@BASEBOARD_FAB2_LIB.BASEBOARD_FAB2(SCH_1):PAGE88_I25@MSTR_SCONN.SCONN288_H44441003(CHIPS)':
 'VSS'<13>: CDS_PINID='VSS(13)';
NODE_NAME     J9L1 252
 '@BASEBOARD_FAB2_LIB.BASEBOARD_FAB2(SCH_1):PAGE88_I25@MSTR_SCONN.SCONN288_H44441003(CHIPS)':
 'VSS'<14>: CDS_PINID='VSS(14)';
NODE_NAME     J9L1 250
 '@BASEBOARD_FAB2_LIB.BASEBOARD_FAB2(SCH_1):PAGE88_I25@MSTR_SCONN.SCONN288_H44441003(CHIPS)':
 'VSS'<15>: CDS_PINID='VSS(15)';
NODE_NAME     J9L1 248
 '@BASEBOARD_FAB2_LIB.BASEBOARD_FAB2(SCH_1):PAGE88_I25@MSTR_SCONN.SCONN288_H44441003(CHIPS)':
 'VSS'<16>: CDS_PINID='VSS(16)';
NODE_NAME     J9L1 246
 '@BASEBOARD_FAB2_LIB.BASEBOARD_FAB2(SCH_1):PAGE88_I25@MSTR_SCONN.SCONN288_H44441003(CHIPS)':
 'VSS'<17>: CDS_PINID='VSS(17)';
NODE_NAME     J9L1 243
 '@BASEBOARD_FAB2_LIB.BASEBOARD_FAB2(SCH_1):PAGE88_I25@MSTR_SCONN.SCONN288_H44441003(CHIPS)':
 'VSS'<18>: CDS_PINID='VSS(18)';
NODE_NAME     J9L1 241
 '@BASEBOARD_FAB2_LIB.BASEBOARD_FAB2(SCH_1):PAGE88_I25@MSTR_SCONN.SCONN288_H44441003(CHIPS)':
 'VSS'<19>: CDS_PINID='VSS(19)';
NODE_NAME     J9L1 239
 '@BASEBOARD_FAB2_LIB.BASEBOARD_FAB2(SCH_1):PAGE88_I25@MSTR_SCONN.SCONN288_H44441003(CHIPS)':
 'VSS'<20>: CDS_PINID='VSS(20)';
NODE_NAME     J9L1 202
 '@BASEBOARD_FAB2_LIB.BASEBOARD_FAB2(SCH_1):PAGE88_I25@MSTR_SCONN.SCONN288_H44441003(CHIPS)':
 'VSS'<21>: CDS_PINID='VSS(21)';
NODE_NAME     J9L1 200
 '@BASEBOARD_FAB2_LIB.BASEBOARD_FAB2(SCH_1):PAGE88_I25@MSTR_SCONN.SCONN288_H44441003(CHIPS)':
 'VSS'<22>: CDS_PINID='VSS(22)';
NODE_NAME     J9L1 198
 '@BASEBOARD_FAB2_LIB.BASEBOARD_FAB2(SCH_1):PAGE88_I25@MSTR_SCONN.SCONN288_H44441003(CHIPS)':
 'VSS'<23>: CDS_PINID='VSS(23)';
NODE_NAME     J9L1 195
 '@BASEBOARD_FAB2_LIB.BASEBOARD_FAB2(SCH_1):PAGE88_I25@MSTR_SCONN.SCONN288_H44441003(CHIPS)':
 'VSS'<24>: CDS_PINID='VSS(24)';
NODE_NAME     J9L1 193
 '@BASEBOARD_FAB2_LIB.BASEBOARD_FAB2(SCH_1):PAGE88_I25@MSTR_SCONN.SCONN288_H44441003(CHIPS)':
 'VSS'<25>: CDS_PINID='VSS(25)';
NODE_NAME     J9L1 191
 '@BASEBOARD_FAB2_LIB.BASEBOARD_FAB2(SCH_1):PAGE88_I25@MSTR_SCONN.SCONN288_H44441003(CHIPS)':
 'VSS'<26>: CDS_PINID='VSS(26)';
NODE_NAME     J9L1 189
 '@BASEBOARD_FAB2_LIB.BASEBOARD_FAB2(SCH_1):PAGE88_I25@MSTR_SCONN.SCONN288_H44441003(CHIPS)':
 'VSS'<27>: CDS_PINID='VSS(27)';
NODE_NAME     J9L1 187
 '@BASEBOARD_FAB2_LIB.BASEBOARD_FAB2(SCH_1):PAGE88_I25@MSTR_SCONN.SCONN288_H44441003(CHIPS)':
 'VSS'<28>: CDS_PINID='VSS(28)';
NODE_NAME     J9L1 184
 '@BASEBOARD_FAB2_LIB.BASEBOARD_FAB2(SCH_1):PAGE88_I25@MSTR_SCONN.SCONN288_H44441003(CHIPS)':
 'VSS'<29>: CDS_PINID='VSS(29)';
NODE_NAME     J9L1 182
 '@BASEBOARD_FAB2_LIB.BASEBOARD_FAB2(SCH_1):PAGE88_I25@MSTR_SCONN.SCONN288_H44441003(CHIPS)':
 'VSS'<30>: CDS_PINID='VSS(30)';
NODE_NAME     J9L1 180
 '@BASEBOARD_FAB2_LIB.BASEBOARD_FAB2(SCH_1):PAGE88_I25@MSTR_SCONN.SCONN288_H44441003(CHIPS)':
 'VSS'<31>: CDS_PINID='VSS(31)';
NODE_NAME     J9L1 178
 '@BASEBOARD_FAB2_LIB.BASEBOARD_FAB2(SCH_1):PAGE88_I25@MSTR_SCONN.SCONN288_H44441003(CHIPS)':
 'VSS'<32>: CDS_PINID='VSS(32)';
NODE_NAME     J9L1 176
 '@BASEBOARD_FAB2_LIB.BASEBOARD_FAB2(SCH_1):PAGE88_I25@MSTR_SCONN.SCONN288_H44441003(CHIPS)':
 'VSS'<33>: CDS_PINID='VSS(33)';
NODE_NAME     J9L1 173
 '@BASEBOARD_FAB2_LIB.BASEBOARD_FAB2(SCH_1):PAGE88_I25@MSTR_SCONN.SCONN288_H44441003(CHIPS)':
 'VSS'<34>: CDS_PINID='VSS(34)';
NODE_NAME     J9L1 171
 '@BASEBOARD_FAB2_LIB.BASEBOARD_FAB2(SCH_1):PAGE88_I25@MSTR_SCONN.SCONN288_H44441003(CHIPS)':
 'VSS'<35>: CDS_PINID='VSS(35)';
NODE_NAME     J9L1 169
 '@BASEBOARD_FAB2_LIB.BASEBOARD_FAB2(SCH_1):PAGE88_I25@MSTR_SCONN.SCONN288_H44441003(CHIPS)':
 'VSS'<36>: CDS_PINID='VSS(36)';
NODE_NAME     J9L1 167
 '@BASEBOARD_FAB2_LIB.BASEBOARD_FAB2(SCH_1):PAGE88_I25@MSTR_SCONN.SCONN288_H44441003(CHIPS)':
 'VSS'<37>: CDS_PINID='VSS(37)';
NODE_NAME     J9L1 165
 '@BASEBOARD_FAB2_LIB.BASEBOARD_FAB2(SCH_1):PAGE88_I25@MSTR_SCONN.SCONN288_H44441003(CHIPS)':
 'VSS'<38>: CDS_PINID='VSS(38)';
NODE_NAME     J9L1 162
 '@BASEBOARD_FAB2_LIB.BASEBOARD_FAB2(SCH_1):PAGE88_I25@MSTR_SCONN.SCONN288_H44441003(CHIPS)':
 'VSS'<39>: CDS_PINID='VSS(39)';
NODE_NAME     J9L1 160
 '@BASEBOARD_FAB2_LIB.BASEBOARD_FAB2(SCH_1):PAGE88_I25@MSTR_SCONN.SCONN288_H44441003(CHIPS)':
 'VSS'<40>: CDS_PINID='VSS(40)';
NODE_NAME     J9L1 158
 '@BASEBOARD_FAB2_LIB.BASEBOARD_FAB2(SCH_1):PAGE88_I25@MSTR_SCONN.SCONN288_H44441003(CHIPS)':
 'VSS'<41>: CDS_PINID='VSS(41)';
NODE_NAME     J9L1 156
 '@BASEBOARD_FAB2_LIB.BASEBOARD_FAB2(SCH_1):PAGE88_I25@MSTR_SCONN.SCONN288_H44441003(CHIPS)':
 'VSS'<42>: CDS_PINID='VSS(42)';
NODE_NAME     J9L1 154
 '@BASEBOARD_FAB2_LIB.BASEBOARD_FAB2(SCH_1):PAGE88_I25@MSTR_SCONN.SCONN288_H44441003(CHIPS)':
 'VSS'<43>: CDS_PINID='VSS(43)';
NODE_NAME     J9L1 151
 '@BASEBOARD_FAB2_LIB.BASEBOARD_FAB2(SCH_1):PAGE88_I25@MSTR_SCONN.SCONN288_H44441003(CHIPS)':
 'VSS'<44>: CDS_PINID='VSS(44)';
NODE_NAME     J9L1 149
 '@BASEBOARD_FAB2_LIB.BASEBOARD_FAB2(SCH_1):PAGE88_I25@MSTR_SCONN.SCONN288_H44441003(CHIPS)':
 'VSS'<45>: CDS_PINID='VSS(45)';
NODE_NAME     J9L1 147
 '@BASEBOARD_FAB2_LIB.BASEBOARD_FAB2(SCH_1):PAGE88_I25@MSTR_SCONN.SCONN288_H44441003(CHIPS)':
 'VSS'<46>: CDS_PINID='VSS(46)';
NODE_NAME     J9L1 138
 '@BASEBOARD_FAB2_LIB.BASEBOARD_FAB2(SCH_1):PAGE88_I25@MSTR_SCONN.SCONN288_H44441003(CHIPS)':
 'VSS'<47>: CDS_PINID='VSS(47)';
NODE_NAME     J9L1 136
 '@BASEBOARD_FAB2_LIB.BASEBOARD_FAB2(SCH_1):PAGE88_I25@MSTR_SCONN.SCONN288_H44441003(CHIPS)':
 'VSS'<48>: CDS_PINID='VSS(48)';
NODE_NAME     J9L1 134
 '@BASEBOARD_FAB2_LIB.BASEBOARD_FAB2(SCH_1):PAGE88_I25@MSTR_SCONN.SCONN288_H44441003(CHIPS)':
 'VSS'<49>: CDS_PINID='VSS(49)';
NODE_NAME     J9L1 131
 '@BASEBOARD_FAB2_LIB.BASEBOARD_FAB2(SCH_1):PAGE88_I25@MSTR_SCONN.SCONN288_H44441003(CHIPS)':
 'VSS'<50>: CDS_PINID='VSS(50)';
NODE_NAME     J9L1 129
 '@BASEBOARD_FAB2_LIB.BASEBOARD_FAB2(SCH_1):PAGE88_I25@MSTR_SCONN.SCONN288_H44441003(CHIPS)':
 'VSS'<51>: CDS_PINID='VSS(51)';
NODE_NAME     J9L1 127
 '@BASEBOARD_FAB2_LIB.BASEBOARD_FAB2(SCH_1):PAGE88_I25@MSTR_SCONN.SCONN288_H44441003(CHIPS)':
 'VSS'<52>: CDS_PINID='VSS(52)';
NODE_NAME     J9L1 125
 '@BASEBOARD_FAB2_LIB.BASEBOARD_FAB2(SCH_1):PAGE88_I25@MSTR_SCONN.SCONN288_H44441003(CHIPS)':
 'VSS'<53>: CDS_PINID='VSS(53)';
NODE_NAME     J9L1 123
 '@BASEBOARD_FAB2_LIB.BASEBOARD_FAB2(SCH_1):PAGE88_I25@MSTR_SCONN.SCONN288_H44441003(CHIPS)':
 'VSS'<54>: CDS_PINID='VSS(54)';
NODE_NAME     J9L1 120
 '@BASEBOARD_FAB2_LIB.BASEBOARD_FAB2(SCH_1):PAGE88_I25@MSTR_SCONN.SCONN288_H44441003(CHIPS)':
 'VSS'<55>: CDS_PINID='VSS(55)';
NODE_NAME     J9L1 118
 '@BASEBOARD_FAB2_LIB.BASEBOARD_FAB2(SCH_1):PAGE88_I25@MSTR_SCONN.SCONN288_H44441003(CHIPS)':
 'VSS'<56>: CDS_PINID='VSS(56)';
NODE_NAME     J9L1 116
 '@BASEBOARD_FAB2_LIB.BASEBOARD_FAB2(SCH_1):PAGE88_I25@MSTR_SCONN.SCONN288_H44441003(CHIPS)':
 'VSS'<57>: CDS_PINID='VSS(57)';
NODE_NAME     J9L1 114
 '@BASEBOARD_FAB2_LIB.BASEBOARD_FAB2(SCH_1):PAGE88_I25@MSTR_SCONN.SCONN288_H44441003(CHIPS)':
 'VSS'<58>: CDS_PINID='VSS(58)';
NODE_NAME     J9L1 112
 '@BASEBOARD_FAB2_LIB.BASEBOARD_FAB2(SCH_1):PAGE88_I25@MSTR_SCONN.SCONN288_H44441003(CHIPS)':
 'VSS'<59>: CDS_PINID='VSS(59)';
NODE_NAME     J9L1 109
 '@BASEBOARD_FAB2_LIB.BASEBOARD_FAB2(SCH_1):PAGE88_I25@MSTR_SCONN.SCONN288_H44441003(CHIPS)':
 'VSS'<60>: CDS_PINID='VSS(60)';
NODE_NAME     J9L1 107
 '@BASEBOARD_FAB2_LIB.BASEBOARD_FAB2(SCH_1):PAGE88_I25@MSTR_SCONN.SCONN288_H44441003(CHIPS)':
 'VSS'<61>: CDS_PINID='VSS(61)';
NODE_NAME     J9L1 105
 '@BASEBOARD_FAB2_LIB.BASEBOARD_FAB2(SCH_1):PAGE88_I25@MSTR_SCONN.SCONN288_H44441003(CHIPS)':
 'VSS'<62>: CDS_PINID='VSS(62)';
NODE_NAME     J9L1 103
 '@BASEBOARD_FAB2_LIB.BASEBOARD_FAB2(SCH_1):PAGE88_I25@MSTR_SCONN.SCONN288_H44441003(CHIPS)':
 'VSS'<63>: CDS_PINID='VSS(63)';
NODE_NAME     J9L1 101
 '@BASEBOARD_FAB2_LIB.BASEBOARD_FAB2(SCH_1):PAGE88_I25@MSTR_SCONN.SCONN288_H44441003(CHIPS)':
 'VSS'<64>: CDS_PINID='VSS(64)';
NODE_NAME     J9L1 98
 '@BASEBOARD_FAB2_LIB.BASEBOARD_FAB2(SCH_1):PAGE88_I25@MSTR_SCONN.SCONN288_H44441003(CHIPS)':
 'VSS'<65>: CDS_PINID='VSS(65)';
NODE_NAME     J9L1 96
 '@BASEBOARD_FAB2_LIB.BASEBOARD_FAB2(SCH_1):PAGE88_I25@MSTR_SCONN.SCONN288_H44441003(CHIPS)':
 'VSS'<66>: CDS_PINID='VSS(66)';
NODE_NAME     J9L1 94
 '@BASEBOARD_FAB2_LIB.BASEBOARD_FAB2(SCH_1):PAGE88_I25@MSTR_SCONN.SCONN288_H44441003(CHIPS)':
 'VSS'<67>: CDS_PINID='VSS(67)';
NODE_NAME     J9L1 57
 '@BASEBOARD_FAB2_LIB.BASEBOARD_FAB2(SCH_1):PAGE88_I25@MSTR_SCONN.SCONN288_H44441003(CHIPS)':
 'VSS'<68>: CDS_PINID='VSS(68)';
NODE_NAME     J9L1 55
 '@BASEBOARD_FAB2_LIB.BASEBOARD_FAB2(SCH_1):PAGE88_I25@MSTR_SCONN.SCONN288_H44441003(CHIPS)':
 'VSS'<69>: CDS_PINID='VSS(69)';
NODE_NAME     J9L1 53
 '@BASEBOARD_FAB2_LIB.BASEBOARD_FAB2(SCH_1):PAGE88_I25@MSTR_SCONN.SCONN288_H44441003(CHIPS)':
 'VSS'<70>: CDS_PINID='VSS(70)';
NODE_NAME     J9L1 50
 '@BASEBOARD_FAB2_LIB.BASEBOARD_FAB2(SCH_1):PAGE88_I25@MSTR_SCONN.SCONN288_H44441003(CHIPS)':
 'VSS'<71>: CDS_PINID='VSS(71)';
NODE_NAME     J9L1 48
 '@BASEBOARD_FAB2_LIB.BASEBOARD_FAB2(SCH_1):PAGE88_I25@MSTR_SCONN.SCONN288_H44441003(CHIPS)':
 'VSS'<72>: CDS_PINID='VSS(72)';
NODE_NAME     J9L1 46
 '@BASEBOARD_FAB2_LIB.BASEBOARD_FAB2(SCH_1):PAGE88_I25@MSTR_SCONN.SCONN288_H44441003(CHIPS)':
 'VSS'<73>: CDS_PINID='VSS(73)';
NODE_NAME     J9L1 44
 '@BASEBOARD_FAB2_LIB.BASEBOARD_FAB2(SCH_1):PAGE88_I25@MSTR_SCONN.SCONN288_H44441003(CHIPS)':
 'VSS'<74>: CDS_PINID='VSS(74)';
NODE_NAME     J9L1 42
 '@BASEBOARD_FAB2_LIB.BASEBOARD_FAB2(SCH_1):PAGE88_I25@MSTR_SCONN.SCONN288_H44441003(CHIPS)':
 'VSS'<75>: CDS_PINID='VSS(75)';
NODE_NAME     J9L1 39
 '@BASEBOARD_FAB2_LIB.BASEBOARD_FAB2(SCH_1):PAGE88_I25@MSTR_SCONN.SCONN288_H44441003(CHIPS)':
 'VSS'<76>: CDS_PINID='VSS(76)';
NODE_NAME     J9L1 37
 '@BASEBOARD_FAB2_LIB.BASEBOARD_FAB2(SCH_1):PAGE88_I25@MSTR_SCONN.SCONN288_H44441003(CHIPS)':
 'VSS'<77>: CDS_PINID='VSS(77)';
NODE_NAME     J9L1 35
 '@BASEBOARD_FAB2_LIB.BASEBOARD_FAB2(SCH_1):PAGE88_I25@MSTR_SCONN.SCONN288_H44441003(CHIPS)':
 'VSS'<78>: CDS_PINID='VSS(78)';
NODE_NAME     J9L1 33
 '@BASEBOARD_FAB2_LIB.BASEBOARD_FAB2(SCH_1):PAGE88_I25@MSTR_SCONN.SCONN288_H44441003(CHIPS)':
 'VSS'<79>: CDS_PINID='VSS(79)';
NODE_NAME     J9L1 31
 '@BASEBOARD_FAB2_LIB.BASEBOARD_FAB2(SCH_1):PAGE88_I25@MSTR_SCONN.SCONN288_H44441003(CHIPS)':
 'VSS'<80>: CDS_PINID='VSS(80)';
NODE_NAME     J9L1 28
 '@BASEBOARD_FAB2_LIB.BASEBOARD_FAB2(SCH_1):PAGE88_I25@MSTR_SCONN.SCONN288_H44441003(CHIPS)':
 'VSS'<81>: CDS_PINID='VSS(81)';
NODE_NAME     J9L1 26
 '@BASEBOARD_FAB2_LIB.BASEBOARD_FAB2(SCH_1):PAGE88_I25@MSTR_SCONN.SCONN288_H44441003(CHIPS)':
 'VSS'<82>: CDS_PINID='VSS(82)';
NODE_NAME     J9L1 24
 '@BASEBOARD_FAB2_LIB.BASEBOARD_FAB2(SCH_1):PAGE88_I25@MSTR_SCONN.SCONN288_H44441003(CHIPS)':
 'VSS'<83>: CDS_PINID='VSS(83)';
NODE_NAME     J9L1 22
 '@BASEBOARD_FAB2_LIB.BASEBOARD_FAB2(SCH_1):PAGE88_I25@MSTR_SCONN.SCONN288_H44441003(CHIPS)':
 'VSS'<84>: CDS_PINID='VSS(84)';
NODE_NAME     J9L1 20
 '@BASEBOARD_FAB2_LIB.BASEBOARD_FAB2(SCH_1):PAGE88_I25@MSTR_SCONN.SCONN288_H44441003(CHIPS)':
 'VSS'<85>: CDS_PINID='VSS(85)';
NODE_NAME     J9L1 17
 '@BASEBOARD_FAB2_LIB.BASEBOARD_FAB2(SCH_1):PAGE88_I25@MSTR_SCONN.SCONN288_H44441003(CHIPS)':
 'VSS'<86>: CDS_PINID='VSS(86)';
NODE_NAME     J9L1 15
 '@BASEBOARD_FAB2_LIB.BASEBOARD_FAB2(SCH_1):PAGE88_I25@MSTR_SCONN.SCONN288_H44441003(CHIPS)':
 'VSS'<87>: CDS_PINID='VSS(87)';
NODE_NAME     J9L1 13
 '@BASEBOARD_FAB2_LIB.BASEBOARD_FAB2(SCH_1):PAGE88_I25@MSTR_SCONN.SCONN288_H44441003(CHIPS)':
 'VSS'<88>: CDS_PINID='VSS(88)';
NODE_NAME     J9L1 11
 '@BASEBOARD_FAB2_LIB.BASEBOARD_FAB2(SCH_1):PAGE88_I25@MSTR_SCONN.SCONN288_H44441003(CHIPS)':
 'VSS'<89>: CDS_PINID='VSS(89)';
NODE_NAME     J9L1 9
 '@BASEBOARD_FAB2_LIB.BASEBOARD_FAB2(SCH_1):PAGE88_I25@MSTR_SCONN.SCONN288_H44441003(CHIPS)':
 'VSS'<90>: CDS_PINID='VSS(90)';
NODE_NAME     J9L1 6
 '@BASEBOARD_FAB2_LIB.BASEBOARD_FAB2(SCH_1):PAGE88_I25@MSTR_SCONN.SCONN288_H44441003(CHIPS)':
 'VSS'<91>: CDS_PINID='VSS(91)';
NODE_NAME     J9L1 4
 '@BASEBOARD_FAB2_LIB.BASEBOARD_FAB2(SCH_1):PAGE88_I25@MSTR_SCONN.SCONN288_H44441003(CHIPS)':
 'VSS'<92>: CDS_PINID='VSS(92)';
NODE_NAME     J9L1 2
 '@BASEBOARD_FAB2_LIB.BASEBOARD_FAB2(SCH_1):PAGE88_I25@MSTR_SCONN.SCONN288_H44441003(CHIPS)':
 'VSS'<93>: CDS_PINID='VSS(93)';
NODE_NAME     J9L1 140
 '@BASEBOARD_FAB2_LIB.BASEBOARD_FAB2(SCH_1):PAGE88_I111@MSTR_SCONN.SCONN288_H44441003(CHIPS)':
 'SA'<1>: CDS_PINID='SA(1)';
NODE_NAME     C9L1 2
 '@BASEBOARD_FAB2_LIB.BASEBOARD_FAB2(SCH_1):PAGE88_I177@DEV_DISCRETE.CAP_A(CHIPS)':
 'B': CDS_PINID='B';
NODE_NAME     Q8D1 4
 '@BASEBOARD_FAB2_LIB.BASEBOARD_FAB2(SCH_1):PAGE89_I35@MSTR_DISCRETE.NPN_DUAL(CHIPS)':
 'E'<0>: CDS_PINID='E(0)';
NODE_NAME     R6D14 1
 '@BASEBOARD_FAB2_LIB.BASEBOARD_FAB2(SCH_1):PAGE90_I52@MSTR_DISCRETE.RES(CHIPS)':
 'A': CDS_PINID='A';
NODE_NAME     R3D25 1
 '@BASEBOARD_FAB2_LIB.BASEBOARD_FAB2(SCH_1):PAGE90_I66@MSTR_DISCRETE.RES(CHIPS)':
 'A': CDS_PINID='A';
NODE_NAME     R4P6 1
 '@BASEBOARD_FAB2_LIB.BASEBOARD_FAB2(SCH_1):PAGE90_I68@MSTR_DISCRETE.RES(CHIPS)':
 'A': CDS_PINID='A';
NODE_NAME     R4P7 1
 '@BASEBOARD_FAB2_LIB.BASEBOARD_FAB2(SCH_1):PAGE90_I72@MSTR_DISCRETE.RES(CHIPS)':
 'A': CDS_PINID='A';
NODE_NAME     R7P15 1
 '@BASEBOARD_FAB2_LIB.BASEBOARD_FAB2(SCH_1):PAGE90_I74@MSTR_DISCRETE.RES(CHIPS)':
 'A': CDS_PINID='A';
NODE_NAME     R5P2 2
 '@BASEBOARD_FAB2_LIB.BASEBOARD_FAB2(SCH_1):PAGE90_I79@MSTR_DISCRETE.RES(CHIPS)':
 'B': CDS_PINID='B';
NODE_NAME     R5P3 2
 '@BASEBOARD_FAB2_LIB.BASEBOARD_FAB2(SCH_1):PAGE90_I80@MSTR_DISCRETE.RES(CHIPS)':
 'B': CDS_PINID='B';
NODE_NAME     R6D5 2
 '@BASEBOARD_FAB2_LIB.BASEBOARD_FAB2(SCH_1):PAGE90_I81@MSTR_DISCRETE.RES(CHIPS)':
 'B': CDS_PINID='B';
NODE_NAME     R8P1 2
 '@BASEBOARD_FAB2_LIB.BASEBOARD_FAB2(SCH_1):PAGE90_I85@MSTR_DISCRETE.RES(CHIPS)':
 'B': CDS_PINID='B';
NODE_NAME     R8P2 2
 '@BASEBOARD_FAB2_LIB.BASEBOARD_FAB2(SCH_1):PAGE90_I86@MSTR_DISCRETE.RES(CHIPS)':
 'B': CDS_PINID='B';
NODE_NAME     R3D9 2
 '@BASEBOARD_FAB2_LIB.BASEBOARD_FAB2(SCH_1):PAGE90_I88@MSTR_DISCRETE.RES(CHIPS)':
 'B': CDS_PINID='B';
NODE_NAME     J8B1 1
 '@BASEBOARD_FAB2_LIB.BASEBOARD_FAB2(SCH_1):PAGE91_I1@MSTR_SCONN.SCONN24_H46321001(CHIPS)':
 'IO1': CDS_PINID='IO1';
NODE_NAME     J8B1 7
 '@BASEBOARD_FAB2_LIB.BASEBOARD_FAB2(SCH_1):PAGE91_I1@MSTR_SCONN.SCONN24_H46321001(CHIPS)':
 'IO7': CDS_PINID='IO7';
NODE_NAME     J8B1 9
 '@BASEBOARD_FAB2_LIB.BASEBOARD_FAB2(SCH_1):PAGE91_I1@MSTR_SCONN.SCONN24_H46321001(CHIPS)':
 'IO9': CDS_PINID='IO9';
NODE_NAME     J8B1 15
 '@BASEBOARD_FAB2_LIB.BASEBOARD_FAB2(SCH_1):PAGE91_I1@MSTR_SCONN.SCONN24_H46321001(CHIPS)':
 'IO15': CDS_PINID='IO15';
NODE_NAME     J8B1 23
 '@BASEBOARD_FAB2_LIB.BASEBOARD_FAB2(SCH_1):PAGE91_I1@MSTR_SCONN.SCONN24_H46321001(CHIPS)':
 'IO23': CDS_PINID='IO23';
NODE_NAME     J8B1 MP1
 '@BASEBOARD_FAB2_LIB.BASEBOARD_FAB2(SCH_1):PAGE91_I1@MSTR_SCONN.SCONN24_H46321001(CHIPS)':
 'MP1': CDS_PINID='MP1';
NODE_NAME     J8B1 MP2
 '@BASEBOARD_FAB2_LIB.BASEBOARD_FAB2(SCH_1):PAGE91_I1@MSTR_SCONN.SCONN24_H46321001(CHIPS)':
 'MP2': CDS_PINID='MP2';
NODE_NAME     U3P2 7
 '@BASEBOARD_FAB2_LIB.BASEBOARD_FAB2(SCH_1):PAGE92_I1@MSTR_DIGITAL.GTL2014(CHIPS)':
 'GND'<0>: CDS_PINID='GND(0)';
NODE_NAME     U3P2 8
 '@BASEBOARD_FAB2_LIB.BASEBOARD_FAB2(SCH_1):PAGE92_I1@MSTR_DIGITAL.GTL2014(CHIPS)':
 'GND'<1>: CDS_PINID='GND(1)';
NODE_NAME     U3P2 11
 '@BASEBOARD_FAB2_LIB.BASEBOARD_FAB2(SCH_1):PAGE92_I1@MSTR_DIGITAL.GTL2014(CHIPS)':
 'GND'<2>: CDS_PINID='GND(2)';
NODE_NAME     U7D2 7
 '@BASEBOARD_FAB2_LIB.BASEBOARD_FAB2(SCH_1):PAGE92_I32@MSTR_DIGITAL.GTL2014(CHIPS)':
 'GND'<0>: CDS_PINID='GND(0)';
NODE_NAME     U7D2 8
 '@BASEBOARD_FAB2_LIB.BASEBOARD_FAB2(SCH_1):PAGE92_I32@MSTR_DIGITAL.GTL2014(CHIPS)':
 'GND'<1>: CDS_PINID='GND(1)';
NODE_NAME     U7D2 11
 '@BASEBOARD_FAB2_LIB.BASEBOARD_FAB2(SCH_1):PAGE92_I32@MSTR_DIGITAL.GTL2014(CHIPS)':
 'GND'<2>: CDS_PINID='GND(2)';
NODE_NAME     C3P49 2
 '@BASEBOARD_FAB2_LIB.BASEBOARD_FAB2(SCH_1):PAGE92_I37@DEV_DISCRETE.CAP_A(CHIPS)':
 'B': CDS_PINID='B';
NODE_NAME     R3P49 2
 '@BASEBOARD_FAB2_LIB.BASEBOARD_FAB2(SCH_1):PAGE92_I38@MSTR_DISCRETE.RES(CHIPS)':
 'B': CDS_PINID='B';
NODE_NAME     R3R1 2
 '@BASEBOARD_FAB2_LIB.BASEBOARD_FAB2(SCH_1):PAGE92_I46@MSTR_DISCRETE.RES(CHIPS)':
 'B': CDS_PINID='B';
NODE_NAME     R7D32 2
 '@BASEBOARD_FAB2_LIB.BASEBOARD_FAB2(SCH_1):PAGE92_I48@MSTR_DISCRETE.RES(CHIPS)':
 'B': CDS_PINID='B';
NODE_NAME     C7D5 2
 '@BASEBOARD_FAB2_LIB.BASEBOARD_FAB2(SCH_1):PAGE92_I52@DEV_DISCRETE.CAP_A(CHIPS)':
 'B': CDS_PINID='B';
NODE_NAME     R7D26 2
 '@BASEBOARD_FAB2_LIB.BASEBOARD_FAB2(SCH_1):PAGE92_I54@MSTR_DISCRETE.RES(CHIPS)':
 'B': CDS_PINID='B';
NODE_NAME     R3R2 2
 '@BASEBOARD_FAB2_LIB.BASEBOARD_FAB2(SCH_1):PAGE92_I75@MSTR_DISCRETE.RES(CHIPS)':
 'B': CDS_PINID='B';
NODE_NAME     C7D4 2
 '@BASEBOARD_FAB2_LIB.BASEBOARD_FAB2(SCH_1):PAGE92_I79@MSTR_DISCRETE.CAP(CHIPS)':
 'B': CDS_PINID='B';
NODE_NAME     C3P50 2
 '@BASEBOARD_FAB2_LIB.BASEBOARD_FAB2(SCH_1):PAGE92_I84@MSTR_DISCRETE.CAP(CHIPS)':
 'B': CDS_PINID='B';
NODE_NAME     U2T4 7
 '@BASEBOARD_FAB2_LIB.BASEBOARD_FAB2(SCH_1):PAGE93_I30@MSTR_DIGITAL.GTL2014(CHIPS)':
 'GND'<0>: CDS_PINID='GND(0)';
NODE_NAME     U2T4 8
 '@BASEBOARD_FAB2_LIB.BASEBOARD_FAB2(SCH_1):PAGE93_I30@MSTR_DIGITAL.GTL2014(CHIPS)':
 'GND'<1>: CDS_PINID='GND(1)';
NODE_NAME     U2T4 11
 '@BASEBOARD_FAB2_LIB.BASEBOARD_FAB2(SCH_1):PAGE93_I30@MSTR_DIGITAL.GTL2014(CHIPS)':
 'GND'<2>: CDS_PINID='GND(2)';
NODE_NAME     C2T33 2
 '@BASEBOARD_FAB2_LIB.BASEBOARD_FAB2(SCH_1):PAGE93_I72@DEV_DISCRETE.CAP_A(CHIPS)':
 'B': CDS_PINID='B';
NODE_NAME     C2T32 2
 '@BASEBOARD_FAB2_LIB.BASEBOARD_FAB2(SCH_1):PAGE93_I95@DEV_DISCRETE.CAP_A(CHIPS)':
 'B': CDS_PINID='B';
NODE_NAME     R2T39 2
 '@BASEBOARD_FAB2_LIB.BASEBOARD_FAB2(SCH_1):PAGE93_I98@MSTR_DISCRETE.RES(CHIPS)':
 'B': CDS_PINID='B';
NODE_NAME     R2T50 2
 '@BASEBOARD_FAB2_LIB.BASEBOARD_FAB2(SCH_1):PAGE93_I127@MSTR_DISCRETE.RES(CHIPS)':
 'B': CDS_PINID='B';
NODE_NAME     Q3U1 1
 '@BASEBOARD_FAB2_LIB.BASEBOARD_FAB2(SCH_1):PAGE94_I49@MSTR_DISCRETE.FET_N_DUAL(CHIPS)':
 'SOURCE'<0>: CDS_PINID='SOURCE(0)';
NODE_NAME     Q7E1 1
 '@BASEBOARD_FAB2_LIB.BASEBOARD_FAB2(SCH_1):PAGE94_I60@MSTR_DISCRETE.FET_N_DUAL(CHIPS)':
 'SOURCE'<0>: CDS_PINID='SOURCE(0)';
NODE_NAME     Q7E1 4
 '@BASEBOARD_FAB2_LIB.BASEBOARD_FAB2(SCH_1):PAGE94_I64@MSTR_DISCRETE.FET_N_DUAL(CHIPS)':
 'SOURCE'<0>: CDS_PINID='SOURCE(0)';
NODE_NAME     Q7E2 1
 '@BASEBOARD_FAB2_LIB.BASEBOARD_FAB2(SCH_1):PAGE94_I69@MSTR_DISCRETE.FET_N_DUAL(CHIPS)':
 'SOURCE'<0>: CDS_PINID='SOURCE(0)';
NODE_NAME     Q7E2 4
 '@BASEBOARD_FAB2_LIB.BASEBOARD_FAB2(SCH_1):PAGE94_I75@MSTR_DISCRETE.FET_N_DUAL(CHIPS)':
 'SOURCE'<0>: CDS_PINID='SOURCE(0)';
NODE_NAME     Q4B1 4
 '@BASEBOARD_FAB2_LIB.BASEBOARD_FAB2(SCH_1):PAGE94_I77@MSTR_DISCRETE.FET_N_DUAL(CHIPS)':
 'SOURCE'<0>: CDS_PINID='SOURCE(0)';
NODE_NAME     Q4B1 1
 '@BASEBOARD_FAB2_LIB.BASEBOARD_FAB2(SCH_1):PAGE94_I84@MSTR_DISCRETE.FET_N_DUAL(CHIPS)':
 'SOURCE'<0>: CDS_PINID='SOURCE(0)';
NODE_NAME     Q3U1 4
 '@BASEBOARD_FAB2_LIB.BASEBOARD_FAB2(SCH_1):PAGE94_I89@MSTR_DISCRETE.FET_N_DUAL(CHIPS)':
 'SOURCE'<0>: CDS_PINID='SOURCE(0)';
NODE_NAME     Q4U1 1
 '@BASEBOARD_FAB2_LIB.BASEBOARD_FAB2(SCH_1):PAGE94_I98@MSTR_DISCRETE.FET_N_DUAL(CHIPS)':
 'SOURCE'<0>: CDS_PINID='SOURCE(0)';
NODE_NAME     Q4U1 4
 '@BASEBOARD_FAB2_LIB.BASEBOARD_FAB2(SCH_1):PAGE94_I102@MSTR_DISCRETE.FET_N_DUAL(CHIPS)':
 'SOURCE'<0>: CDS_PINID='SOURCE(0)';
NODE_NAME     R4U4 2
 '@BASEBOARD_FAB2_LIB.BASEBOARD_FAB2(SCH_1):PAGE94_I104@MSTR_DISCRETE.RES(CHIPS)':
 'B': CDS_PINID='B';
NODE_NAME     Q2U1 1
 '@BASEBOARD_FAB2_LIB.BASEBOARD_FAB2(SCH_1):PAGE95_I28@MSTR_DISCRETE.FET_N_DUAL(CHIPS)':
 'SOURCE'<0>: CDS_PINID='SOURCE(0)';
NODE_NAME     Q4B2 1
 '@BASEBOARD_FAB2_LIB.BASEBOARD_FAB2(SCH_1):PAGE95_I32@MSTR_DISCRETE.FET_N_DUAL(CHIPS)':
 'SOURCE'<0>: CDS_PINID='SOURCE(0)';
NODE_NAME     Q4B2 4
 '@BASEBOARD_FAB2_LIB.BASEBOARD_FAB2(SCH_1):PAGE95_I33@MSTR_DISCRETE.FET_N_DUAL(CHIPS)':
 'SOURCE'<0>: CDS_PINID='SOURCE(0)';
NODE_NAME     Q7E3 4
 '@BASEBOARD_FAB2_LIB.BASEBOARD_FAB2(SCH_1):PAGE95_I51@MSTR_DISCRETE.FET_N_DUAL(CHIPS)':
 'SOURCE'<0>: CDS_PINID='SOURCE(0)';
NODE_NAME     Q7E3 1
 '@BASEBOARD_FAB2_LIB.BASEBOARD_FAB2(SCH_1):PAGE95_I52@MSTR_DISCRETE.FET_N_DUAL(CHIPS)':
 'SOURCE'<0>: CDS_PINID='SOURCE(0)';
NODE_NAME     Q7E5 4
 '@BASEBOARD_FAB2_LIB.BASEBOARD_FAB2(SCH_1):PAGE95_I59@MSTR_DISCRETE.FET_N_DUAL(CHIPS)':
 'SOURCE'<0>: CDS_PINID='SOURCE(0)';
NODE_NAME     Q7E6 4
 '@BASEBOARD_FAB2_LIB.BASEBOARD_FAB2(SCH_1):PAGE95_I69@MSTR_DISCRETE.FET_N_DUAL(CHIPS)':
 'SOURCE'<0>: CDS_PINID='SOURCE(0)';
NODE_NAME     C7E3 2
 '@BASEBOARD_FAB2_LIB.BASEBOARD_FAB2(SCH_1):PAGE95_I92@DEV_DISCRETE.CAP_A(CHIPS)':
 'B': CDS_PINID='B';
NODE_NAME     Q7E5 1
 '@BASEBOARD_FAB2_LIB.BASEBOARD_FAB2(SCH_1):PAGE95_I111@MSTR_DISCRETE.FET_N_DUAL(CHIPS)':
 'SOURCE'<0>: CDS_PINID='SOURCE(0)';
NODE_NAME     Q7E6 1
 '@BASEBOARD_FAB2_LIB.BASEBOARD_FAB2(SCH_1):PAGE95_I112@MSTR_DISCRETE.FET_N_DUAL(CHIPS)':
 'SOURCE'<0>: CDS_PINID='SOURCE(0)';
NODE_NAME     Q2U1 4
 '@BASEBOARD_FAB2_LIB.BASEBOARD_FAB2(SCH_1):PAGE95_I113@MSTR_DISCRETE.FET_N_DUAL(CHIPS)':
 'SOURCE'<0>: CDS_PINID='SOURCE(0)';
NODE_NAME     C7E4 2
 '@BASEBOARD_FAB2_LIB.BASEBOARD_FAB2(SCH_1):PAGE95_I115@DEV_DISCRETE.CAP_A(CHIPS)':
 'B': CDS_PINID='B';
NODE_NAME     U3P1 7
 '@BASEBOARD_FAB2_LIB.BASEBOARD_FAB2(SCH_1):PAGE96_I42@MSTR_DIGITAL.GTL2014(CHIPS)':
 'GND'<0>: CDS_PINID='GND(0)';
NODE_NAME     U3P1 8
 '@BASEBOARD_FAB2_LIB.BASEBOARD_FAB2(SCH_1):PAGE96_I42@MSTR_DIGITAL.GTL2014(CHIPS)':
 'GND'<1>: CDS_PINID='GND(1)';
NODE_NAME     U3P1 11
 '@BASEBOARD_FAB2_LIB.BASEBOARD_FAB2(SCH_1):PAGE96_I42@MSTR_DIGITAL.GTL2014(CHIPS)':
 'GND'<2>: CDS_PINID='GND(2)';
NODE_NAME     U4C2 7
 '@BASEBOARD_FAB2_LIB.BASEBOARD_FAB2(SCH_1):PAGE96_I46@MSTR_DIGITAL.GTL2014(CHIPS)':
 'GND'<0>: CDS_PINID='GND(0)';
NODE_NAME     U4C2 8
 '@BASEBOARD_FAB2_LIB.BASEBOARD_FAB2(SCH_1):PAGE96_I46@MSTR_DIGITAL.GTL2014(CHIPS)':
 'GND'<1>: CDS_PINID='GND(1)';
NODE_NAME     U4C2 11
 '@BASEBOARD_FAB2_LIB.BASEBOARD_FAB2(SCH_1):PAGE96_I46@MSTR_DIGITAL.GTL2014(CHIPS)':
 'GND'<2>: CDS_PINID='GND(2)';
NODE_NAME     R4C9 1
 '@BASEBOARD_FAB2_LIB.BASEBOARD_FAB2(SCH_1):PAGE96_I69@MSTR_DISCRETE.RES(CHIPS)':
 'A': CDS_PINID='A';
NODE_NAME     R3P32 1
 '@BASEBOARD_FAB2_LIB.BASEBOARD_FAB2(SCH_1):PAGE96_I71@MSTR_DISCRETE.RES(CHIPS)':
 'A': CDS_PINID='A';
NODE_NAME     C3P42 2
 '@BASEBOARD_FAB2_LIB.BASEBOARD_FAB2(SCH_1):PAGE96_I73@DEV_DISCRETE.CAP_A(CHIPS)':
 'B': CDS_PINID='B';
NODE_NAME     C4C3 2
 '@BASEBOARD_FAB2_LIB.BASEBOARD_FAB2(SCH_1):PAGE96_I75@DEV_DISCRETE.CAP_A(CHIPS)':
 'B': CDS_PINID='B';
NODE_NAME     R4P5 1
 '@BASEBOARD_FAB2_LIB.BASEBOARD_FAB2(SCH_1):PAGE97_I80@MSTR_DISCRETE.RES(CHIPS)':
 'A': CDS_PINID='A';
NODE_NAME     R7P13 1
 '@BASEBOARD_FAB2_LIB.BASEBOARD_FAB2(SCH_1):PAGE97_I81@MSTR_DISCRETE.RES(CHIPS)':
 'A': CDS_PINID='A';
NODE_NAME     R4F5 2
 '@BASEBOARD_FAB2_LIB.BASEBOARD_FAB2(SCH_1):PAGE98_I4@MSTR_DISCRETE.RES(CHIPS)':
 'B': CDS_PINID='B';
NODE_NAME     C4F9 2
 '@BASEBOARD_FAB2_LIB.BASEBOARD_FAB2(SCH_1):PAGE98_I7@DEV_DISCRETE.CAP_A(CHIPS)':
 'B': CDS_PINID='B';
NODE_NAME     R6L16 2
 '@BASEBOARD_FAB2_LIB.BASEBOARD_FAB2(SCH_1):PAGE98_I12@MSTR_DISCRETE.RES(CHIPS)':
 'B': CDS_PINID='B';
NODE_NAME     C6M2 2
 '@BASEBOARD_FAB2_LIB.BASEBOARD_FAB2(SCH_1):PAGE98_I33@DEV_DISCRETE.CAP_A(CHIPS)':
 'B': CDS_PINID='B';
NODE_NAME     R4G3 2
 '@BASEBOARD_FAB2_LIB.BASEBOARD_FAB2(SCH_1):PAGE98_I40@MSTR_DISCRETE.RES(CHIPS)':
 'B': CDS_PINID='B';
NODE_NAME     C4G1 2
 '@BASEBOARD_FAB2_LIB.BASEBOARD_FAB2(SCH_1):PAGE98_I43@DEV_DISCRETE.CAP_A(CHIPS)':
 'B': CDS_PINID='B';
NODE_NAME     R4G22 2
 '@BASEBOARD_FAB2_LIB.BASEBOARD_FAB2(SCH_1):PAGE98_I48@MSTR_DISCRETE.RES(CHIPS)':
 'B': CDS_PINID='B';
NODE_NAME     C4G17 2
 '@BASEBOARD_FAB2_LIB.BASEBOARD_FAB2(SCH_1):PAGE98_I51@DEV_DISCRETE.CAP_A(CHIPS)':
 'B': CDS_PINID='B';
NODE_NAME     R6L12 2
 '@BASEBOARD_FAB2_LIB.BASEBOARD_FAB2(SCH_1):PAGE98_I56@MSTR_DISCRETE.RES(CHIPS)':
 'B': CDS_PINID='B';
NODE_NAME     C6L7 2
 '@BASEBOARD_FAB2_LIB.BASEBOARD_FAB2(SCH_1):PAGE98_I59@DEV_DISCRETE.CAP_A(CHIPS)':
 'B': CDS_PINID='B';
NODE_NAME     R6L1 2
 '@BASEBOARD_FAB2_LIB.BASEBOARD_FAB2(SCH_1):PAGE98_I64@MSTR_DISCRETE.RES(CHIPS)':
 'B': CDS_PINID='B';
NODE_NAME     C6L2 2
 '@BASEBOARD_FAB2_LIB.BASEBOARD_FAB2(SCH_1):PAGE98_I67@DEV_DISCRETE.CAP_A(CHIPS)':
 'B': CDS_PINID='B';
NODE_NAME     C6F2 2
 '@BASEBOARD_FAB2_LIB.BASEBOARD_FAB2(SCH_1):PAGE99_I2@DEV_DISCRETE.CAP_A(CHIPS)':
 'B': CDS_PINID='B';
NODE_NAME     C6F3 2
 '@BASEBOARD_FAB2_LIB.BASEBOARD_FAB2(SCH_1):PAGE99_I7@DEV_DISCRETE.CAP_A(CHIPS)':
 'B': CDS_PINID='B';
NODE_NAME     C7E1 2
 '@BASEBOARD_FAB2_LIB.BASEBOARD_FAB2(SCH_1):PAGE99_I23@DEV_DISCRETE.CAP_A(CHIPS)':
 'B': CDS_PINID='B';
NODE_NAME     C4G22 2
 '@BASEBOARD_FAB2_LIB.BASEBOARD_FAB2(SCH_1):PAGE99_I27@DEV_DISCRETE.CAP_A(CHIPS)':
 'B': CDS_PINID='B';
NODE_NAME     C7E2 2
 '@BASEBOARD_FAB2_LIB.BASEBOARD_FAB2(SCH_1):PAGE99_I32@DEV_DISCRETE.CAP_A(CHIPS)':
 'B': CDS_PINID='B';
NODE_NAME     C4G25 2
 '@BASEBOARD_FAB2_LIB.BASEBOARD_FAB2(SCH_1):PAGE99_I41@DEV_DISCRETE.CAP_A(CHIPS)':
 'B': CDS_PINID='B';
NODE_NAME     C3B4 2
 '@BASEBOARD_FAB2_LIB.BASEBOARD_FAB2(SCH_1):PAGE99_I47@DEV_DISCRETE.CAP_A(CHIPS)':
 'B': CDS_PINID='B';
NODE_NAME     C3B5 2
 '@BASEBOARD_FAB2_LIB.BASEBOARD_FAB2(SCH_1):PAGE99_I53@DEV_DISCRETE.CAP_A(CHIPS)':
 'B': CDS_PINID='B';
NODE_NAME     R1F6 2
 '@BASEBOARD_FAB2_LIB.BASEBOARD_FAB2(SCH_1):PAGE100_I2@MSTR_DISCRETE.RES(CHIPS)':
 'B': CDS_PINID='B';
NODE_NAME     R9L11 2
 '@BASEBOARD_FAB2_LIB.BASEBOARD_FAB2(SCH_1):PAGE100_I4@MSTR_DISCRETE.RES(CHIPS)':
 'B': CDS_PINID='B';
NODE_NAME     C1F19 2
 '@BASEBOARD_FAB2_LIB.BASEBOARD_FAB2(SCH_1):PAGE100_I8@DEV_DISCRETE.CAP_A(CHIPS)':
 'B': CDS_PINID='B';
NODE_NAME     C9M2 2
 '@BASEBOARD_FAB2_LIB.BASEBOARD_FAB2(SCH_1):PAGE100_I15@DEV_DISCRETE.CAP_A(CHIPS)':
 'B': CDS_PINID='B';
NODE_NAME     R1G3 2
 '@BASEBOARD_FAB2_LIB.BASEBOARD_FAB2(SCH_1):PAGE100_I20@MSTR_DISCRETE.RES(CHIPS)':
 'B': CDS_PINID='B';
NODE_NAME     R9L6 2
 '@BASEBOARD_FAB2_LIB.BASEBOARD_FAB2(SCH_1):PAGE100_I24@MSTR_DISCRETE.RES(CHIPS)':
 'B': CDS_PINID='B';
NODE_NAME     C1G8 2
 '@BASEBOARD_FAB2_LIB.BASEBOARD_FAB2(SCH_1):PAGE100_I26@DEV_DISCRETE.CAP_A(CHIPS)':
 'B': CDS_PINID='B';
NODE_NAME     C9L8 2
 '@BASEBOARD_FAB2_LIB.BASEBOARD_FAB2(SCH_1):PAGE100_I30@DEV_DISCRETE.CAP_A(CHIPS)':
 'B': CDS_PINID='B';
NODE_NAME     R1G17 2
 '@BASEBOARD_FAB2_LIB.BASEBOARD_FAB2(SCH_1):PAGE100_I36@MSTR_DISCRETE.RES(CHIPS)':
 'B': CDS_PINID='B';
NODE_NAME     R9L1 2
 '@BASEBOARD_FAB2_LIB.BASEBOARD_FAB2(SCH_1):PAGE100_I40@MSTR_DISCRETE.RES(CHIPS)':
 'B': CDS_PINID='B';
NODE_NAME     C1G18 2
 '@BASEBOARD_FAB2_LIB.BASEBOARD_FAB2(SCH_1):PAGE100_I42@DEV_DISCRETE.CAP_A(CHIPS)':
 'B': CDS_PINID='B';
NODE_NAME     C9L3 2
 '@BASEBOARD_FAB2_LIB.BASEBOARD_FAB2(SCH_1):PAGE100_I46@DEV_DISCRETE.CAP_A(CHIPS)':
 'B': CDS_PINID='B';
NODE_NAME     R8F25 2
 '@BASEBOARD_FAB2_LIB.BASEBOARD_FAB2(SCH_1):PAGE101_I28@MSTR_DISCRETE.RES(CHIPS)':
 'B': CDS_PINID='B';
NODE_NAME     EU8F2 1
 '@BASEBOARD_FAB2_LIB.BASEBOARD_FAB2(SCH_1):PAGE101_I34@MSTR_CLOCK.ICS9FGP204(CHIPS)':
 'GND'<0>: CDS_PINID='GND(0)';
NODE_NAME     EU8F2 41
 '@BASEBOARD_FAB2_LIB.BASEBOARD_FAB2(SCH_1):PAGE101_I34@MSTR_CLOCK.ICS9FGP204(CHIPS)':
 'GND'<1>: CDS_PINID='GND(1)';
NODE_NAME     EU8F2 14
 '@BASEBOARD_FAB2_LIB.BASEBOARD_FAB2(SCH_1):PAGE101_I34@MSTR_CLOCK.ICS9FGP204(CHIPS)':
 'GND32K': CDS_PINID='GND32K';
NODE_NAME     EU8F2 21
 '@BASEBOARD_FAB2_LIB.BASEBOARD_FAB2(SCH_1):PAGE101_I34@MSTR_CLOCK.ICS9FGP204(CHIPS)':
 'GND33': CDS_PINID='GND33';
NODE_NAME     EU8F2 35
 '@BASEBOARD_FAB2_LIB.BASEBOARD_FAB2(SCH_1):PAGE101_I34@MSTR_CLOCK.ICS9FGP204(CHIPS)':
 'GND_RGMII': CDS_PINID='GND_RGMII';
NODE_NAME     EU8F2 10
 '@BASEBOARD_FAB2_LIB.BASEBOARD_FAB2(SCH_1):PAGE101_I34@MSTR_CLOCK.ICS9FGP204(CHIPS)':
 'GNDCPU': CDS_PINID='GNDCPU';
NODE_NAME     EU8F2 18
 '@BASEBOARD_FAB2_LIB.BASEBOARD_FAB2(SCH_1):PAGE101_I34@MSTR_CLOCK.ICS9FGP204(CHIPS)':
 'GNDREF': CDS_PINID='GNDREF';
NODE_NAME     EU8F2 27
 '@BASEBOARD_FAB2_LIB.BASEBOARD_FAB2(SCH_1):PAGE101_I34@MSTR_CLOCK.ICS9FGP204(CHIPS)':
 'GNDRMII'<0>: CDS_PINID='GNDRMII(0)';
NODE_NAME     EU8F2 30
 '@BASEBOARD_FAB2_LIB.BASEBOARD_FAB2(SCH_1):PAGE101_I34@MSTR_CLOCK.ICS9FGP204(CHIPS)':
 'GNDRMII'<1>: CDS_PINID='GNDRMII(1)';
NODE_NAME     R2T25 2
 '@BASEBOARD_FAB2_LIB.BASEBOARD_FAB2(SCH_1):PAGE101_I48@MSTR_DISCRETE.RES(CHIPS)':
 'B': CDS_PINID='B';
NODE_NAME     C2T31 2
 '@BASEBOARD_FAB2_LIB.BASEBOARD_FAB2(SCH_1):PAGE101_I89@DEV_DISCRETE.CAP_A(CHIPS)':
 'B': CDS_PINID='B';
NODE_NAME     C2T27 2
 '@BASEBOARD_FAB2_LIB.BASEBOARD_FAB2(SCH_1):PAGE101_I90@DEV_DISCRETE.CAP_A(CHIPS)':
 'B': CDS_PINID='B';
NODE_NAME     C2T38 2
 '@BASEBOARD_FAB2_LIB.BASEBOARD_FAB2(SCH_1):PAGE101_I97@DEV_DISCRETE.CAP_A(CHIPS)':
 'B': CDS_PINID='B';
NODE_NAME     C2T37 2
 '@BASEBOARD_FAB2_LIB.BASEBOARD_FAB2(SCH_1):PAGE101_I99@DEV_DISCRETE.CAP_A(CHIPS)':
 'B': CDS_PINID='B';
NODE_NAME     C2T18 2
 '@BASEBOARD_FAB2_LIB.BASEBOARD_FAB2(SCH_1):PAGE101_I104@DEV_DISCRETE.CAP_A(CHIPS)':
 'B': CDS_PINID='B';
NODE_NAME     C2T19 2
 '@BASEBOARD_FAB2_LIB.BASEBOARD_FAB2(SCH_1):PAGE101_I106@DEV_DISCRETE.CAP_A(CHIPS)':
 'B': CDS_PINID='B';
NODE_NAME     C2T34 2
 '@BASEBOARD_FAB2_LIB.BASEBOARD_FAB2(SCH_1):PAGE101_I109@DEV_DISCRETE.CAP_A(CHIPS)':
 'B': CDS_PINID='B';
NODE_NAME     C2T30 2
 '@BASEBOARD_FAB2_LIB.BASEBOARD_FAB2(SCH_1):PAGE101_I110@DEV_DISCRETE.CAP_A(CHIPS)':
 'B': CDS_PINID='B';
NODE_NAME     C2T25 2
 '@BASEBOARD_FAB2_LIB.BASEBOARD_FAB2(SCH_1):PAGE101_I111@DEV_DISCRETE.CAP_A(CHIPS)':
 'B': CDS_PINID='B';
NODE_NAME     C2T17 2
 '@BASEBOARD_FAB2_LIB.BASEBOARD_FAB2(SCH_1):PAGE101_I112@DEV_DISCRETE.CAP_A(CHIPS)':
 'B': CDS_PINID='B';
NODE_NAME     C2T22 2
 '@BASEBOARD_FAB2_LIB.BASEBOARD_FAB2(SCH_1):PAGE101_I113@MSTR_DISCRETE.CAP(CHIPS)':
 'B': CDS_PINID='B';
NODE_NAME     C2T28 2
 '@BASEBOARD_FAB2_LIB.BASEBOARD_FAB2(SCH_1):PAGE101_I116@DEV_DISCRETE.CAP_A(CHIPS)':
 'B': CDS_PINID='B';
NODE_NAME     EU4D2 7
 '@BASEBOARD_FAB2_LIB.BASEBOARD_FAB2(SCH_1):PAGE102_I1@MSTR_CLOCK.NB3W1200L(CHIPS)':
 'GND'<0>: CDS_PINID='GND(0)';
NODE_NAME     EU4D2 23
 '@BASEBOARD_FAB2_LIB.BASEBOARD_FAB2(SCH_1):PAGE102_I1@MSTR_CLOCK.NB3W1200L(CHIPS)':
 'GND'<1>: CDS_PINID='GND(1)';
NODE_NAME     EU4D2 33
 '@BASEBOARD_FAB2_LIB.BASEBOARD_FAB2(SCH_1):PAGE102_I1@MSTR_CLOCK.NB3W1200L(CHIPS)':
 'GND'<2>: CDS_PINID='GND(2)';
NODE_NAME     EU4D2 41
 '@BASEBOARD_FAB2_LIB.BASEBOARD_FAB2(SCH_1):PAGE102_I1@MSTR_CLOCK.NB3W1200L(CHIPS)':
 'GND'<3>: CDS_PINID='GND(3)';
NODE_NAME     EU4D2 48
 '@BASEBOARD_FAB2_LIB.BASEBOARD_FAB2(SCH_1):PAGE102_I1@MSTR_CLOCK.NB3W1200L(CHIPS)':
 'GND'<4>: CDS_PINID='GND(4)';
NODE_NAME     EU4D2 58
 '@BASEBOARD_FAB2_LIB.BASEBOARD_FAB2(SCH_1):PAGE102_I1@MSTR_CLOCK.NB3W1200L(CHIPS)':
 'GND'<5>: CDS_PINID='GND(5)';
NODE_NAME     EU4D2 2
 '@BASEBOARD_FAB2_LIB.BASEBOARD_FAB2(SCH_1):PAGE102_I1@MSTR_CLOCK.NB3W1200L(CHIPS)':
 'GNDA': CDS_PINID='GNDA';
NODE_NAME     EU4D2 65
 '@BASEBOARD_FAB2_LIB.BASEBOARD_FAB2(SCH_1):PAGE102_I1@MSTR_CLOCK.NB3W1200L(CHIPS)':
 'THPAD': CDS_PINID='THPAD';
NODE_NAME     C3D22 2
 '@BASEBOARD_FAB2_LIB.BASEBOARD_FAB2(SCH_1):PAGE102_I10@MSTR_DISCRETE.CAP(CHIPS)':
 'B': CDS_PINID='B';
NODE_NAME     C6P4 2
 '@BASEBOARD_FAB2_LIB.BASEBOARD_FAB2(SCH_1):PAGE102_I11@DEV_DISCRETE.CAP_A(CHIPS)':
 'B': CDS_PINID='B';
NODE_NAME     C6P6 2
 '@BASEBOARD_FAB2_LIB.BASEBOARD_FAB2(SCH_1):PAGE102_I12@DEV_DISCRETE.CAP_A(CHIPS)':
 'B': CDS_PINID='B';
NODE_NAME     C6P10 2
 '@BASEBOARD_FAB2_LIB.BASEBOARD_FAB2(SCH_1):PAGE102_I13@DEV_DISCRETE.CAP_A(CHIPS)':
 'B': CDS_PINID='B';
NODE_NAME     C6P5 2
 '@BASEBOARD_FAB2_LIB.BASEBOARD_FAB2(SCH_1):PAGE102_I14@DEV_DISCRETE.CAP_A(CHIPS)':
 'B': CDS_PINID='B';
NODE_NAME     C6P12 2
 '@BASEBOARD_FAB2_LIB.BASEBOARD_FAB2(SCH_1):PAGE102_I15@DEV_DISCRETE.CAP_A(CHIPS)':
 'B': CDS_PINID='B';
NODE_NAME     C6P11 2
 '@BASEBOARD_FAB2_LIB.BASEBOARD_FAB2(SCH_1):PAGE102_I16@DEV_DISCRETE.CAP_A(CHIPS)':
 'B': CDS_PINID='B';
NODE_NAME     C4D24 2
 '@BASEBOARD_FAB2_LIB.BASEBOARD_FAB2(SCH_1):PAGE102_I18@DEV_DISCRETE.CAP_A(CHIPS)':
 'B': CDS_PINID='B';
NODE_NAME     C4D23 2
 '@BASEBOARD_FAB2_LIB.BASEBOARD_FAB2(SCH_1):PAGE102_I19@DEV_DISCRETE.CAP_A(CHIPS)':
 'B': CDS_PINID='B';
NODE_NAME     C4D22 2
 '@BASEBOARD_FAB2_LIB.BASEBOARD_FAB2(SCH_1):PAGE102_I28@DEV_DISCRETE.CAP_A(CHIPS)':
 'B': CDS_PINID='B';
NODE_NAME     C4D27 2
 '@BASEBOARD_FAB2_LIB.BASEBOARD_FAB2(SCH_1):PAGE102_I30@DEV_DISCRETE.CAP_A(CHIPS)':
 'B': CDS_PINID='B';
NODE_NAME     R6P23 2
 '@BASEBOARD_FAB2_LIB.BASEBOARD_FAB2(SCH_1):PAGE102_I46@MSTR_DISCRETE.RES(CHIPS)':
 'B': CDS_PINID='B';
NODE_NAME     R6P22 2
 '@BASEBOARD_FAB2_LIB.BASEBOARD_FAB2(SCH_1):PAGE102_I47@MSTR_DISCRETE.RES(CHIPS)':
 'B': CDS_PINID='B';
NODE_NAME     C6P9 2
 '@BASEBOARD_FAB2_LIB.BASEBOARD_FAB2(SCH_1):PAGE102_I79@DEV_DISCRETE.CAP_A(CHIPS)':
 'B': CDS_PINID='B';
NODE_NAME     R6P21 2
 '@BASEBOARD_FAB2_LIB.BASEBOARD_FAB2(SCH_1):PAGE102_I80@MSTR_DISCRETE.RES(CHIPS)':
 'B': CDS_PINID='B';
NODE_NAME     R6P20 2
 '@BASEBOARD_FAB2_LIB.BASEBOARD_FAB2(SCH_1):PAGE102_I81@MSTR_DISCRETE.RES(CHIPS)':
 'B': CDS_PINID='B';
NODE_NAME     R7P9 2
 '@BASEBOARD_FAB2_LIB.BASEBOARD_FAB2(SCH_1):PAGE103_I121@MSTR_DISCRETE.RES(CHIPS)':
 'B': CDS_PINID='B';
NODE_NAME     R7P12 2
 '@BASEBOARD_FAB2_LIB.BASEBOARD_FAB2(SCH_1):PAGE103_I123@MSTR_DISCRETE.RES(CHIPS)':
 'B': CDS_PINID='B';
NODE_NAME     R7P6 2
 '@BASEBOARD_FAB2_LIB.BASEBOARD_FAB2(SCH_1):PAGE103_I125@MSTR_DISCRETE.RES(CHIPS)':
 'B': CDS_PINID='B';
NODE_NAME     R7P7 2
 '@BASEBOARD_FAB2_LIB.BASEBOARD_FAB2(SCH_1):PAGE103_I127@MSTR_DISCRETE.RES(CHIPS)':
 'B': CDS_PINID='B';
NODE_NAME     R7P3 2
 '@BASEBOARD_FAB2_LIB.BASEBOARD_FAB2(SCH_1):PAGE103_I129@MSTR_DISCRETE.RES(CHIPS)':
 'B': CDS_PINID='B';
NODE_NAME     R7P4 2
 '@BASEBOARD_FAB2_LIB.BASEBOARD_FAB2(SCH_1):PAGE103_I131@MSTR_DISCRETE.RES(CHIPS)':
 'B': CDS_PINID='B';
NODE_NAME     R7P1 2
 '@BASEBOARD_FAB2_LIB.BASEBOARD_FAB2(SCH_1):PAGE103_I133@MSTR_DISCRETE.RES(CHIPS)':
 'B': CDS_PINID='B';
NODE_NAME     R7P2 2
 '@BASEBOARD_FAB2_LIB.BASEBOARD_FAB2(SCH_1):PAGE103_I135@MSTR_DISCRETE.RES(CHIPS)':
 'B': CDS_PINID='B';
NODE_NAME     R6P7 2
 '@BASEBOARD_FAB2_LIB.BASEBOARD_FAB2(SCH_1):PAGE103_I137@MSTR_DISCRETE.RES(CHIPS)':
 'B': CDS_PINID='B';
NODE_NAME     R6P8 2
 '@BASEBOARD_FAB2_LIB.BASEBOARD_FAB2(SCH_1):PAGE103_I139@MSTR_DISCRETE.RES(CHIPS)':
 'B': CDS_PINID='B';
NODE_NAME     R6P5 2
 '@BASEBOARD_FAB2_LIB.BASEBOARD_FAB2(SCH_1):PAGE103_I141@MSTR_DISCRETE.RES(CHIPS)':
 'B': CDS_PINID='B';
NODE_NAME     R6P6 2
 '@BASEBOARD_FAB2_LIB.BASEBOARD_FAB2(SCH_1):PAGE103_I143@MSTR_DISCRETE.RES(CHIPS)':
 'B': CDS_PINID='B';
NODE_NAME     R6P3 2
 '@BASEBOARD_FAB2_LIB.BASEBOARD_FAB2(SCH_1):PAGE103_I145@MSTR_DISCRETE.RES(CHIPS)':
 'B': CDS_PINID='B';
NODE_NAME     R6P4 2
 '@BASEBOARD_FAB2_LIB.BASEBOARD_FAB2(SCH_1):PAGE103_I147@MSTR_DISCRETE.RES(CHIPS)':
 'B': CDS_PINID='B';
NODE_NAME     R6P1 2
 '@BASEBOARD_FAB2_LIB.BASEBOARD_FAB2(SCH_1):PAGE103_I149@MSTR_DISCRETE.RES(CHIPS)':
 'B': CDS_PINID='B';
NODE_NAME     R6P2 2
 '@BASEBOARD_FAB2_LIB.BASEBOARD_FAB2(SCH_1):PAGE103_I151@MSTR_DISCRETE.RES(CHIPS)':
 'B': CDS_PINID='B';
NODE_NAME     R6P11 2
 '@BASEBOARD_FAB2_LIB.BASEBOARD_FAB2(SCH_1):PAGE103_I153@MSTR_DISCRETE.RES(CHIPS)':
 'B': CDS_PINID='B';
NODE_NAME     R6P9 2
 '@BASEBOARD_FAB2_LIB.BASEBOARD_FAB2(SCH_1):PAGE103_I155@MSTR_DISCRETE.RES(CHIPS)':
 'B': CDS_PINID='B';
NODE_NAME     R6P13 2
 '@BASEBOARD_FAB2_LIB.BASEBOARD_FAB2(SCH_1):PAGE103_I157@MSTR_DISCRETE.RES(CHIPS)':
 'B': CDS_PINID='B';
NODE_NAME     R6P12 2
 '@BASEBOARD_FAB2_LIB.BASEBOARD_FAB2(SCH_1):PAGE103_I159@MSTR_DISCRETE.RES(CHIPS)':
 'B': CDS_PINID='B';
NODE_NAME     R4D24 2
 '@BASEBOARD_FAB2_LIB.BASEBOARD_FAB2(SCH_1):PAGE103_I161@MSTR_DISCRETE.RES(CHIPS)':
 'B': CDS_PINID='B';
NODE_NAME     R4D18 2
 '@BASEBOARD_FAB2_LIB.BASEBOARD_FAB2(SCH_1):PAGE103_I163@MSTR_DISCRETE.RES(CHIPS)':
 'B': CDS_PINID='B';
NODE_NAME     R6P17 2
 '@BASEBOARD_FAB2_LIB.BASEBOARD_FAB2(SCH_1):PAGE103_I165@MSTR_DISCRETE.RES(CHIPS)':
 'B': CDS_PINID='B';
NODE_NAME     R6P15 2
 '@BASEBOARD_FAB2_LIB.BASEBOARD_FAB2(SCH_1):PAGE103_I167@MSTR_DISCRETE.RES(CHIPS)':
 'B': CDS_PINID='B';
NODE_NAME     C6F1 2
 '@BASEBOARD_FAB2_LIB.BASEBOARD_FAB2(SCH_1):PAGE104_I25@DEV_DISCRETE.CAP_A(CHIPS)':
 'B': CDS_PINID='B';
NODE_NAME     C3F2 2
 '@BASEBOARD_FAB2_LIB.BASEBOARD_FAB2(SCH_1):PAGE104_I34@DEV_DISCRETE.CAP_A(CHIPS)':
 'B': CDS_PINID='B';
NODE_NAME     Y6F1 3
 '@BASEBOARD_FAB2_LIB.BASEBOARD_FAB2(SCH_1):PAGE104_I71@MSTR_DISCRETE.OSC_C(CHIPS)':
 'GND': CDS_PINID='GND';
NODE_NAME     Y3F1 3
 '@BASEBOARD_FAB2_LIB.BASEBOARD_FAB2(SCH_1):PAGE104_I72@MSTR_DISCRETE.OSC_C(CHIPS)':
 'GND': CDS_PINID='GND';
NODE_NAME     C2U20 2
 '@BASEBOARD_FAB2_LIB.BASEBOARD_FAB2(SCH_1):PAGE108_I1@DEV_DISCRETE.CAP_A(CHIPS)':
 'B': CDS_PINID='B';
NODE_NAME     C2U24 2
 '@BASEBOARD_FAB2_LIB.BASEBOARD_FAB2(SCH_1):PAGE108_I2@DEV_DISCRETE.CAP_A(CHIPS)':
 'B': CDS_PINID='B';
NODE_NAME     C2U21 2
 '@BASEBOARD_FAB2_LIB.BASEBOARD_FAB2(SCH_1):PAGE108_I5@DEV_DISCRETE.CAP_A(CHIPS)':
 'B': CDS_PINID='B';
NODE_NAME     C2U25 2
 '@BASEBOARD_FAB2_LIB.BASEBOARD_FAB2(SCH_1):PAGE108_I7@DEV_DISCRETE.CAP_A(CHIPS)':
 'B': CDS_PINID='B';
NODE_NAME     J8G1 13
 '@BASEBOARD_FAB2_LIB.BASEBOARD_FAB2(SCH_1):PAGE108_I258@MSTR_SCONN.SCONN200_H68296001(CHIPS)':
 'IO13': CDS_PINID='IO13';
NODE_NAME     J8G1 14
 '@BASEBOARD_FAB2_LIB.BASEBOARD_FAB2(SCH_1):PAGE108_I258@MSTR_SCONN.SCONN200_H68296001(CHIPS)':
 'IO14': CDS_PINID='IO14';
NODE_NAME     J8G1 26
 '@BASEBOARD_FAB2_LIB.BASEBOARD_FAB2(SCH_1):PAGE108_I258@MSTR_SCONN.SCONN200_H68296001(CHIPS)':
 'IO26': CDS_PINID='IO26';
NODE_NAME     J8G1 31
 '@BASEBOARD_FAB2_LIB.BASEBOARD_FAB2(SCH_1):PAGE108_I258@MSTR_SCONN.SCONN200_H68296001(CHIPS)':
 'IO31': CDS_PINID='IO31';
NODE_NAME     J8G1 34
 '@BASEBOARD_FAB2_LIB.BASEBOARD_FAB2(SCH_1):PAGE108_I258@MSTR_SCONN.SCONN200_H68296001(CHIPS)':
 'IO34': CDS_PINID='IO34';
NODE_NAME     J8G1 37
 '@BASEBOARD_FAB2_LIB.BASEBOARD_FAB2(SCH_1):PAGE108_I258@MSTR_SCONN.SCONN200_H68296001(CHIPS)':
 'IO37': CDS_PINID='IO37';
NODE_NAME     J8G1 40
 '@BASEBOARD_FAB2_LIB.BASEBOARD_FAB2(SCH_1):PAGE108_I258@MSTR_SCONN.SCONN200_H68296001(CHIPS)':
 'IO40': CDS_PINID='IO40';
NODE_NAME     J8G1 43
 '@BASEBOARD_FAB2_LIB.BASEBOARD_FAB2(SCH_1):PAGE108_I258@MSTR_SCONN.SCONN200_H68296001(CHIPS)':
 'IO43': CDS_PINID='IO43';
NODE_NAME     J8G1 46
 '@BASEBOARD_FAB2_LIB.BASEBOARD_FAB2(SCH_1):PAGE108_I258@MSTR_SCONN.SCONN200_H68296001(CHIPS)':
 'IO46': CDS_PINID='IO46';
NODE_NAME     J8G1 49
 '@BASEBOARD_FAB2_LIB.BASEBOARD_FAB2(SCH_1):PAGE108_I258@MSTR_SCONN.SCONN200_H68296001(CHIPS)':
 'IO49': CDS_PINID='IO49';
NODE_NAME     J8G1 52
 '@BASEBOARD_FAB2_LIB.BASEBOARD_FAB2(SCH_1):PAGE108_I258@MSTR_SCONN.SCONN200_H68296001(CHIPS)':
 'IO52': CDS_PINID='IO52';
NODE_NAME     J8G1 55
 '@BASEBOARD_FAB2_LIB.BASEBOARD_FAB2(SCH_1):PAGE108_I258@MSTR_SCONN.SCONN200_H68296001(CHIPS)':
 'IO55': CDS_PINID='IO55';
NODE_NAME     J8G1 58
 '@BASEBOARD_FAB2_LIB.BASEBOARD_FAB2(SCH_1):PAGE108_I258@MSTR_SCONN.SCONN200_H68296001(CHIPS)':
 'IO58': CDS_PINID='IO58';
NODE_NAME     J8G1 61
 '@BASEBOARD_FAB2_LIB.BASEBOARD_FAB2(SCH_1):PAGE108_I258@MSTR_SCONN.SCONN200_H68296001(CHIPS)':
 'IO61': CDS_PINID='IO61';
NODE_NAME     J8G1 64
 '@BASEBOARD_FAB2_LIB.BASEBOARD_FAB2(SCH_1):PAGE108_I258@MSTR_SCONN.SCONN200_H68296001(CHIPS)':
 'IO64': CDS_PINID='IO64';
NODE_NAME     J8G1 65
 '@BASEBOARD_FAB2_LIB.BASEBOARD_FAB2(SCH_1):PAGE108_I258@MSTR_SCONN.SCONN200_H68296001(CHIPS)':
 'IO65': CDS_PINID='IO65';
NODE_NAME     J8G1 68
 '@BASEBOARD_FAB2_LIB.BASEBOARD_FAB2(SCH_1):PAGE108_I258@MSTR_SCONN.SCONN200_H68296001(CHIPS)':
 'IO68': CDS_PINID='IO68';
NODE_NAME     J8G1 71
 '@BASEBOARD_FAB2_LIB.BASEBOARD_FAB2(SCH_1):PAGE108_I258@MSTR_SCONN.SCONN200_H68296001(CHIPS)':
 'IO71': CDS_PINID='IO71';
NODE_NAME     J8G1 74
 '@BASEBOARD_FAB2_LIB.BASEBOARD_FAB2(SCH_1):PAGE108_I258@MSTR_SCONN.SCONN200_H68296001(CHIPS)':
 'IO74': CDS_PINID='IO74';
NODE_NAME     J8G1 77
 '@BASEBOARD_FAB2_LIB.BASEBOARD_FAB2(SCH_1):PAGE108_I258@MSTR_SCONN.SCONN200_H68296001(CHIPS)':
 'IO77': CDS_PINID='IO77';
NODE_NAME     J8G1 80
 '@BASEBOARD_FAB2_LIB.BASEBOARD_FAB2(SCH_1):PAGE108_I258@MSTR_SCONN.SCONN200_H68296001(CHIPS)':
 'IO80': CDS_PINID='IO80';
NODE_NAME     J8G1 83
 '@BASEBOARD_FAB2_LIB.BASEBOARD_FAB2(SCH_1):PAGE108_I258@MSTR_SCONN.SCONN200_H68296001(CHIPS)':
 'IO83': CDS_PINID='IO83';
NODE_NAME     J8G1 86
 '@BASEBOARD_FAB2_LIB.BASEBOARD_FAB2(SCH_1):PAGE108_I258@MSTR_SCONN.SCONN200_H68296001(CHIPS)':
 'IO86': CDS_PINID='IO86';
NODE_NAME     J8G1 89
 '@BASEBOARD_FAB2_LIB.BASEBOARD_FAB2(SCH_1):PAGE108_I258@MSTR_SCONN.SCONN200_H68296001(CHIPS)':
 'IO89': CDS_PINID='IO89';
NODE_NAME     J8G1 92
 '@BASEBOARD_FAB2_LIB.BASEBOARD_FAB2(SCH_1):PAGE108_I258@MSTR_SCONN.SCONN200_H68296001(CHIPS)':
 'IO92': CDS_PINID='IO92';
NODE_NAME     J8G1 95
 '@BASEBOARD_FAB2_LIB.BASEBOARD_FAB2(SCH_1):PAGE108_I258@MSTR_SCONN.SCONN200_H68296001(CHIPS)':
 'IO95': CDS_PINID='IO95';
NODE_NAME     J8G1 98
 '@BASEBOARD_FAB2_LIB.BASEBOARD_FAB2(SCH_1):PAGE108_I258@MSTR_SCONN.SCONN200_H68296001(CHIPS)':
 'IO98': CDS_PINID='IO98';
NODE_NAME     J8G1 MH1
 '@BASEBOARD_FAB2_LIB.BASEBOARD_FAB2(SCH_1):PAGE108_I258@MSTR_SCONN.SCONN200_H68296001(CHIPS)':
 'MH1': CDS_PINID='MH1';
NODE_NAME     J8G1 MH2
 '@BASEBOARD_FAB2_LIB.BASEBOARD_FAB2(SCH_1):PAGE108_I258@MSTR_SCONN.SCONN200_H68296001(CHIPS)':
 'MH2': CDS_PINID='MH2';
NODE_NAME     C2U23 2
 '@BASEBOARD_FAB2_LIB.BASEBOARD_FAB2(SCH_1):PAGE108_I315@DEV_DISCRETE.CAP_A(CHIPS)':
 'B': CDS_PINID='B';
NODE_NAME     C2U22 2
 '@BASEBOARD_FAB2_LIB.BASEBOARD_FAB2(SCH_1):PAGE108_I318@DEV_DISCRETE.CAP_A(CHIPS)':
 'B': CDS_PINID='B';
NODE_NAME     C9A2 2
 '@BASEBOARD_FAB2_LIB.BASEBOARD_FAB2(SCH_1):PAGE111_I10@DEV_DISCRETE.CAP_A(CHIPS)':
 'B': CDS_PINID='B';
NODE_NAME     C9A5 2
 '@BASEBOARD_FAB2_LIB.BASEBOARD_FAB2(SCH_1):PAGE111_I12@DEV_DISCRETE.CAP_A(CHIPS)':
 'B': CDS_PINID='B';
NODE_NAME     C1L8 2
 '@BASEBOARD_FAB2_LIB.BASEBOARD_FAB2(SCH_1):PAGE111_I14@DEV_DISCRETE.CAP_A(CHIPS)':
 'B': CDS_PINID='B';
NODE_NAME     C9A6 2
 '@BASEBOARD_FAB2_LIB.BASEBOARD_FAB2(SCH_1):PAGE111_I25@DEV_DISCRETE.CAP_A(CHIPS)':
 'B': CDS_PINID='B';
NODE_NAME     J9A3 2
 '@BASEBOARD_FAB2_LIB.BASEBOARD_FAB2(SCH_1):PAGE111_I26@MSTR_SCONN.SCONN60_C21100002(CHIPS)':
 'IO2': CDS_PINID='IO2';
NODE_NAME     J9A3 7
 '@BASEBOARD_FAB2_LIB.BASEBOARD_FAB2(SCH_1):PAGE111_I26@MSTR_SCONN.SCONN60_C21100002(CHIPS)':
 'IO7': CDS_PINID='IO7';
NODE_NAME     J9A3 8
 '@BASEBOARD_FAB2_LIB.BASEBOARD_FAB2(SCH_1):PAGE111_I26@MSTR_SCONN.SCONN60_C21100002(CHIPS)':
 'IO8': CDS_PINID='IO8';
NODE_NAME     J9A3 13
 '@BASEBOARD_FAB2_LIB.BASEBOARD_FAB2(SCH_1):PAGE111_I26@MSTR_SCONN.SCONN60_C21100002(CHIPS)':
 'IO13': CDS_PINID='IO13';
NODE_NAME     J9A3 14
 '@BASEBOARD_FAB2_LIB.BASEBOARD_FAB2(SCH_1):PAGE111_I26@MSTR_SCONN.SCONN60_C21100002(CHIPS)':
 'IO14': CDS_PINID='IO14';
NODE_NAME     J9A3 19
 '@BASEBOARD_FAB2_LIB.BASEBOARD_FAB2(SCH_1):PAGE111_I26@MSTR_SCONN.SCONN60_C21100002(CHIPS)':
 'IO19': CDS_PINID='IO19';
NODE_NAME     J9A3 20
 '@BASEBOARD_FAB2_LIB.BASEBOARD_FAB2(SCH_1):PAGE111_I26@MSTR_SCONN.SCONN60_C21100002(CHIPS)':
 'IO20': CDS_PINID='IO20';
NODE_NAME     J9A3 25
 '@BASEBOARD_FAB2_LIB.BASEBOARD_FAB2(SCH_1):PAGE111_I26@MSTR_SCONN.SCONN60_C21100002(CHIPS)':
 'IO25': CDS_PINID='IO25';
NODE_NAME     J9A3 26
 '@BASEBOARD_FAB2_LIB.BASEBOARD_FAB2(SCH_1):PAGE111_I26@MSTR_SCONN.SCONN60_C21100002(CHIPS)':
 'IO26': CDS_PINID='IO26';
NODE_NAME     J9A3 31
 '@BASEBOARD_FAB2_LIB.BASEBOARD_FAB2(SCH_1):PAGE111_I26@MSTR_SCONN.SCONN60_C21100002(CHIPS)':
 'IO31': CDS_PINID='IO31';
NODE_NAME     J9A3 32
 '@BASEBOARD_FAB2_LIB.BASEBOARD_FAB2(SCH_1):PAGE111_I26@MSTR_SCONN.SCONN60_C21100002(CHIPS)':
 'IO32': CDS_PINID='IO32';
NODE_NAME     J9A3 37
 '@BASEBOARD_FAB2_LIB.BASEBOARD_FAB2(SCH_1):PAGE111_I26@MSTR_SCONN.SCONN60_C21100002(CHIPS)':
 'IO37': CDS_PINID='IO37';
NODE_NAME     J9A3 38
 '@BASEBOARD_FAB2_LIB.BASEBOARD_FAB2(SCH_1):PAGE111_I26@MSTR_SCONN.SCONN60_C21100002(CHIPS)':
 'IO38': CDS_PINID='IO38';
NODE_NAME     J9A3 49
 '@BASEBOARD_FAB2_LIB.BASEBOARD_FAB2(SCH_1):PAGE111_I26@MSTR_SCONN.SCONN60_C21100002(CHIPS)':
 'IO49': CDS_PINID='IO49';
NODE_NAME     J9A3 50
 '@BASEBOARD_FAB2_LIB.BASEBOARD_FAB2(SCH_1):PAGE111_I26@MSTR_SCONN.SCONN60_C21100002(CHIPS)':
 'IO50': CDS_PINID='IO50';
NODE_NAME     J9A3 59
 '@BASEBOARD_FAB2_LIB.BASEBOARD_FAB2(SCH_1):PAGE111_I26@MSTR_SCONN.SCONN60_C21100002(CHIPS)':
 'IO59': CDS_PINID='IO59';
NODE_NAME     C1L5 2
 '@BASEBOARD_FAB2_LIB.BASEBOARD_FAB2(SCH_1):PAGE111_I30@DEV_DISCRETE.CAP_A(CHIPS)':
 'B': CDS_PINID='B';
NODE_NAME     C9A4 2
 '@BASEBOARD_FAB2_LIB.BASEBOARD_FAB2(SCH_1):PAGE111_I59@DEV_DISCRETE.CAP_A(CHIPS)':
 'B': CDS_PINID='B';
NODE_NAME     C1L11 2
 '@BASEBOARD_FAB2_LIB.BASEBOARD_FAB2(SCH_1):PAGE111_I87@DEV_DISCRETE.CAP_A(CHIPS)':
 'B': CDS_PINID='B';
NODE_NAME     U1M7 2
 '@BASEBOARD_FAB2_LIB.BASEBOARD_FAB2(SCH_1):PAGE112_I40@MSTR_ANALOG.NC7SB3157(CHIPS)':
 'GND': CDS_PINID='GND';
NODE_NAME     C1M36 2
 '@BASEBOARD_FAB2_LIB.BASEBOARD_FAB2(SCH_1):PAGE112_I42@DEV_DISCRETE.CAP_A(CHIPS)':
 'B': CDS_PINID='B';
NODE_NAME     C1M37 2
 '@BASEBOARD_FAB2_LIB.BASEBOARD_FAB2(SCH_1):PAGE112_I47@DEV_DISCRETE.CAP_A(CHIPS)':
 'B': CDS_PINID='B';
NODE_NAME     R7P29 2
 '@BASEBOARD_FAB2_LIB.BASEBOARD_FAB2(SCH_1):PAGE112_I61@MSTR_DISCRETE.RES(CHIPS)':
 'B': CDS_PINID='B';
NODE_NAME     R6T5 2
 '@BASEBOARD_FAB2_LIB.BASEBOARD_FAB2(SCH_1):PAGE112_I62@MSTR_DISCRETE.RES(CHIPS)':
 'B': CDS_PINID='B';
NODE_NAME     R3M10 2
 '@BASEBOARD_FAB2_LIB.BASEBOARD_FAB2(SCH_1):PAGE112_I85@MSTR_DISCRETE.RES(CHIPS)':
 'B': CDS_PINID='B';
NODE_NAME     R8B2 2
 '@BASEBOARD_FAB2_LIB.BASEBOARD_FAB2(SCH_1):PAGE112_I94@MSTR_DISCRETE.RES(CHIPS)':
 'B': CDS_PINID='B';
NODE_NAME     R8B1 2
 '@BASEBOARD_FAB2_LIB.BASEBOARD_FAB2(SCH_1):PAGE112_I95@MSTR_DISCRETE.RES(CHIPS)':
 'B': CDS_PINID='B';
NODE_NAME     C1M30 2
 '@BASEBOARD_FAB2_LIB.BASEBOARD_FAB2(SCH_1):PAGE112_I131@DEV_DISCRETE.CAP_A(CHIPS)':
 'B': CDS_PINID='B';
NODE_NAME     C1L1 2
 '@BASEBOARD_FAB2_LIB.BASEBOARD_FAB2(SCH_1):PAGE112_I136@MSTR_DISCRETE.CAP(CHIPS)':
 'B': CDS_PINID='B';
NODE_NAME     C1L19 2
 '@BASEBOARD_FAB2_LIB.BASEBOARD_FAB2(SCH_1):PAGE112_I140@MSTR_DISCRETE.CAP(CHIPS)':
 'B': CDS_PINID='B';
NODE_NAME     U1M2 2
 '@BASEBOARD_FAB2_LIB.BASEBOARD_FAB2(SCH_1):PAGE113_I107@MSTR_ANALOG.NC7SB3157(CHIPS)':
 'GND': CDS_PINID='GND';
NODE_NAME     C1M31 2
 '@BASEBOARD_FAB2_LIB.BASEBOARD_FAB2(SCH_1):PAGE113_I116@DEV_DISCRETE.CAP_A(CHIPS)':
 'B': CDS_PINID='B';
NODE_NAME     C1M32 2
 '@BASEBOARD_FAB2_LIB.BASEBOARD_FAB2(SCH_1):PAGE113_I117@DEV_DISCRETE.CAP_A(CHIPS)':
 'B': CDS_PINID='B';
NODE_NAME     C1M28 2
 '@BASEBOARD_FAB2_LIB.BASEBOARD_FAB2(SCH_1):PAGE113_I119@DEV_DISCRETE.CAP_A(CHIPS)':
 'B': CDS_PINID='B';
NODE_NAME     C1M29 2
 '@BASEBOARD_FAB2_LIB.BASEBOARD_FAB2(SCH_1):PAGE113_I147@DEV_DISCRETE.CAP_A(CHIPS)':
 'B': CDS_PINID='B';
NODE_NAME     J9B4 2
 '@BASEBOARD_FAB2_LIB.BASEBOARD_FAB2(SCH_1):PAGE113_I175@MSTR_SCONN.SCONN10_C12536004(CHIPS)':
 'IO2': CDS_PINID='IO2';
NODE_NAME     J9B4 10
 '@BASEBOARD_FAB2_LIB.BASEBOARD_FAB2(SCH_1):PAGE113_I175@MSTR_SCONN.SCONN10_C12536004(CHIPS)':
 'IO10': CDS_PINID='IO10';
NODE_NAME     R9B9 2
 '@BASEBOARD_FAB2_LIB.BASEBOARD_FAB2(SCH_1):PAGE113_I179@MSTR_DISCRETE.RES(CHIPS)':
 'B': CDS_PINID='B';
NODE_NAME     U9A5 4
 '@BASEBOARD_FAB2_LIB.BASEBOARD_FAB2(SCH_1):PAGE113_I185@MSTR_TTL.74CBTLV1G125(CHIPS)':
 'B': CDS_PINID='B';
NODE_NAME     R1M23 2
 '@BASEBOARD_FAB2_LIB.BASEBOARD_FAB2(SCH_1):PAGE113_I199@MSTR_DISCRETE.RES(CHIPS)':
 'B': CDS_PINID='B';
NODE_NAME     C4R2 2
 '@BASEBOARD_FAB2_LIB.BASEBOARD_FAB2(SCH_1):PAGE113_I246@DEV_DISCRETE.CAP_A(CHIPS)':
 'B': CDS_PINID='B';
NODE_NAME     C1M33 2
 '@BASEBOARD_FAB2_LIB.BASEBOARD_FAB2(SCH_1):PAGE113_I248@DEV_DISCRETE.CAP_A(CHIPS)':
 'B': CDS_PINID='B';
NODE_NAME     C6M6 2
 '@BASEBOARD_FAB2_LIB.BASEBOARD_FAB2(SCH_1):PAGE113_I250@DEV_DISCRETE.CAP_A(CHIPS)':
 'B': CDS_PINID='B';
NODE_NAME     U2M1 2
 '@BASEBOARD_FAB2_LIB.BASEBOARD_FAB2(SCH_1):PAGE113_I255@MSTR_ANALOG.NC7SB3157(CHIPS)':
 'GND': CDS_PINID='GND';
NODE_NAME     C1M34 2
 '@BASEBOARD_FAB2_LIB.BASEBOARD_FAB2(SCH_1):PAGE113_I265@DEV_DISCRETE.CAP_A(CHIPS)':
 'B': CDS_PINID='B';
NODE_NAME     C1M35 2
 '@BASEBOARD_FAB2_LIB.BASEBOARD_FAB2(SCH_1):PAGE113_I266@DEV_DISCRETE.CAP_A(CHIPS)':
 'B': CDS_PINID='B';
NODE_NAME     C1L20 2
 '@BASEBOARD_FAB2_LIB.BASEBOARD_FAB2(SCH_1):PAGE113_I267@DEV_DISCRETE.CAP_A(CHIPS)':
 'B': CDS_PINID='B';
NODE_NAME     C7C5 2
 '@BASEBOARD_FAB2_LIB.BASEBOARD_FAB2(SCH_1):PAGE114_I47@MSTR_DISCRETE.CAP(CHIPS)':
 'B': CDS_PINID='B';
NODE_NAME     C7C4 2
 '@BASEBOARD_FAB2_LIB.BASEBOARD_FAB2(SCH_1):PAGE114_I50@MSTR_DISCRETE.CAP(CHIPS)':
 'B': CDS_PINID='B';
NODE_NAME     R8B21 2
 '@BASEBOARD_FAB2_LIB.BASEBOARD_FAB2(SCH_1):PAGE114_I124@MSTR_DISCRETE.RES(CHIPS)':
 'B': CDS_PINID='B';
NODE_NAME     R3N1 2
 '@BASEBOARD_FAB2_LIB.BASEBOARD_FAB2(SCH_1):PAGE114_I149@MSTR_DISCRETE.RES(CHIPS)':
 'B': CDS_PINID='B';
NODE_NAME     R8B9 2
 '@BASEBOARD_FAB2_LIB.BASEBOARD_FAB2(SCH_1):PAGE115_I90@MSTR_DISCRETE.RES(CHIPS)':
 'B': CDS_PINID='B';
NODE_NAME     R8B32 2
 '@BASEBOARD_FAB2_LIB.BASEBOARD_FAB2(SCH_1):PAGE115_I114@MSTR_DISCRETE.RES(CHIPS)':
 'B': CDS_PINID='B';
NODE_NAME     R7B8 2
 '@BASEBOARD_FAB2_LIB.BASEBOARD_FAB2(SCH_1):PAGE116_I229@MSTR_DISCRETE.RES(CHIPS)':
 'B': CDS_PINID='B';
NODE_NAME     R7B7 2
 '@BASEBOARD_FAB2_LIB.BASEBOARD_FAB2(SCH_1):PAGE116_I230@MSTR_DISCRETE.RES(CHIPS)':
 'B': CDS_PINID='B';
NODE_NAME     R3M9 2
 '@BASEBOARD_FAB2_LIB.BASEBOARD_FAB2(SCH_1):PAGE116_I234@MSTR_DISCRETE.RES(CHIPS)':
 'B': CDS_PINID='B';
NODE_NAME     R3M8 2
 '@BASEBOARD_FAB2_LIB.BASEBOARD_FAB2(SCH_1):PAGE116_I235@MSTR_DISCRETE.RES(CHIPS)':
 'B': CDS_PINID='B';
NODE_NAME     R3N14 2
 '@BASEBOARD_FAB2_LIB.BASEBOARD_FAB2(SCH_1):PAGE118_I67@MSTR_DISCRETE.RES(CHIPS)':
 'B': CDS_PINID='B';
NODE_NAME     C7D1 2
 '@BASEBOARD_FAB2_LIB.BASEBOARD_FAB2(SCH_1):PAGE118_I136@DEV_DISCRETE.CAP_A(CHIPS)':
 'B': CDS_PINID='B';
NODE_NAME     Q9A2 1
 '@BASEBOARD_FAB2_LIB.BASEBOARD_FAB2(SCH_1):PAGE119_I175@MSTR_DISCRETE.FET_N_DUAL(CHIPS)':
 'SOURCE'<0>: CDS_PINID='SOURCE(0)';
NODE_NAME     Q9A2 4
 '@BASEBOARD_FAB2_LIB.BASEBOARD_FAB2(SCH_1):PAGE119_I180@MSTR_DISCRETE.FET_N_DUAL(CHIPS)':
 'SOURCE'<0>: CDS_PINID='SOURCE(0)';
NODE_NAME     R8C26 2
 '@BASEBOARD_FAB2_LIB.BASEBOARD_FAB2(SCH_1):PAGE121_I35@MSTR_DISCRETE.RES(CHIPS)':
 'B': CDS_PINID='B';
NODE_NAME     R7C20 2
 '@BASEBOARD_FAB2_LIB.BASEBOARD_FAB2(SCH_1):PAGE121_I73@MSTR_DISCRETE.RES(CHIPS)':
 'B': CDS_PINID='B';
NODE_NAME     U7C1 N31
 '@BASEBOARD_FAB2_LIB.BASEBOARD_FAB2(SCH_1):PAGE123_I13@MSTR_U_PROC.LBG_CORE_QAT_EXT_D(CHIPS)':
 'VSS'<355>: CDS_PINID='VSS(355)';
NODE_NAME     U7C1 N27
 '@BASEBOARD_FAB2_LIB.BASEBOARD_FAB2(SCH_1):PAGE123_I13@MSTR_U_PROC.LBG_CORE_QAT_EXT_D(CHIPS)':
 'VSS'<356>: CDS_PINID='VSS(356)';
NODE_NAME     U7C1 N24
 '@BASEBOARD_FAB2_LIB.BASEBOARD_FAB2(SCH_1):PAGE123_I13@MSTR_U_PROC.LBG_CORE_QAT_EXT_D(CHIPS)':
 'VSS'<357>: CDS_PINID='VSS(357)';
NODE_NAME     U7C1 N20
 '@BASEBOARD_FAB2_LIB.BASEBOARD_FAB2(SCH_1):PAGE123_I13@MSTR_U_PROC.LBG_CORE_QAT_EXT_D(CHIPS)':
 'VSS'<358>: CDS_PINID='VSS(358)';
NODE_NAME     U7C1 N17
 '@BASEBOARD_FAB2_LIB.BASEBOARD_FAB2(SCH_1):PAGE123_I13@MSTR_U_PROC.LBG_CORE_QAT_EXT_D(CHIPS)':
 'VSS'<359>: CDS_PINID='VSS(359)';
NODE_NAME     U7C1 N13
 '@BASEBOARD_FAB2_LIB.BASEBOARD_FAB2(SCH_1):PAGE123_I13@MSTR_U_PROC.LBG_CORE_QAT_EXT_D(CHIPS)':
 'VSS'<360>: CDS_PINID='VSS(360)';
NODE_NAME     U7C1 M48
 '@BASEBOARD_FAB2_LIB.BASEBOARD_FAB2(SCH_1):PAGE123_I13@MSTR_U_PROC.LBG_CORE_QAT_EXT_D(CHIPS)':
 'VSS'<361>: CDS_PINID='VSS(361)';
NODE_NAME     U7C1 M44
 '@BASEBOARD_FAB2_LIB.BASEBOARD_FAB2(SCH_1):PAGE123_I13@MSTR_U_PROC.LBG_CORE_QAT_EXT_D(CHIPS)':
 'VSS'<362>: CDS_PINID='VSS(362)';
NODE_NAME     U7C1 N50
 '@BASEBOARD_FAB2_LIB.BASEBOARD_FAB2(SCH_1):PAGE123_I13@MSTR_U_PROC.LBG_CORE_QAT_EXT_D(CHIPS)':
 'VSS'<363>: CDS_PINID='VSS(363)';
NODE_NAME     U7C1 N42
 '@BASEBOARD_FAB2_LIB.BASEBOARD_FAB2(SCH_1):PAGE123_I13@MSTR_U_PROC.LBG_CORE_QAT_EXT_D(CHIPS)':
 'VSS'<364>: CDS_PINID='VSS(364)';
NODE_NAME     U7C1 M40
 '@BASEBOARD_FAB2_LIB.BASEBOARD_FAB2(SCH_1):PAGE123_I13@MSTR_U_PROC.LBG_CORE_QAT_EXT_D(CHIPS)':
 'VSS'<365>: CDS_PINID='VSS(365)';
NODE_NAME     U7C1 M4
 '@BASEBOARD_FAB2_LIB.BASEBOARD_FAB2(SCH_1):PAGE123_I13@MSTR_U_PROC.LBG_CORE_QAT_EXT_D(CHIPS)':
 'VSS'<366>: CDS_PINID='VSS(366)';
NODE_NAME     U7C1 M37
 '@BASEBOARD_FAB2_LIB.BASEBOARD_FAB2(SCH_1):PAGE123_I13@MSTR_U_PROC.LBG_CORE_QAT_EXT_D(CHIPS)':
 'VSS'<367>: CDS_PINID='VSS(367)';
NODE_NAME     U7C1 M33
 '@BASEBOARD_FAB2_LIB.BASEBOARD_FAB2(SCH_1):PAGE123_I13@MSTR_U_PROC.LBG_CORE_QAT_EXT_D(CHIPS)':
 'VSS'<368>: CDS_PINID='VSS(368)';
NODE_NAME     U7C1 M29
 '@BASEBOARD_FAB2_LIB.BASEBOARD_FAB2(SCH_1):PAGE123_I13@MSTR_U_PROC.LBG_CORE_QAT_EXT_D(CHIPS)':
 'VSS'<369>: CDS_PINID='VSS(369)';
NODE_NAME     U7C1 M26
 '@BASEBOARD_FAB2_LIB.BASEBOARD_FAB2(SCH_1):PAGE123_I13@MSTR_U_PROC.LBG_CORE_QAT_EXT_D(CHIPS)':
 'VSS'<370>: CDS_PINID='VSS(370)';
NODE_NAME     U7C1 M22
 '@BASEBOARD_FAB2_LIB.BASEBOARD_FAB2(SCH_1):PAGE123_I13@MSTR_U_PROC.LBG_CORE_QAT_EXT_D(CHIPS)':
 'VSS'<371>: CDS_PINID='VSS(371)';
NODE_NAME     U7C1 M2
 '@BASEBOARD_FAB2_LIB.BASEBOARD_FAB2(SCH_1):PAGE123_I13@MSTR_U_PROC.LBG_CORE_QAT_EXT_D(CHIPS)':
 'VSS'<372>: CDS_PINID='VSS(372)';
NODE_NAME     U7C1 L68
 '@BASEBOARD_FAB2_LIB.BASEBOARD_FAB2(SCH_1):PAGE123_I13@MSTR_U_PROC.LBG_CORE_QAT_EXT_D(CHIPS)':
 'VSS'<373>: CDS_PINID='VSS(373)';
NODE_NAME     U7C1 L5
 '@BASEBOARD_FAB2_LIB.BASEBOARD_FAB2(SCH_1):PAGE123_I13@MSTR_U_PROC.LBG_CORE_QAT_EXT_D(CHIPS)':
 'VSS'<374>: CDS_PINID='VSS(374)';
NODE_NAME     U7C1 K71
 '@BASEBOARD_FAB2_LIB.BASEBOARD_FAB2(SCH_1):PAGE123_I13@MSTR_U_PROC.LBG_CORE_QAT_EXT_D(CHIPS)':
 'VSS'<375>: CDS_PINID='VSS(375)';
NODE_NAME     U7C1 K69
 '@BASEBOARD_FAB2_LIB.BASEBOARD_FAB2(SCH_1):PAGE123_I13@MSTR_U_PROC.LBG_CORE_QAT_EXT_D(CHIPS)':
 'VSS'<376>: CDS_PINID='VSS(376)';
NODE_NAME     U7C1 K54
 '@BASEBOARD_FAB2_LIB.BASEBOARD_FAB2(SCH_1):PAGE123_I13@MSTR_U_PROC.LBG_CORE_QAT_EXT_D(CHIPS)':
 'VSS'<377>: CDS_PINID='VSS(377)';
NODE_NAME     U7C1 J70
 '@BASEBOARD_FAB2_LIB.BASEBOARD_FAB2(SCH_1):PAGE123_I13@MSTR_U_PROC.LBG_CORE_QAT_EXT_D(CHIPS)':
 'VSS'<378>: CDS_PINID='VSS(378)';
NODE_NAME     U7C1 J68
 '@BASEBOARD_FAB2_LIB.BASEBOARD_FAB2(SCH_1):PAGE123_I13@MSTR_U_PROC.LBG_CORE_QAT_EXT_D(CHIPS)':
 'VSS'<379>: CDS_PINID='VSS(379)';
NODE_NAME     U7C1 J59
 '@BASEBOARD_FAB2_LIB.BASEBOARD_FAB2(SCH_1):PAGE123_I13@MSTR_U_PROC.LBG_CORE_QAT_EXT_D(CHIPS)':
 'VSS'<380>: CDS_PINID='VSS(380)';
NODE_NAME     U7C1 J44
 '@BASEBOARD_FAB2_LIB.BASEBOARD_FAB2(SCH_1):PAGE123_I13@MSTR_U_PROC.LBG_CORE_QAT_EXT_D(CHIPS)':
 'VSS'<381>: CDS_PINID='VSS(381)';
NODE_NAME     U7C1 J37
 '@BASEBOARD_FAB2_LIB.BASEBOARD_FAB2(SCH_1):PAGE123_I13@MSTR_U_PROC.LBG_CORE_QAT_EXT_D(CHIPS)':
 'VSS'<382>: CDS_PINID='VSS(382)';
NODE_NAME     U7C1 J22
 '@BASEBOARD_FAB2_LIB.BASEBOARD_FAB2(SCH_1):PAGE123_I13@MSTR_U_PROC.LBG_CORE_QAT_EXT_D(CHIPS)':
 'VSS'<383>: CDS_PINID='VSS(383)';
NODE_NAME     U7C1 J15
 '@BASEBOARD_FAB2_LIB.BASEBOARD_FAB2(SCH_1):PAGE123_I13@MSTR_U_PROC.LBG_CORE_QAT_EXT_D(CHIPS)':
 'VSS'<384>: CDS_PINID='VSS(384)';
NODE_NAME     U7C1 J11
 '@BASEBOARD_FAB2_LIB.BASEBOARD_FAB2(SCH_1):PAGE123_I13@MSTR_U_PROC.LBG_CORE_QAT_EXT_D(CHIPS)':
 'VSS'<385>: CDS_PINID='VSS(385)';
NODE_NAME     U7C1 H65
 '@BASEBOARD_FAB2_LIB.BASEBOARD_FAB2(SCH_1):PAGE123_I13@MSTR_U_PROC.LBG_CORE_QAT_EXT_D(CHIPS)':
 'VSS'<386>: CDS_PINID='VSS(386)';
NODE_NAME     U7C1 J7
 '@BASEBOARD_FAB2_LIB.BASEBOARD_FAB2(SCH_1):PAGE123_I13@MSTR_U_PROC.LBG_CORE_QAT_EXT_D(CHIPS)':
 'VSS'<387>: CDS_PINID='VSS(387)';
NODE_NAME     U7C1 J5
 '@BASEBOARD_FAB2_LIB.BASEBOARD_FAB2(SCH_1):PAGE123_I13@MSTR_U_PROC.LBG_CORE_QAT_EXT_D(CHIPS)':
 'VSS'<388>: CDS_PINID='VSS(388)';
NODE_NAME     U7C1 J29
 '@BASEBOARD_FAB2_LIB.BASEBOARD_FAB2(SCH_1):PAGE123_I13@MSTR_U_PROC.LBG_CORE_QAT_EXT_D(CHIPS)':
 'VSS'<389>: CDS_PINID='VSS(389)';
NODE_NAME     U7C1 H58
 '@BASEBOARD_FAB2_LIB.BASEBOARD_FAB2(SCH_1):PAGE123_I13@MSTR_U_PROC.LBG_CORE_QAT_EXT_D(CHIPS)':
 'VSS'<390>: CDS_PINID='VSS(390)';
NODE_NAME     U7C1 G66
 '@BASEBOARD_FAB2_LIB.BASEBOARD_FAB2(SCH_1):PAGE123_I13@MSTR_U_PROC.LBG_CORE_QAT_EXT_D(CHIPS)':
 'VSS'<391>: CDS_PINID='VSS(391)';
NODE_NAME     U7C1 G63
 '@BASEBOARD_FAB2_LIB.BASEBOARD_FAB2(SCH_1):PAGE123_I13@MSTR_U_PROC.LBG_CORE_QAT_EXT_D(CHIPS)':
 'VSS'<392>: CDS_PINID='VSS(392)';
NODE_NAME     U7C1 G6
 '@BASEBOARD_FAB2_LIB.BASEBOARD_FAB2(SCH_1):PAGE123_I13@MSTR_U_PROC.LBG_CORE_QAT_EXT_D(CHIPS)':
 'VSS'<393>: CDS_PINID='VSS(393)';
NODE_NAME     U7C1 G48
 '@BASEBOARD_FAB2_LIB.BASEBOARD_FAB2(SCH_1):PAGE123_I13@MSTR_U_PROC.LBG_CORE_QAT_EXT_D(CHIPS)':
 'VSS'<394>: CDS_PINID='VSS(394)';
NODE_NAME     U7C1 G37
 '@BASEBOARD_FAB2_LIB.BASEBOARD_FAB2(SCH_1):PAGE123_I13@MSTR_U_PROC.LBG_CORE_QAT_EXT_D(CHIPS)':
 'VSS'<395>: CDS_PINID='VSS(395)';
NODE_NAME     U7C1 G29
 '@BASEBOARD_FAB2_LIB.BASEBOARD_FAB2(SCH_1):PAGE123_I13@MSTR_U_PROC.LBG_CORE_QAT_EXT_D(CHIPS)':
 'VSS'<396>: CDS_PINID='VSS(396)';
NODE_NAME     U7C1 G22
 '@BASEBOARD_FAB2_LIB.BASEBOARD_FAB2(SCH_1):PAGE123_I13@MSTR_U_PROC.LBG_CORE_QAT_EXT_D(CHIPS)':
 'VSS'<397>: CDS_PINID='VSS(397)';
NODE_NAME     U7C1 E9
 '@BASEBOARD_FAB2_LIB.BASEBOARD_FAB2(SCH_1):PAGE123_I13@MSTR_U_PROC.LBG_CORE_QAT_EXT_D(CHIPS)':
 'VSS'<398>: CDS_PINID='VSS(398)';
NODE_NAME     U7C1 G59
 '@BASEBOARD_FAB2_LIB.BASEBOARD_FAB2(SCH_1):PAGE123_I13@MSTR_U_PROC.LBG_CORE_QAT_EXT_D(CHIPS)':
 'VSS'<399>: CDS_PINID='VSS(399)';
NODE_NAME     U7C1 E63
 '@BASEBOARD_FAB2_LIB.BASEBOARD_FAB2(SCH_1):PAGE123_I13@MSTR_U_PROC.LBG_CORE_QAT_EXT_D(CHIPS)':
 'VSS'<400>: CDS_PINID='VSS(400)';
NODE_NAME     U7C1 E61
 '@BASEBOARD_FAB2_LIB.BASEBOARD_FAB2(SCH_1):PAGE123_I13@MSTR_U_PROC.LBG_CORE_QAT_EXT_D(CHIPS)':
 'VSS'<401>: CDS_PINID='VSS(401)';
NODE_NAME     U7C1 E6
 '@BASEBOARD_FAB2_LIB.BASEBOARD_FAB2(SCH_1):PAGE123_I13@MSTR_U_PROC.LBG_CORE_QAT_EXT_D(CHIPS)':
 'VSS'<402>: CDS_PINID='VSS(402)';
NODE_NAME     U7C1 E57
 '@BASEBOARD_FAB2_LIB.BASEBOARD_FAB2(SCH_1):PAGE123_I13@MSTR_U_PROC.LBG_CORE_QAT_EXT_D(CHIPS)':
 'VSS'<403>: CDS_PINID='VSS(403)';
NODE_NAME     U7C1 E54
 '@BASEBOARD_FAB2_LIB.BASEBOARD_FAB2(SCH_1):PAGE123_I13@MSTR_U_PROC.LBG_CORE_QAT_EXT_D(CHIPS)':
 'VSS'<404>: CDS_PINID='VSS(404)';
NODE_NAME     U7C1 E52
 '@BASEBOARD_FAB2_LIB.BASEBOARD_FAB2(SCH_1):PAGE123_I13@MSTR_U_PROC.LBG_CORE_QAT_EXT_D(CHIPS)':
 'VSS'<405>: CDS_PINID='VSS(405)';
NODE_NAME     U7C1 E50
 '@BASEBOARD_FAB2_LIB.BASEBOARD_FAB2(SCH_1):PAGE123_I13@MSTR_U_PROC.LBG_CORE_QAT_EXT_D(CHIPS)':
 'VSS'<406>: CDS_PINID='VSS(406)';
NODE_NAME     U7C1 E48
 '@BASEBOARD_FAB2_LIB.BASEBOARD_FAB2(SCH_1):PAGE123_I13@MSTR_U_PROC.LBG_CORE_QAT_EXT_D(CHIPS)':
 'VSS'<407>: CDS_PINID='VSS(407)';
NODE_NAME     U7C1 E45
 '@BASEBOARD_FAB2_LIB.BASEBOARD_FAB2(SCH_1):PAGE123_I13@MSTR_U_PROC.LBG_CORE_QAT_EXT_D(CHIPS)':
 'VSS'<408>: CDS_PINID='VSS(408)';
NODE_NAME     U7C1 E43
 '@BASEBOARD_FAB2_LIB.BASEBOARD_FAB2(SCH_1):PAGE123_I13@MSTR_U_PROC.LBG_CORE_QAT_EXT_D(CHIPS)':
 'VSS'<409>: CDS_PINID='VSS(409)';
NODE_NAME     U7C1 E41
 '@BASEBOARD_FAB2_LIB.BASEBOARD_FAB2(SCH_1):PAGE123_I13@MSTR_U_PROC.LBG_CORE_QAT_EXT_D(CHIPS)':
 'VSS'<410>: CDS_PINID='VSS(410)';
NODE_NAME     U7C1 E39
 '@BASEBOARD_FAB2_LIB.BASEBOARD_FAB2(SCH_1):PAGE123_I13@MSTR_U_PROC.LBG_CORE_QAT_EXT_D(CHIPS)':
 'VSS'<411>: CDS_PINID='VSS(411)';
NODE_NAME     U7C1 E37
 '@BASEBOARD_FAB2_LIB.BASEBOARD_FAB2(SCH_1):PAGE123_I13@MSTR_U_PROC.LBG_CORE_QAT_EXT_D(CHIPS)':
 'VSS'<412>: CDS_PINID='VSS(412)';
NODE_NAME     U7C1 E34
 '@BASEBOARD_FAB2_LIB.BASEBOARD_FAB2(SCH_1):PAGE123_I13@MSTR_U_PROC.LBG_CORE_QAT_EXT_D(CHIPS)':
 'VSS'<413>: CDS_PINID='VSS(413)';
NODE_NAME     U7C1 E32
 '@BASEBOARD_FAB2_LIB.BASEBOARD_FAB2(SCH_1):PAGE123_I13@MSTR_U_PROC.LBG_CORE_QAT_EXT_D(CHIPS)':
 'VSS'<414>: CDS_PINID='VSS(414)';
NODE_NAME     U7C1 E30
 '@BASEBOARD_FAB2_LIB.BASEBOARD_FAB2(SCH_1):PAGE123_I13@MSTR_U_PROC.LBG_CORE_QAT_EXT_D(CHIPS)':
 'VSS'<415>: CDS_PINID='VSS(415)';
NODE_NAME     U7C1 E28
 '@BASEBOARD_FAB2_LIB.BASEBOARD_FAB2(SCH_1):PAGE123_I13@MSTR_U_PROC.LBG_CORE_QAT_EXT_D(CHIPS)':
 'VSS'<416>: CDS_PINID='VSS(416)';
NODE_NAME     U7C1 E26
 '@BASEBOARD_FAB2_LIB.BASEBOARD_FAB2(SCH_1):PAGE123_I13@MSTR_U_PROC.LBG_CORE_QAT_EXT_D(CHIPS)':
 'VSS'<417>: CDS_PINID='VSS(417)';
NODE_NAME     U7C1 E24
 '@BASEBOARD_FAB2_LIB.BASEBOARD_FAB2(SCH_1):PAGE123_I13@MSTR_U_PROC.LBG_CORE_QAT_EXT_D(CHIPS)':
 'VSS'<418>: CDS_PINID='VSS(418)';
NODE_NAME     U7C1 E22
 '@BASEBOARD_FAB2_LIB.BASEBOARD_FAB2(SCH_1):PAGE123_I13@MSTR_U_PROC.LBG_CORE_QAT_EXT_D(CHIPS)':
 'VSS'<419>: CDS_PINID='VSS(419)';
NODE_NAME     U7C1 E20
 '@BASEBOARD_FAB2_LIB.BASEBOARD_FAB2(SCH_1):PAGE123_I13@MSTR_U_PROC.LBG_CORE_QAT_EXT_D(CHIPS)':
 'VSS'<420>: CDS_PINID='VSS(420)';
NODE_NAME     U7C1 E15
 '@BASEBOARD_FAB2_LIB.BASEBOARD_FAB2(SCH_1):PAGE123_I13@MSTR_U_PROC.LBG_CORE_QAT_EXT_D(CHIPS)':
 'VSS'<421>: CDS_PINID='VSS(421)';
NODE_NAME     U7C1 E13
 '@BASEBOARD_FAB2_LIB.BASEBOARD_FAB2(SCH_1):PAGE123_I13@MSTR_U_PROC.LBG_CORE_QAT_EXT_D(CHIPS)':
 'VSS'<422>: CDS_PINID='VSS(422)';
NODE_NAME     U7C1 E11
 '@BASEBOARD_FAB2_LIB.BASEBOARD_FAB2(SCH_1):PAGE123_I13@MSTR_U_PROC.LBG_CORE_QAT_EXT_D(CHIPS)':
 'VSS'<423>: CDS_PINID='VSS(423)';
NODE_NAME     U7C1 D47
 '@BASEBOARD_FAB2_LIB.BASEBOARD_FAB2(SCH_1):PAGE123_I13@MSTR_U_PROC.LBG_CORE_QAT_EXT_D(CHIPS)':
 'VSS'<424>: CDS_PINID='VSS(424)';
NODE_NAME     U7C1 E65
 '@BASEBOARD_FAB2_LIB.BASEBOARD_FAB2(SCH_1):PAGE123_I13@MSTR_U_PROC.LBG_CORE_QAT_EXT_D(CHIPS)':
 'VSS'<425>: CDS_PINID='VSS(425)';
NODE_NAME     U7C1 E59
 '@BASEBOARD_FAB2_LIB.BASEBOARD_FAB2(SCH_1):PAGE123_I13@MSTR_U_PROC.LBG_CORE_QAT_EXT_D(CHIPS)':
 'VSS'<426>: CDS_PINID='VSS(426)';
NODE_NAME     U7C1 D27
 '@BASEBOARD_FAB2_LIB.BASEBOARD_FAB2(SCH_1):PAGE123_I13@MSTR_U_PROC.LBG_CORE_QAT_EXT_D(CHIPS)':
 'VSS'<427>: CDS_PINID='VSS(427)';
NODE_NAME     U7C1 D25
 '@BASEBOARD_FAB2_LIB.BASEBOARD_FAB2(SCH_1):PAGE123_I13@MSTR_U_PROC.LBG_CORE_QAT_EXT_D(CHIPS)':
 'VSS'<428>: CDS_PINID='VSS(428)';
NODE_NAME     U7C1 D19
 '@BASEBOARD_FAB2_LIB.BASEBOARD_FAB2(SCH_1):PAGE123_I13@MSTR_U_PROC.LBG_CORE_QAT_EXT_D(CHIPS)':
 'VSS'<429>: CDS_PINID='VSS(429)';
NODE_NAME     U7C1 D16
 '@BASEBOARD_FAB2_LIB.BASEBOARD_FAB2(SCH_1):PAGE123_I13@MSTR_U_PROC.LBG_CORE_QAT_EXT_D(CHIPS)':
 'VSS'<430>: CDS_PINID='VSS(430)';
NODE_NAME     U7C1 D12
 '@BASEBOARD_FAB2_LIB.BASEBOARD_FAB2(SCH_1):PAGE123_I13@MSTR_U_PROC.LBG_CORE_QAT_EXT_D(CHIPS)':
 'VSS'<431>: CDS_PINID='VSS(431)';
NODE_NAME     U7C1 C65
 '@BASEBOARD_FAB2_LIB.BASEBOARD_FAB2(SCH_1):PAGE123_I13@MSTR_U_PROC.LBG_CORE_QAT_EXT_D(CHIPS)':
 'VSS'<432>: CDS_PINID='VSS(432)';
NODE_NAME     U7C1 C41
 '@BASEBOARD_FAB2_LIB.BASEBOARD_FAB2(SCH_1):PAGE123_I13@MSTR_U_PROC.LBG_CORE_QAT_EXT_D(CHIPS)':
 'VSS'<433>: CDS_PINID='VSS(433)';
NODE_NAME     U7C1 C37
 '@BASEBOARD_FAB2_LIB.BASEBOARD_FAB2(SCH_1):PAGE123_I13@MSTR_U_PROC.LBG_CORE_QAT_EXT_D(CHIPS)':
 'VSS'<434>: CDS_PINID='VSS(434)';
NODE_NAME     U7C1 C34
 '@BASEBOARD_FAB2_LIB.BASEBOARD_FAB2(SCH_1):PAGE123_I13@MSTR_U_PROC.LBG_CORE_QAT_EXT_D(CHIPS)':
 'VSS'<435>: CDS_PINID='VSS(435)';
NODE_NAME     U7C1 C30
 '@BASEBOARD_FAB2_LIB.BASEBOARD_FAB2(SCH_1):PAGE123_I13@MSTR_U_PROC.LBG_CORE_QAT_EXT_D(CHIPS)':
 'VSS'<436>: CDS_PINID='VSS(436)';
NODE_NAME     U7C1 C22
 '@BASEBOARD_FAB2_LIB.BASEBOARD_FAB2(SCH_1):PAGE123_I13@MSTR_U_PROC.LBG_CORE_QAT_EXT_D(CHIPS)':
 'VSS'<437>: CDS_PINID='VSS(437)';
NODE_NAME     U7C1 B47
 '@BASEBOARD_FAB2_LIB.BASEBOARD_FAB2(SCH_1):PAGE123_I13@MSTR_U_PROC.LBG_CORE_QAT_EXT_D(CHIPS)':
 'VSS'<438>: CDS_PINID='VSS(438)';
NODE_NAME     U7C1 B27
 '@BASEBOARD_FAB2_LIB.BASEBOARD_FAB2(SCH_1):PAGE123_I13@MSTR_U_PROC.LBG_CORE_QAT_EXT_D(CHIPS)':
 'VSS'<439>: CDS_PINID='VSS(439)';
NODE_NAME     U7C1 B25
 '@BASEBOARD_FAB2_LIB.BASEBOARD_FAB2(SCH_1):PAGE123_I13@MSTR_U_PROC.LBG_CORE_QAT_EXT_D(CHIPS)':
 'VSS'<440>: CDS_PINID='VSS(440)';
NODE_NAME     U7C1 B19
 '@BASEBOARD_FAB2_LIB.BASEBOARD_FAB2(SCH_1):PAGE123_I13@MSTR_U_PROC.LBG_CORE_QAT_EXT_D(CHIPS)':
 'VSS'<441>: CDS_PINID='VSS(441)';
NODE_NAME     U7C1 B12
 '@BASEBOARD_FAB2_LIB.BASEBOARD_FAB2(SCH_1):PAGE123_I13@MSTR_U_PROC.LBG_CORE_QAT_EXT_D(CHIPS)':
 'VSS'<442>: CDS_PINID='VSS(442)';
NODE_NAME     U7C1 A41
 '@BASEBOARD_FAB2_LIB.BASEBOARD_FAB2(SCH_1):PAGE123_I13@MSTR_U_PROC.LBG_CORE_QAT_EXT_D(CHIPS)':
 'VSS'<443>: CDS_PINID='VSS(443)';
NODE_NAME     U7C1 A37
 '@BASEBOARD_FAB2_LIB.BASEBOARD_FAB2(SCH_1):PAGE123_I13@MSTR_U_PROC.LBG_CORE_QAT_EXT_D(CHIPS)':
 'VSS'<444>: CDS_PINID='VSS(444)';
NODE_NAME     U7C1 A34
 '@BASEBOARD_FAB2_LIB.BASEBOARD_FAB2(SCH_1):PAGE123_I13@MSTR_U_PROC.LBG_CORE_QAT_EXT_D(CHIPS)':
 'VSS'<445>: CDS_PINID='VSS(445)';
NODE_NAME     U7C1 A30
 '@BASEBOARD_FAB2_LIB.BASEBOARD_FAB2(SCH_1):PAGE123_I13@MSTR_U_PROC.LBG_CORE_QAT_EXT_D(CHIPS)':
 'VSS'<446>: CDS_PINID='VSS(446)';
NODE_NAME     U7C1 A22
 '@BASEBOARD_FAB2_LIB.BASEBOARD_FAB2(SCH_1):PAGE123_I13@MSTR_U_PROC.LBG_CORE_QAT_EXT_D(CHIPS)':
 'VSS'<447>: CDS_PINID='VSS(447)';
NODE_NAME     U7C1 A18
 '@BASEBOARD_FAB2_LIB.BASEBOARD_FAB2(SCH_1):PAGE123_I13@MSTR_U_PROC.LBG_CORE_QAT_EXT_D(CHIPS)':
 'VSS'<448>: CDS_PINID='VSS(448)';
NODE_NAME     U7C1 Y70
 '@BASEBOARD_FAB2_LIB.BASEBOARD_FAB2(SCH_1):PAGE123_I13@MSTR_U_PROC.LBG_CORE_QAT_EXT_D(CHIPS)':
 'VSS'<449>: CDS_PINID='VSS(449)';
NODE_NAME     U7C1 Y72
 '@BASEBOARD_FAB2_LIB.BASEBOARD_FAB2(SCH_1):PAGE123_I13@MSTR_U_PROC.LBG_CORE_QAT_EXT_D(CHIPS)':
 'VSS'<450>: CDS_PINID='VSS(450)';
NODE_NAME     U7C1 AT37
 '@BASEBOARD_FAB2_LIB.BASEBOARD_FAB2(SCH_1):PAGE123_I13@MSTR_U_PROC.LBG_CORE_QAT_EXT_D(CHIPS)':
 'VSS'<451>: CDS_PINID='VSS(451)';
NODE_NAME     U7C1 BB48
 '@BASEBOARD_FAB2_LIB.BASEBOARD_FAB2(SCH_1):PAGE123_I13@MSTR_U_PROC.LBG_CORE_QAT_EXT_D(CHIPS)':
 'VSS'<452>: CDS_PINID='VSS(452)';
NODE_NAME     U7C1 CA70
 '@BASEBOARD_FAB2_LIB.BASEBOARD_FAB2(SCH_1):PAGE123_I13@MSTR_U_PROC.LBG_CORE_QAT_EXT_D(CHIPS)':
 'VSS'<453>: CDS_PINID='VSS(453)';
NODE_NAME     U7C1 BW72
 '@BASEBOARD_FAB2_LIB.BASEBOARD_FAB2(SCH_1):PAGE123_I13@MSTR_U_PROC.LBG_CORE_QAT_EXT_D(CHIPS)':
 'VSS'<454>: CDS_PINID='VSS(454)';
NODE_NAME     U7C1 BW70
 '@BASEBOARD_FAB2_LIB.BASEBOARD_FAB2(SCH_1):PAGE123_I13@MSTR_U_PROC.LBG_CORE_QAT_EXT_D(CHIPS)':
 'VSS'<455>: CDS_PINID='VSS(455)';
NODE_NAME     U7C1 BU72
 '@BASEBOARD_FAB2_LIB.BASEBOARD_FAB2(SCH_1):PAGE123_I13@MSTR_U_PROC.LBG_CORE_QAT_EXT_D(CHIPS)':
 'VSS'<456>: CDS_PINID='VSS(456)';
NODE_NAME     U7C1 BR72
 '@BASEBOARD_FAB2_LIB.BASEBOARD_FAB2(SCH_1):PAGE123_I13@MSTR_U_PROC.LBG_CORE_QAT_EXT_D(CHIPS)':
 'VSS'<457>: CDS_PINID='VSS(457)';
NODE_NAME     U7C1 G72
 '@BASEBOARD_FAB2_LIB.BASEBOARD_FAB2(SCH_1):PAGE123_I13@MSTR_U_PROC.LBG_CORE_QAT_EXT_D(CHIPS)':
 'VSS'<458>: CDS_PINID='VSS(458)';
NODE_NAME     U7C1 G1
 '@BASEBOARD_FAB2_LIB.BASEBOARD_FAB2(SCH_1):PAGE123_I13@MSTR_U_PROC.LBG_CORE_QAT_EXT_D(CHIPS)':
 'VSS'<459>: CDS_PINID='VSS(459)';
NODE_NAME     U7C1 E72
 '@BASEBOARD_FAB2_LIB.BASEBOARD_FAB2(SCH_1):PAGE123_I13@MSTR_U_PROC.LBG_CORE_QAT_EXT_D(CHIPS)':
 'VSS'<460>: CDS_PINID='VSS(460)';
NODE_NAME     U7C1 E1
 '@BASEBOARD_FAB2_LIB.BASEBOARD_FAB2(SCH_1):PAGE123_I13@MSTR_U_PROC.LBG_CORE_QAT_EXT_D(CHIPS)':
 'VSS'<461>: CDS_PINID='VSS(461)';
NODE_NAME     U7C1 C72
 '@BASEBOARD_FAB2_LIB.BASEBOARD_FAB2(SCH_1):PAGE123_I13@MSTR_U_PROC.LBG_CORE_QAT_EXT_D(CHIPS)':
 'VSS'<462>: CDS_PINID='VSS(462)';
NODE_NAME     U7C1 C3
 '@BASEBOARD_FAB2_LIB.BASEBOARD_FAB2(SCH_1):PAGE123_I13@MSTR_U_PROC.LBG_CORE_QAT_EXT_D(CHIPS)':
 'VSS'<463>: CDS_PINID='VSS(463)';
NODE_NAME     U7C1 BR1
 '@BASEBOARD_FAB2_LIB.BASEBOARD_FAB2(SCH_1):PAGE123_I13@MSTR_U_PROC.LBG_CORE_QAT_EXT_D(CHIPS)':
 'VSS'<464>: CDS_PINID='VSS(464)';
NODE_NAME     U7C1 BU1
 '@BASEBOARD_FAB2_LIB.BASEBOARD_FAB2(SCH_1):PAGE123_I13@MSTR_U_PROC.LBG_CORE_QAT_EXT_D(CHIPS)':
 'VSS'<465>: CDS_PINID='VSS(465)';
NODE_NAME     U7C1 BW1
 '@BASEBOARD_FAB2_LIB.BASEBOARD_FAB2(SCH_1):PAGE123_I13@MSTR_U_PROC.LBG_CORE_QAT_EXT_D(CHIPS)':
 'VSS'<466>: CDS_PINID='VSS(466)';
NODE_NAME     U7C1 CA3
 '@BASEBOARD_FAB2_LIB.BASEBOARD_FAB2(SCH_1):PAGE123_I13@MSTR_U_PROC.LBG_CORE_QAT_EXT_D(CHIPS)':
 'VSS'<467>: CDS_PINID='VSS(467)';
NODE_NAME     U7C1 A70
 '@BASEBOARD_FAB2_LIB.BASEBOARD_FAB2(SCH_1):PAGE123_I13@MSTR_U_PROC.LBG_CORE_QAT_EXT_D(CHIPS)':
 'VSS'<468>: CDS_PINID='VSS(468)';
NODE_NAME     U7C1 CA5
 '@BASEBOARD_FAB2_LIB.BASEBOARD_FAB2(SCH_1):PAGE123_I13@MSTR_U_PROC.LBG_CORE_QAT_EXT_D(CHIPS)':
 'VSS'<469>: CDS_PINID='VSS(469)';
NODE_NAME     U7C1 CA7
 '@BASEBOARD_FAB2_LIB.BASEBOARD_FAB2(SCH_1):PAGE123_I13@MSTR_U_PROC.LBG_CORE_QAT_EXT_D(CHIPS)':
 'VSS'<470>: CDS_PINID='VSS(470)';
NODE_NAME     U7C1 CA9
 '@BASEBOARD_FAB2_LIB.BASEBOARD_FAB2(SCH_1):PAGE123_I13@MSTR_U_PROC.LBG_CORE_QAT_EXT_D(CHIPS)':
 'VSS'<471>: CDS_PINID='VSS(471)';
NODE_NAME     U7C1 CA65
 '@BASEBOARD_FAB2_LIB.BASEBOARD_FAB2(SCH_1):PAGE123_I13@MSTR_U_PROC.LBG_CORE_QAT_EXT_D(CHIPS)':
 'VSS'<472>: CDS_PINID='VSS(472)';
NODE_NAME     U7C1 CA66
 '@BASEBOARD_FAB2_LIB.BASEBOARD_FAB2(SCH_1):PAGE123_I13@MSTR_U_PROC.LBG_CORE_QAT_EXT_D(CHIPS)':
 'VSS'<473>: CDS_PINID='VSS(473)';
NODE_NAME     U7C1 CA68
 '@BASEBOARD_FAB2_LIB.BASEBOARD_FAB2(SCH_1):PAGE123_I13@MSTR_U_PROC.LBG_CORE_QAT_EXT_D(CHIPS)':
 'VSS'<474>: CDS_PINID='VSS(474)';
NODE_NAME     U7C1 BN72
 '@BASEBOARD_FAB2_LIB.BASEBOARD_FAB2(SCH_1):PAGE123_I13@MSTR_U_PROC.LBG_CORE_QAT_EXT_D(CHIPS)':
 'VSS'<475>: CDS_PINID='VSS(475)';
NODE_NAME     U7C1 BN1
 '@BASEBOARD_FAB2_LIB.BASEBOARD_FAB2(SCH_1):PAGE123_I13@MSTR_U_PROC.LBG_CORE_QAT_EXT_D(CHIPS)':
 'VSS'<476>: CDS_PINID='VSS(476)';
NODE_NAME     U7C1 J72
 '@BASEBOARD_FAB2_LIB.BASEBOARD_FAB2(SCH_1):PAGE123_I13@MSTR_U_PROC.LBG_CORE_QAT_EXT_D(CHIPS)':
 'VSS'<477>: CDS_PINID='VSS(477)';
NODE_NAME     U7C1 J1
 '@BASEBOARD_FAB2_LIB.BASEBOARD_FAB2(SCH_1):PAGE123_I13@MSTR_U_PROC.LBG_CORE_QAT_EXT_D(CHIPS)':
 'VSS'<478>: CDS_PINID='VSS(478)';
NODE_NAME     U7C1 A68
 '@BASEBOARD_FAB2_LIB.BASEBOARD_FAB2(SCH_1):PAGE123_I13@MSTR_U_PROC.LBG_CORE_QAT_EXT_D(CHIPS)':
 'VSS'<479>: CDS_PINID='VSS(479)';
NODE_NAME     U7C1 A66
 '@BASEBOARD_FAB2_LIB.BASEBOARD_FAB2(SCH_1):PAGE123_I13@MSTR_U_PROC.LBG_CORE_QAT_EXT_D(CHIPS)':
 'VSS'<480>: CDS_PINID='VSS(480)';
NODE_NAME     U7C1 A65
 '@BASEBOARD_FAB2_LIB.BASEBOARD_FAB2(SCH_1):PAGE123_I13@MSTR_U_PROC.LBG_CORE_QAT_EXT_D(CHIPS)':
 'VSS'<481>: CDS_PINID='VSS(481)';
NODE_NAME     U7C1 A9
 '@BASEBOARD_FAB2_LIB.BASEBOARD_FAB2(SCH_1):PAGE123_I13@MSTR_U_PROC.LBG_CORE_QAT_EXT_D(CHIPS)':
 'VSS'<482>: CDS_PINID='VSS(482)';
NODE_NAME     U7C1 A7
 '@BASEBOARD_FAB2_LIB.BASEBOARD_FAB2(SCH_1):PAGE123_I13@MSTR_U_PROC.LBG_CORE_QAT_EXT_D(CHIPS)':
 'VSS'<483>: CDS_PINID='VSS(483)';
NODE_NAME     U7C1 A5
 '@BASEBOARD_FAB2_LIB.BASEBOARD_FAB2(SCH_1):PAGE123_I13@MSTR_U_PROC.LBG_CORE_QAT_EXT_D(CHIPS)':
 'VSS'<484>: CDS_PINID='VSS(484)';
NODE_NAME     U7C1 E3
 '@BASEBOARD_FAB2_LIB.BASEBOARD_FAB2(SCH_1):PAGE123_I13@MSTR_U_PROC.LBG_CORE_QAT_EXT_D(CHIPS)':
 'VSS'<485>: CDS_PINID='VSS(485)';
NODE_NAME     U7C1 F3
 '@BASEBOARD_FAB2_LIB.BASEBOARD_FAB2(SCH_1):PAGE123_I13@MSTR_U_PROC.LBG_CORE_QAT_EXT_D(CHIPS)':
 'VSS'<486>: CDS_PINID='VSS(486)';
NODE_NAME     U7C1 BR3
 '@BASEBOARD_FAB2_LIB.BASEBOARD_FAB2(SCH_1):PAGE123_I13@MSTR_U_PROC.LBG_CORE_QAT_EXT_D(CHIPS)':
 'VSS'<487>: CDS_PINID='VSS(487)';
NODE_NAME     U7C1 BU3
 '@BASEBOARD_FAB2_LIB.BASEBOARD_FAB2(SCH_1):PAGE123_I13@MSTR_U_PROC.LBG_CORE_QAT_EXT_D(CHIPS)':
 'VSS'<488>: CDS_PINID='VSS(488)';
NODE_NAME     U7C1 E70
 '@BASEBOARD_FAB2_LIB.BASEBOARD_FAB2(SCH_1):PAGE123_I13@MSTR_U_PROC.LBG_CORE_QAT_EXT_D(CHIPS)':
 'VSS'<489>: CDS_PINID='VSS(489)';
NODE_NAME     U7C1 F70
 '@BASEBOARD_FAB2_LIB.BASEBOARD_FAB2(SCH_1):PAGE123_I13@MSTR_U_PROC.LBG_CORE_QAT_EXT_D(CHIPS)':
 'VSS'<490>: CDS_PINID='VSS(490)';
NODE_NAME     U7C1 BR70
 '@BASEBOARD_FAB2_LIB.BASEBOARD_FAB2(SCH_1):PAGE123_I13@MSTR_U_PROC.LBG_CORE_QAT_EXT_D(CHIPS)':
 'VSS'<491>: CDS_PINID='VSS(491)';
NODE_NAME     U7C1 BU70
 '@BASEBOARD_FAB2_LIB.BASEBOARD_FAB2(SCH_1):PAGE123_I13@MSTR_U_PROC.LBG_CORE_QAT_EXT_D(CHIPS)':
 'VSS'<492>: CDS_PINID='VSS(492)';
NODE_NAME     U7C1 BT69
 '@BASEBOARD_FAB2_LIB.BASEBOARD_FAB2(SCH_1):PAGE123_I13@MSTR_U_PROC.LBG_CORE_QAT_EXT_D(CHIPS)':
 'VSS'<493>: CDS_PINID='VSS(493)';
NODE_NAME     U7C1 BP69
 '@BASEBOARD_FAB2_LIB.BASEBOARD_FAB2(SCH_1):PAGE123_I13@MSTR_U_PROC.LBG_CORE_QAT_EXT_D(CHIPS)':
 'VSS'<494>: CDS_PINID='VSS(494)';
NODE_NAME     U7C1 CA52
 '@BASEBOARD_FAB2_LIB.BASEBOARD_FAB2(SCH_1):PAGE124_I15@MSTR_U_PROC.LBG_CORE_QAT_EXT_D(CHIPS)':
 'VSS'<0>: CDS_PINID='VSS(0)';
NODE_NAME     U7C1 CA50
 '@BASEBOARD_FAB2_LIB.BASEBOARD_FAB2(SCH_1):PAGE124_I15@MSTR_U_PROC.LBG_CORE_QAT_EXT_D(CHIPS)':
 'VSS'<1>: CDS_PINID='VSS(1)';
NODE_NAME     U7C1 CA26
 '@BASEBOARD_FAB2_LIB.BASEBOARD_FAB2(SCH_1):PAGE124_I15@MSTR_U_PROC.LBG_CORE_QAT_EXT_D(CHIPS)':
 'VSS'<2>: CDS_PINID='VSS(2)';
NODE_NAME     U7C1 CA18
 '@BASEBOARD_FAB2_LIB.BASEBOARD_FAB2(SCH_1):PAGE124_I15@MSTR_U_PROC.LBG_CORE_QAT_EXT_D(CHIPS)':
 'VSS'<3>: CDS_PINID='VSS(3)';
NODE_NAME     U7C1 CA15
 '@BASEBOARD_FAB2_LIB.BASEBOARD_FAB2(SCH_1):PAGE124_I15@MSTR_U_PROC.LBG_CORE_QAT_EXT_D(CHIPS)':
 'VSS'<4>: CDS_PINID='VSS(4)';
NODE_NAME     U7C1 BY49
 '@BASEBOARD_FAB2_LIB.BASEBOARD_FAB2(SCH_1):PAGE124_I15@MSTR_U_PROC.LBG_CORE_QAT_EXT_D(CHIPS)':
 'VSS'<5>: CDS_PINID='VSS(5)';
NODE_NAME     U7C1 BY40
 '@BASEBOARD_FAB2_LIB.BASEBOARD_FAB2(SCH_1):PAGE124_I15@MSTR_U_PROC.LBG_CORE_QAT_EXT_D(CHIPS)':
 'VSS'<6>: CDS_PINID='VSS(6)';
NODE_NAME     U7C1 BW52
 '@BASEBOARD_FAB2_LIB.BASEBOARD_FAB2(SCH_1):PAGE124_I15@MSTR_U_PROC.LBG_CORE_QAT_EXT_D(CHIPS)':
 'VSS'<7>: CDS_PINID='VSS(7)';
NODE_NAME     U7C1 BW26
 '@BASEBOARD_FAB2_LIB.BASEBOARD_FAB2(SCH_1):PAGE124_I15@MSTR_U_PROC.LBG_CORE_QAT_EXT_D(CHIPS)':
 'VSS'<8>: CDS_PINID='VSS(8)';
NODE_NAME     U7C1 BW18
 '@BASEBOARD_FAB2_LIB.BASEBOARD_FAB2(SCH_1):PAGE124_I15@MSTR_U_PROC.LBG_CORE_QAT_EXT_D(CHIPS)':
 'VSS'<9>: CDS_PINID='VSS(9)';
NODE_NAME     U7C1 BW15
 '@BASEBOARD_FAB2_LIB.BASEBOARD_FAB2(SCH_1):PAGE124_I15@MSTR_U_PROC.LBG_CORE_QAT_EXT_D(CHIPS)':
 'VSS'<10>: CDS_PINID='VSS(10)';
NODE_NAME     U7C1 BV40
 '@BASEBOARD_FAB2_LIB.BASEBOARD_FAB2(SCH_1):PAGE124_I15@MSTR_U_PROC.LBG_CORE_QAT_EXT_D(CHIPS)':
 'VSS'<11>: CDS_PINID='VSS(11)';
NODE_NAME     U7C1 BU9
 '@BASEBOARD_FAB2_LIB.BASEBOARD_FAB2(SCH_1):PAGE124_I15@MSTR_U_PROC.LBG_CORE_QAT_EXT_D(CHIPS)':
 'VSS'<12>: CDS_PINID='VSS(12)';
NODE_NAME     U7C1 BU63
 '@BASEBOARD_FAB2_LIB.BASEBOARD_FAB2(SCH_1):PAGE124_I15@MSTR_U_PROC.LBG_CORE_QAT_EXT_D(CHIPS)':
 'VSS'<13>: CDS_PINID='VSS(13)';
NODE_NAME     U7C1 BU61
 '@BASEBOARD_FAB2_LIB.BASEBOARD_FAB2(SCH_1):PAGE124_I15@MSTR_U_PROC.LBG_CORE_QAT_EXT_D(CHIPS)':
 'VSS'<14>: CDS_PINID='VSS(14)';
NODE_NAME     U7C1 BU59
 '@BASEBOARD_FAB2_LIB.BASEBOARD_FAB2(SCH_1):PAGE124_I15@MSTR_U_PROC.LBG_CORE_QAT_EXT_D(CHIPS)':
 'VSS'<15>: CDS_PINID='VSS(15)';
NODE_NAME     U7C1 BU57
 '@BASEBOARD_FAB2_LIB.BASEBOARD_FAB2(SCH_1):PAGE124_I15@MSTR_U_PROC.LBG_CORE_QAT_EXT_D(CHIPS)':
 'VSS'<16>: CDS_PINID='VSS(16)';
NODE_NAME     U7C1 BU54
 '@BASEBOARD_FAB2_LIB.BASEBOARD_FAB2(SCH_1):PAGE124_I15@MSTR_U_PROC.LBG_CORE_QAT_EXT_D(CHIPS)':
 'VSS'<17>: CDS_PINID='VSS(17)';
NODE_NAME     U7C1 BU52
 '@BASEBOARD_FAB2_LIB.BASEBOARD_FAB2(SCH_1):PAGE124_I15@MSTR_U_PROC.LBG_CORE_QAT_EXT_D(CHIPS)':
 'VSS'<18>: CDS_PINID='VSS(18)';
NODE_NAME     U7C1 BU50
 '@BASEBOARD_FAB2_LIB.BASEBOARD_FAB2(SCH_1):PAGE124_I15@MSTR_U_PROC.LBG_CORE_QAT_EXT_D(CHIPS)':
 'VSS'<19>: CDS_PINID='VSS(19)';
NODE_NAME     U7C1 BU48
 '@BASEBOARD_FAB2_LIB.BASEBOARD_FAB2(SCH_1):PAGE124_I15@MSTR_U_PROC.LBG_CORE_QAT_EXT_D(CHIPS)':
 'VSS'<20>: CDS_PINID='VSS(20)';
NODE_NAME     U7C1 BU45
 '@BASEBOARD_FAB2_LIB.BASEBOARD_FAB2(SCH_1):PAGE124_I15@MSTR_U_PROC.LBG_CORE_QAT_EXT_D(CHIPS)':
 'VSS'<21>: CDS_PINID='VSS(21)';
NODE_NAME     U7C1 BU43
 '@BASEBOARD_FAB2_LIB.BASEBOARD_FAB2(SCH_1):PAGE124_I15@MSTR_U_PROC.LBG_CORE_QAT_EXT_D(CHIPS)':
 'VSS'<22>: CDS_PINID='VSS(22)';
NODE_NAME     U7C1 BU41
 '@BASEBOARD_FAB2_LIB.BASEBOARD_FAB2(SCH_1):PAGE124_I15@MSTR_U_PROC.LBG_CORE_QAT_EXT_D(CHIPS)':
 'VSS'<23>: CDS_PINID='VSS(23)';
NODE_NAME     U7C1 BU39
 '@BASEBOARD_FAB2_LIB.BASEBOARD_FAB2(SCH_1):PAGE124_I15@MSTR_U_PROC.LBG_CORE_QAT_EXT_D(CHIPS)':
 'VSS'<24>: CDS_PINID='VSS(24)';
NODE_NAME     U7C1 BU37
 '@BASEBOARD_FAB2_LIB.BASEBOARD_FAB2(SCH_1):PAGE124_I15@MSTR_U_PROC.LBG_CORE_QAT_EXT_D(CHIPS)':
 'VSS'<25>: CDS_PINID='VSS(25)';
NODE_NAME     U7C1 BU34
 '@BASEBOARD_FAB2_LIB.BASEBOARD_FAB2(SCH_1):PAGE124_I15@MSTR_U_PROC.LBG_CORE_QAT_EXT_D(CHIPS)':
 'VSS'<26>: CDS_PINID='VSS(26)';
NODE_NAME     U7C1 BU32
 '@BASEBOARD_FAB2_LIB.BASEBOARD_FAB2(SCH_1):PAGE124_I15@MSTR_U_PROC.LBG_CORE_QAT_EXT_D(CHIPS)':
 'VSS'<27>: CDS_PINID='VSS(27)';
NODE_NAME     U7C1 BU30
 '@BASEBOARD_FAB2_LIB.BASEBOARD_FAB2(SCH_1):PAGE124_I15@MSTR_U_PROC.LBG_CORE_QAT_EXT_D(CHIPS)':
 'VSS'<28>: CDS_PINID='VSS(28)';
NODE_NAME     U7C1 BU28
 '@BASEBOARD_FAB2_LIB.BASEBOARD_FAB2(SCH_1):PAGE124_I15@MSTR_U_PROC.LBG_CORE_QAT_EXT_D(CHIPS)':
 'VSS'<29>: CDS_PINID='VSS(29)';
NODE_NAME     U7C1 BU26
 '@BASEBOARD_FAB2_LIB.BASEBOARD_FAB2(SCH_1):PAGE124_I15@MSTR_U_PROC.LBG_CORE_QAT_EXT_D(CHIPS)':
 'VSS'<30>: CDS_PINID='VSS(30)';
NODE_NAME     U7C1 BU24
 '@BASEBOARD_FAB2_LIB.BASEBOARD_FAB2(SCH_1):PAGE124_I15@MSTR_U_PROC.LBG_CORE_QAT_EXT_D(CHIPS)':
 'VSS'<31>: CDS_PINID='VSS(31)';
NODE_NAME     U7C1 BU22
 '@BASEBOARD_FAB2_LIB.BASEBOARD_FAB2(SCH_1):PAGE124_I15@MSTR_U_PROC.LBG_CORE_QAT_EXT_D(CHIPS)':
 'VSS'<32>: CDS_PINID='VSS(32)';
NODE_NAME     U7C1 BU20
 '@BASEBOARD_FAB2_LIB.BASEBOARD_FAB2(SCH_1):PAGE124_I15@MSTR_U_PROC.LBG_CORE_QAT_EXT_D(CHIPS)':
 'VSS'<33>: CDS_PINID='VSS(33)';
NODE_NAME     U7C1 BU18
 '@BASEBOARD_FAB2_LIB.BASEBOARD_FAB2(SCH_1):PAGE124_I15@MSTR_U_PROC.LBG_CORE_QAT_EXT_D(CHIPS)':
 'VSS'<34>: CDS_PINID='VSS(34)';
NODE_NAME     U7C1 BU15
 '@BASEBOARD_FAB2_LIB.BASEBOARD_FAB2(SCH_1):PAGE124_I15@MSTR_U_PROC.LBG_CORE_QAT_EXT_D(CHIPS)':
 'VSS'<35>: CDS_PINID='VSS(35)';
NODE_NAME     U7C1 BV49
 '@BASEBOARD_FAB2_LIB.BASEBOARD_FAB2(SCH_1):PAGE124_I15@MSTR_U_PROC.LBG_CORE_QAT_EXT_D(CHIPS)':
 'VSS'<36>: CDS_PINID='VSS(36)';
NODE_NAME     U7C1 BU11
 '@BASEBOARD_FAB2_LIB.BASEBOARD_FAB2(SCH_1):PAGE124_I15@MSTR_U_PROC.LBG_CORE_QAT_EXT_D(CHIPS)':
 'VSS'<37>: CDS_PINID='VSS(37)';
NODE_NAME     U7C1 BU13
 '@BASEBOARD_FAB2_LIB.BASEBOARD_FAB2(SCH_1):PAGE124_I15@MSTR_U_PROC.LBG_CORE_QAT_EXT_D(CHIPS)':
 'VSS'<38>: CDS_PINID='VSS(38)';
NODE_NAME     U7C1 BT66
 '@BASEBOARD_FAB2_LIB.BASEBOARD_FAB2(SCH_1):PAGE124_I15@MSTR_U_PROC.LBG_CORE_QAT_EXT_D(CHIPS)':
 'VSS'<39>: CDS_PINID='VSS(39)';
NODE_NAME     U7C1 BR6
 '@BASEBOARD_FAB2_LIB.BASEBOARD_FAB2(SCH_1):PAGE124_I15@MSTR_U_PROC.LBG_CORE_QAT_EXT_D(CHIPS)':
 'VSS'<40>: CDS_PINID='VSS(40)';
NODE_NAME     U7C1 BR58
 '@BASEBOARD_FAB2_LIB.BASEBOARD_FAB2(SCH_1):PAGE124_I15@MSTR_U_PROC.LBG_CORE_QAT_EXT_D(CHIPS)':
 'VSS'<41>: CDS_PINID='VSS(41)';
NODE_NAME     U7C1 BR54
 '@BASEBOARD_FAB2_LIB.BASEBOARD_FAB2(SCH_1):PAGE124_I15@MSTR_U_PROC.LBG_CORE_QAT_EXT_D(CHIPS)':
 'VSS'<42>: CDS_PINID='VSS(42)';
NODE_NAME     U7C1 BT8
 '@BASEBOARD_FAB2_LIB.BASEBOARD_FAB2(SCH_1):PAGE124_I15@MSTR_U_PROC.LBG_CORE_QAT_EXT_D(CHIPS)':
 'VSS'<43>: CDS_PINID='VSS(43)';
NODE_NAME     U7C1 BR50
 '@BASEBOARD_FAB2_LIB.BASEBOARD_FAB2(SCH_1):PAGE124_I15@MSTR_U_PROC.LBG_CORE_QAT_EXT_D(CHIPS)':
 'VSS'<44>: CDS_PINID='VSS(44)';
NODE_NAME     U7C1 BR20
 '@BASEBOARD_FAB2_LIB.BASEBOARD_FAB2(SCH_1):PAGE124_I15@MSTR_U_PROC.LBG_CORE_QAT_EXT_D(CHIPS)':
 'VSS'<45>: CDS_PINID='VSS(45)';
NODE_NAME     U7C1 BN66
 '@BASEBOARD_FAB2_LIB.BASEBOARD_FAB2(SCH_1):PAGE124_I15@MSTR_U_PROC.LBG_CORE_QAT_EXT_D(CHIPS)':
 'VSS'<46>: CDS_PINID='VSS(46)';
NODE_NAME     U7C1 BN52
 '@BASEBOARD_FAB2_LIB.BASEBOARD_FAB2(SCH_1):PAGE124_I15@MSTR_U_PROC.LBG_CORE_QAT_EXT_D(CHIPS)':
 'VSS'<47>: CDS_PINID='VSS(47)';
NODE_NAME     U7C1 BN5
 '@BASEBOARD_FAB2_LIB.BASEBOARD_FAB2(SCH_1):PAGE124_I15@MSTR_U_PROC.LBG_CORE_QAT_EXT_D(CHIPS)':
 'VSS'<48>: CDS_PINID='VSS(48)';
NODE_NAME     U7C1 BN59
 '@BASEBOARD_FAB2_LIB.BASEBOARD_FAB2(SCH_1):PAGE124_I15@MSTR_U_PROC.LBG_CORE_QAT_EXT_D(CHIPS)':
 'VSS'<49>: CDS_PINID='VSS(49)';
NODE_NAME     U7C1 BN22
 '@BASEBOARD_FAB2_LIB.BASEBOARD_FAB2(SCH_1):PAGE124_I15@MSTR_U_PROC.LBG_CORE_QAT_EXT_D(CHIPS)':
 'VSS'<50>: CDS_PINID='VSS(50)';
NODE_NAME     U7C1 BM9
 '@BASEBOARD_FAB2_LIB.BASEBOARD_FAB2(SCH_1):PAGE124_I15@MSTR_U_PROC.LBG_CORE_QAT_EXT_D(CHIPS)':
 'VSS'<51>: CDS_PINID='VSS(51)';
NODE_NAME     U7C1 BM71
 '@BASEBOARD_FAB2_LIB.BASEBOARD_FAB2(SCH_1):PAGE124_I15@MSTR_U_PROC.LBG_CORE_QAT_EXT_D(CHIPS)':
 'VSS'<52>: CDS_PINID='VSS(52)';
NODE_NAME     U7C1 BM69
 '@BASEBOARD_FAB2_LIB.BASEBOARD_FAB2(SCH_1):PAGE124_I15@MSTR_U_PROC.LBG_CORE_QAT_EXT_D(CHIPS)':
 'VSS'<53>: CDS_PINID='VSS(53)';
NODE_NAME     U7C1 BM58
 '@BASEBOARD_FAB2_LIB.BASEBOARD_FAB2(SCH_1):PAGE124_I15@MSTR_U_PROC.LBG_CORE_QAT_EXT_D(CHIPS)':
 'VSS'<54>: CDS_PINID='VSS(54)';
NODE_NAME     U7C1 BM50
 '@BASEBOARD_FAB2_LIB.BASEBOARD_FAB2(SCH_1):PAGE124_I15@MSTR_U_PROC.LBG_CORE_QAT_EXT_D(CHIPS)':
 'VSS'<55>: CDS_PINID='VSS(55)';
NODE_NAME     U7C1 BM46
 '@BASEBOARD_FAB2_LIB.BASEBOARD_FAB2(SCH_1):PAGE124_I15@MSTR_U_PROC.LBG_CORE_QAT_EXT_D(CHIPS)':
 'VSS'<56>: CDS_PINID='VSS(56)';
NODE_NAME     U7C1 BN37
 '@BASEBOARD_FAB2_LIB.BASEBOARD_FAB2(SCH_1):PAGE124_I15@MSTR_U_PROC.LBG_CORE_QAT_EXT_D(CHIPS)':
 'VSS'<57>: CDS_PINID='VSS(57)';
NODE_NAME     U7C1 BM17
 '@BASEBOARD_FAB2_LIB.BASEBOARD_FAB2(SCH_1):PAGE124_I15@MSTR_U_PROC.LBG_CORE_QAT_EXT_D(CHIPS)':
 'VSS'<58>: CDS_PINID='VSS(58)';
NODE_NAME     U7C1 BM13
 '@BASEBOARD_FAB2_LIB.BASEBOARD_FAB2(SCH_1):PAGE124_I15@MSTR_U_PROC.LBG_CORE_QAT_EXT_D(CHIPS)':
 'VSS'<59>: CDS_PINID='VSS(59)';
NODE_NAME     U7C1 BL72
 '@BASEBOARD_FAB2_LIB.BASEBOARD_FAB2(SCH_1):PAGE124_I15@MSTR_U_PROC.LBG_CORE_QAT_EXT_D(CHIPS)':
 'VSS'<60>: CDS_PINID='VSS(60)';
NODE_NAME     U7C1 BL70
 '@BASEBOARD_FAB2_LIB.BASEBOARD_FAB2(SCH_1):PAGE124_I15@MSTR_U_PROC.LBG_CORE_QAT_EXT_D(CHIPS)':
 'VSS'<61>: CDS_PINID='VSS(61)';
NODE_NAME     U7C1 BL63
 '@BASEBOARD_FAB2_LIB.BASEBOARD_FAB2(SCH_1):PAGE124_I15@MSTR_U_PROC.LBG_CORE_QAT_EXT_D(CHIPS)':
 'VSS'<62>: CDS_PINID='VSS(62)';
NODE_NAME     U7C1 BL5
 '@BASEBOARD_FAB2_LIB.BASEBOARD_FAB2(SCH_1):PAGE124_I15@MSTR_U_PROC.LBG_CORE_QAT_EXT_D(CHIPS)':
 'VSS'<63>: CDS_PINID='VSS(63)';
NODE_NAME     U7C1 BL37
 '@BASEBOARD_FAB2_LIB.BASEBOARD_FAB2(SCH_1):PAGE124_I15@MSTR_U_PROC.LBG_CORE_QAT_EXT_D(CHIPS)':
 'VSS'<64>: CDS_PINID='VSS(64)';
NODE_NAME     U7C1 BL68
 '@BASEBOARD_FAB2_LIB.BASEBOARD_FAB2(SCH_1):PAGE124_I15@MSTR_U_PROC.LBG_CORE_QAT_EXT_D(CHIPS)':
 'VSS'<65>: CDS_PINID='VSS(65)';
NODE_NAME     U7C1 BL40
 '@BASEBOARD_FAB2_LIB.BASEBOARD_FAB2(SCH_1):PAGE124_I15@MSTR_U_PROC.LBG_CORE_QAT_EXT_D(CHIPS)':
 'VSS'<66>: CDS_PINID='VSS(66)';
NODE_NAME     U7C1 BL22
 '@BASEBOARD_FAB2_LIB.BASEBOARD_FAB2(SCH_1):PAGE124_I15@MSTR_U_PROC.LBG_CORE_QAT_EXT_D(CHIPS)':
 'VSS'<67>: CDS_PINID='VSS(67)';
NODE_NAME     U7C1 BK50
 '@BASEBOARD_FAB2_LIB.BASEBOARD_FAB2(SCH_1):PAGE124_I15@MSTR_U_PROC.LBG_CORE_QAT_EXT_D(CHIPS)':
 'VSS'<68>: CDS_PINID='VSS(68)';
NODE_NAME     U7C1 BK42
 '@BASEBOARD_FAB2_LIB.BASEBOARD_FAB2(SCH_1):PAGE124_I15@MSTR_U_PROC.LBG_CORE_QAT_EXT_D(CHIPS)':
 'VSS'<69>: CDS_PINID='VSS(69)';
NODE_NAME     U7C1 BK38
 '@BASEBOARD_FAB2_LIB.BASEBOARD_FAB2(SCH_1):PAGE124_I15@MSTR_U_PROC.LBG_CORE_QAT_EXT_D(CHIPS)':
 'VSS'<70>: CDS_PINID='VSS(70)';
NODE_NAME     U7C1 BK35
 '@BASEBOARD_FAB2_LIB.BASEBOARD_FAB2(SCH_1):PAGE124_I15@MSTR_U_PROC.LBG_CORE_QAT_EXT_D(CHIPS)':
 'VSS'<71>: CDS_PINID='VSS(71)';
NODE_NAME     U7C1 BK31
 '@BASEBOARD_FAB2_LIB.BASEBOARD_FAB2(SCH_1):PAGE124_I15@MSTR_U_PROC.LBG_CORE_QAT_EXT_D(CHIPS)':
 'VSS'<72>: CDS_PINID='VSS(72)';
NODE_NAME     U7C1 BK27
 '@BASEBOARD_FAB2_LIB.BASEBOARD_FAB2(SCH_1):PAGE124_I15@MSTR_U_PROC.LBG_CORE_QAT_EXT_D(CHIPS)':
 'VSS'<73>: CDS_PINID='VSS(73)';
NODE_NAME     U7C1 BK24
 '@BASEBOARD_FAB2_LIB.BASEBOARD_FAB2(SCH_1):PAGE124_I15@MSTR_U_PROC.LBG_CORE_QAT_EXT_D(CHIPS)':
 'VSS'<74>: CDS_PINID='VSS(74)';
NODE_NAME     U7C1 BJ68
 '@BASEBOARD_FAB2_LIB.BASEBOARD_FAB2(SCH_1):PAGE124_I16@MSTR_U_PROC.LBG_CORE_QAT_EXT_D(CHIPS)':
 'VSS'<75>: CDS_PINID='VSS(75)';
NODE_NAME     U7C1 BJ52
 '@BASEBOARD_FAB2_LIB.BASEBOARD_FAB2(SCH_1):PAGE124_I16@MSTR_U_PROC.LBG_CORE_QAT_EXT_D(CHIPS)':
 'VSS'<76>: CDS_PINID='VSS(76)';
NODE_NAME     U7C1 BJ33
 '@BASEBOARD_FAB2_LIB.BASEBOARD_FAB2(SCH_1):PAGE124_I16@MSTR_U_PROC.LBG_CORE_QAT_EXT_D(CHIPS)':
 'VSS'<77>: CDS_PINID='VSS(77)';
NODE_NAME     U7C1 BJ3
 '@BASEBOARD_FAB2_LIB.BASEBOARD_FAB2(SCH_1):PAGE124_I16@MSTR_U_PROC.LBG_CORE_QAT_EXT_D(CHIPS)':
 'VSS'<78>: CDS_PINID='VSS(78)';
NODE_NAME     U7C1 BJ26
 '@BASEBOARD_FAB2_LIB.BASEBOARD_FAB2(SCH_1):PAGE124_I16@MSTR_U_PROC.LBG_CORE_QAT_EXT_D(CHIPS)':
 'VSS'<79>: CDS_PINID='VSS(79)';
NODE_NAME     U7C1 BJ18
 '@BASEBOARD_FAB2_LIB.BASEBOARD_FAB2(SCH_1):PAGE124_I16@MSTR_U_PROC.LBG_CORE_QAT_EXT_D(CHIPS)':
 'VSS'<80>: CDS_PINID='VSS(80)';
NODE_NAME     U7C1 BJ15
 '@BASEBOARD_FAB2_LIB.BASEBOARD_FAB2(SCH_1):PAGE124_I16@MSTR_U_PROC.LBG_CORE_QAT_EXT_D(CHIPS)':
 'VSS'<81>: CDS_PINID='VSS(81)';
NODE_NAME     U7C1 BJ7
 '@BASEBOARD_FAB2_LIB.BASEBOARD_FAB2(SCH_1):PAGE124_I16@MSTR_U_PROC.LBG_CORE_QAT_EXT_D(CHIPS)':
 'VSS'<82>: CDS_PINID='VSS(82)';
NODE_NAME     U7C1 BJ5
 '@BASEBOARD_FAB2_LIB.BASEBOARD_FAB2(SCH_1):PAGE124_I16@MSTR_U_PROC.LBG_CORE_QAT_EXT_D(CHIPS)':
 'VSS'<83>: CDS_PINID='VSS(83)';
NODE_NAME     U7C1 BJ11
 '@BASEBOARD_FAB2_LIB.BASEBOARD_FAB2(SCH_1):PAGE124_I16@MSTR_U_PROC.LBG_CORE_QAT_EXT_D(CHIPS)':
 'VSS'<84>: CDS_PINID='VSS(84)';
NODE_NAME     U7C1 BJ1
 '@BASEBOARD_FAB2_LIB.BASEBOARD_FAB2(SCH_1):PAGE124_I16@MSTR_U_PROC.LBG_CORE_QAT_EXT_D(CHIPS)':
 'VSS'<85>: CDS_PINID='VSS(85)';
NODE_NAME     U7C1 BH54
 '@BASEBOARD_FAB2_LIB.BASEBOARD_FAB2(SCH_1):PAGE124_I16@MSTR_U_PROC.LBG_CORE_QAT_EXT_D(CHIPS)':
 'VSS'<86>: CDS_PINID='VSS(86)';
NODE_NAME     U7C1 BH46
 '@BASEBOARD_FAB2_LIB.BASEBOARD_FAB2(SCH_1):PAGE124_I16@MSTR_U_PROC.LBG_CORE_QAT_EXT_D(CHIPS)':
 'VSS'<87>: CDS_PINID='VSS(87)';
NODE_NAME     U7C1 BH42
 '@BASEBOARD_FAB2_LIB.BASEBOARD_FAB2(SCH_1):PAGE124_I16@MSTR_U_PROC.LBG_CORE_QAT_EXT_D(CHIPS)':
 'VSS'<88>: CDS_PINID='VSS(88)';
NODE_NAME     U7C1 BH38
 '@BASEBOARD_FAB2_LIB.BASEBOARD_FAB2(SCH_1):PAGE124_I16@MSTR_U_PROC.LBG_CORE_QAT_EXT_D(CHIPS)':
 'VSS'<89>: CDS_PINID='VSS(89)';
NODE_NAME     U7C1 BH27
 '@BASEBOARD_FAB2_LIB.BASEBOARD_FAB2(SCH_1):PAGE124_I16@MSTR_U_PROC.LBG_CORE_QAT_EXT_D(CHIPS)':
 'VSS'<90>: CDS_PINID='VSS(90)';
NODE_NAME     U7C1 BG63
 '@BASEBOARD_FAB2_LIB.BASEBOARD_FAB2(SCH_1):PAGE124_I16@MSTR_U_PROC.LBG_CORE_QAT_EXT_D(CHIPS)':
 'VSS'<91>: CDS_PINID='VSS(91)';
NODE_NAME     U7C1 BG59
 '@BASEBOARD_FAB2_LIB.BASEBOARD_FAB2(SCH_1):PAGE124_I16@MSTR_U_PROC.LBG_CORE_QAT_EXT_D(CHIPS)':
 'VSS'<92>: CDS_PINID='VSS(92)';
NODE_NAME     U7C1 BG48
 '@BASEBOARD_FAB2_LIB.BASEBOARD_FAB2(SCH_1):PAGE124_I16@MSTR_U_PROC.LBG_CORE_QAT_EXT_D(CHIPS)':
 'VSS'<93>: CDS_PINID='VSS(93)';
NODE_NAME     U7C1 BG33
 '@BASEBOARD_FAB2_LIB.BASEBOARD_FAB2(SCH_1):PAGE124_I16@MSTR_U_PROC.LBG_CORE_QAT_EXT_D(CHIPS)':
 'VSS'<94>: CDS_PINID='VSS(94)';
NODE_NAME     U7C1 BF9
 '@BASEBOARD_FAB2_LIB.BASEBOARD_FAB2(SCH_1):PAGE124_I16@MSTR_U_PROC.LBG_CORE_QAT_EXT_D(CHIPS)':
 'VSS'<95>: CDS_PINID='VSS(95)';
NODE_NAME     U7C1 BF68
 '@BASEBOARD_FAB2_LIB.BASEBOARD_FAB2(SCH_1):PAGE124_I16@MSTR_U_PROC.LBG_CORE_QAT_EXT_D(CHIPS)':
 'VSS'<96>: CDS_PINID='VSS(96)';
NODE_NAME     U7C1 BF65
 '@BASEBOARD_FAB2_LIB.BASEBOARD_FAB2(SCH_1):PAGE124_I16@MSTR_U_PROC.LBG_CORE_QAT_EXT_D(CHIPS)':
 'VSS'<97>: CDS_PINID='VSS(97)';
NODE_NAME     U7C1 BF61
 '@BASEBOARD_FAB2_LIB.BASEBOARD_FAB2(SCH_1):PAGE124_I16@MSTR_U_PROC.LBG_CORE_QAT_EXT_D(CHIPS)':
 'VSS'<98>: CDS_PINID='VSS(98)';
NODE_NAME     U7C1 BF58
 '@BASEBOARD_FAB2_LIB.BASEBOARD_FAB2(SCH_1):PAGE124_I16@MSTR_U_PROC.LBG_CORE_QAT_EXT_D(CHIPS)':
 'VSS'<99>: CDS_PINID='VSS(99)';
NODE_NAME     U7C1 BF50
 '@BASEBOARD_FAB2_LIB.BASEBOARD_FAB2(SCH_1):PAGE124_I16@MSTR_U_PROC.LBG_CORE_QAT_EXT_D(CHIPS)':
 'VSS'<100>: CDS_PINID='VSS(100)';
NODE_NAME     U7C1 BF5
 '@BASEBOARD_FAB2_LIB.BASEBOARD_FAB2(SCH_1):PAGE124_I16@MSTR_U_PROC.LBG_CORE_QAT_EXT_D(CHIPS)':
 'VSS'<101>: CDS_PINID='VSS(101)';
NODE_NAME     U7C1 BF42
 '@BASEBOARD_FAB2_LIB.BASEBOARD_FAB2(SCH_1):PAGE124_I16@MSTR_U_PROC.LBG_CORE_QAT_EXT_D(CHIPS)':
 'VSS'<102>: CDS_PINID='VSS(102)';
NODE_NAME     U7C1 BF38
 '@BASEBOARD_FAB2_LIB.BASEBOARD_FAB2(SCH_1):PAGE124_I16@MSTR_U_PROC.LBG_CORE_QAT_EXT_D(CHIPS)':
 'VSS'<103>: CDS_PINID='VSS(103)';
NODE_NAME     U7C1 BF27
 '@BASEBOARD_FAB2_LIB.BASEBOARD_FAB2(SCH_1):PAGE124_I16@MSTR_U_PROC.LBG_CORE_QAT_EXT_D(CHIPS)':
 'VSS'<104>: CDS_PINID='VSS(104)';
NODE_NAME     U7C1 BF24
 '@BASEBOARD_FAB2_LIB.BASEBOARD_FAB2(SCH_1):PAGE124_I16@MSTR_U_PROC.LBG_CORE_QAT_EXT_D(CHIPS)':
 'VSS'<105>: CDS_PINID='VSS(105)';
NODE_NAME     U7C1 BF20
 '@BASEBOARD_FAB2_LIB.BASEBOARD_FAB2(SCH_1):PAGE124_I16@MSTR_U_PROC.LBG_CORE_QAT_EXT_D(CHIPS)':
 'VSS'<106>: CDS_PINID='VSS(106)';
NODE_NAME     U7C1 BG44
 '@BASEBOARD_FAB2_LIB.BASEBOARD_FAB2(SCH_1):PAGE124_I16@MSTR_U_PROC.LBG_CORE_QAT_EXT_D(CHIPS)':
 'VSS'<107>: CDS_PINID='VSS(107)';
NODE_NAME     U7C1 BF54
 '@BASEBOARD_FAB2_LIB.BASEBOARD_FAB2(SCH_1):PAGE124_I16@MSTR_U_PROC.LBG_CORE_QAT_EXT_D(CHIPS)':
 'VSS'<108>: CDS_PINID='VSS(108)';
NODE_NAME     U7C1 BF17
 '@BASEBOARD_FAB2_LIB.BASEBOARD_FAB2(SCH_1):PAGE124_I16@MSTR_U_PROC.LBG_CORE_QAT_EXT_D(CHIPS)':
 'VSS'<109>: CDS_PINID='VSS(109)';
NODE_NAME     U7C1 BF13
 '@BASEBOARD_FAB2_LIB.BASEBOARD_FAB2(SCH_1):PAGE124_I16@MSTR_U_PROC.LBG_CORE_QAT_EXT_D(CHIPS)':
 'VSS'<110>: CDS_PINID='VSS(110)';
NODE_NAME     U7C1 BE66
 '@BASEBOARD_FAB2_LIB.BASEBOARD_FAB2(SCH_1):PAGE124_I16@MSTR_U_PROC.LBG_CORE_QAT_EXT_D(CHIPS)':
 'VSS'<111>: CDS_PINID='VSS(111)';
NODE_NAME     U7C1 BE63
 '@BASEBOARD_FAB2_LIB.BASEBOARD_FAB2(SCH_1):PAGE124_I16@MSTR_U_PROC.LBG_CORE_QAT_EXT_D(CHIPS)':
 'VSS'<112>: CDS_PINID='VSS(112)';
NODE_NAME     U7C1 BE59
 '@BASEBOARD_FAB2_LIB.BASEBOARD_FAB2(SCH_1):PAGE124_I16@MSTR_U_PROC.LBG_CORE_QAT_EXT_D(CHIPS)':
 'VSS'<113>: CDS_PINID='VSS(113)';
NODE_NAME     U7C1 BE56
 '@BASEBOARD_FAB2_LIB.BASEBOARD_FAB2(SCH_1):PAGE124_I16@MSTR_U_PROC.LBG_CORE_QAT_EXT_D(CHIPS)':
 'VSS'<114>: CDS_PINID='VSS(114)';
NODE_NAME     U7C1 BE37
 '@BASEBOARD_FAB2_LIB.BASEBOARD_FAB2(SCH_1):PAGE124_I16@MSTR_U_PROC.LBG_CORE_QAT_EXT_D(CHIPS)':
 'VSS'<115>: CDS_PINID='VSS(115)';
NODE_NAME     U7C1 BE33
 '@BASEBOARD_FAB2_LIB.BASEBOARD_FAB2(SCH_1):PAGE124_I16@MSTR_U_PROC.LBG_CORE_QAT_EXT_D(CHIPS)':
 'VSS'<116>: CDS_PINID='VSS(116)';
NODE_NAME     U7C1 BE29
 '@BASEBOARD_FAB2_LIB.BASEBOARD_FAB2(SCH_1):PAGE124_I16@MSTR_U_PROC.LBG_CORE_QAT_EXT_D(CHIPS)':
 'VSS'<117>: CDS_PINID='VSS(117)';
NODE_NAME     U7C1 BD68
 '@BASEBOARD_FAB2_LIB.BASEBOARD_FAB2(SCH_1):PAGE124_I16@MSTR_U_PROC.LBG_CORE_QAT_EXT_D(CHIPS)':
 'VSS'<118>: CDS_PINID='VSS(118)';
NODE_NAME     U7C1 BD54
 '@BASEBOARD_FAB2_LIB.BASEBOARD_FAB2(SCH_1):PAGE124_I16@MSTR_U_PROC.LBG_CORE_QAT_EXT_D(CHIPS)':
 'VSS'<119>: CDS_PINID='VSS(119)';
NODE_NAME     U7C1 BD50
 '@BASEBOARD_FAB2_LIB.BASEBOARD_FAB2(SCH_1):PAGE124_I16@MSTR_U_PROC.LBG_CORE_QAT_EXT_D(CHIPS)':
 'VSS'<120>: CDS_PINID='VSS(120)';
NODE_NAME     U7C1 BD5
 '@BASEBOARD_FAB2_LIB.BASEBOARD_FAB2(SCH_1):PAGE124_I16@MSTR_U_PROC.LBG_CORE_QAT_EXT_D(CHIPS)':
 'VSS'<121>: CDS_PINID='VSS(121)';
NODE_NAME     U7C1 BD35
 '@BASEBOARD_FAB2_LIB.BASEBOARD_FAB2(SCH_1):PAGE124_I16@MSTR_U_PROC.LBG_CORE_QAT_EXT_D(CHIPS)':
 'VSS'<122>: CDS_PINID='VSS(122)';
NODE_NAME     U7C1 BD31
 '@BASEBOARD_FAB2_LIB.BASEBOARD_FAB2(SCH_1):PAGE124_I16@MSTR_U_PROC.LBG_CORE_QAT_EXT_D(CHIPS)':
 'VSS'<123>: CDS_PINID='VSS(123)';
NODE_NAME     U7C1 BD27
 '@BASEBOARD_FAB2_LIB.BASEBOARD_FAB2(SCH_1):PAGE124_I16@MSTR_U_PROC.LBG_CORE_QAT_EXT_D(CHIPS)':
 'VSS'<124>: CDS_PINID='VSS(124)';
NODE_NAME     U7C1 BD24
 '@BASEBOARD_FAB2_LIB.BASEBOARD_FAB2(SCH_1):PAGE124_I16@MSTR_U_PROC.LBG_CORE_QAT_EXT_D(CHIPS)':
 'VSS'<125>: CDS_PINID='VSS(125)';
NODE_NAME     U7C1 BC71
 '@BASEBOARD_FAB2_LIB.BASEBOARD_FAB2(SCH_1):PAGE124_I16@MSTR_U_PROC.LBG_CORE_QAT_EXT_D(CHIPS)':
 'VSS'<126>: CDS_PINID='VSS(126)';
NODE_NAME     U7C1 BC69
 '@BASEBOARD_FAB2_LIB.BASEBOARD_FAB2(SCH_1):PAGE124_I16@MSTR_U_PROC.LBG_CORE_QAT_EXT_D(CHIPS)':
 'VSS'<127>: CDS_PINID='VSS(127)';
NODE_NAME     U7C1 BB72
 '@BASEBOARD_FAB2_LIB.BASEBOARD_FAB2(SCH_1):PAGE124_I16@MSTR_U_PROC.LBG_CORE_QAT_EXT_D(CHIPS)':
 'VSS'<128>: CDS_PINID='VSS(128)';
NODE_NAME     U7C1 BB70
 '@BASEBOARD_FAB2_LIB.BASEBOARD_FAB2(SCH_1):PAGE124_I16@MSTR_U_PROC.LBG_CORE_QAT_EXT_D(CHIPS)':
 'VSS'<129>: CDS_PINID='VSS(129)';
NODE_NAME     U7C1 BB68
 '@BASEBOARD_FAB2_LIB.BASEBOARD_FAB2(SCH_1):PAGE124_I16@MSTR_U_PROC.LBG_CORE_QAT_EXT_D(CHIPS)':
 'VSS'<130>: CDS_PINID='VSS(130)';
NODE_NAME     U7C1 BB66
 '@BASEBOARD_FAB2_LIB.BASEBOARD_FAB2(SCH_1):PAGE124_I16@MSTR_U_PROC.LBG_CORE_QAT_EXT_D(CHIPS)':
 'VSS'<131>: CDS_PINID='VSS(131)';
NODE_NAME     U7C1 BB59
 '@BASEBOARD_FAB2_LIB.BASEBOARD_FAB2(SCH_1):PAGE124_I16@MSTR_U_PROC.LBG_CORE_QAT_EXT_D(CHIPS)':
 'VSS'<132>: CDS_PINID='VSS(132)';
NODE_NAME     U7C1 BB44
 '@BASEBOARD_FAB2_LIB.BASEBOARD_FAB2(SCH_1):PAGE124_I16@MSTR_U_PROC.LBG_CORE_QAT_EXT_D(CHIPS)':
 'VSS'<133>: CDS_PINID='VSS(133)';
NODE_NAME     U7C1 BB22
 '@BASEBOARD_FAB2_LIB.BASEBOARD_FAB2(SCH_1):PAGE124_I16@MSTR_U_PROC.LBG_CORE_QAT_EXT_D(CHIPS)':
 'VSS'<134>: CDS_PINID='VSS(134)';
NODE_NAME     U7C1 BB18
 '@BASEBOARD_FAB2_LIB.BASEBOARD_FAB2(SCH_1):PAGE124_I16@MSTR_U_PROC.LBG_CORE_QAT_EXT_D(CHIPS)':
 'VSS'<135>: CDS_PINID='VSS(135)';
NODE_NAME     U7C1 BB15
 '@BASEBOARD_FAB2_LIB.BASEBOARD_FAB2(SCH_1):PAGE124_I16@MSTR_U_PROC.LBG_CORE_QAT_EXT_D(CHIPS)':
 'VSS'<136>: CDS_PINID='VSS(136)';
NODE_NAME     U7C1 BB11
 '@BASEBOARD_FAB2_LIB.BASEBOARD_FAB2(SCH_1):PAGE124_I16@MSTR_U_PROC.LBG_CORE_QAT_EXT_D(CHIPS)':
 'VSS'<137>: CDS_PINID='VSS(137)';
NODE_NAME     U7C1 BB7
 '@BASEBOARD_FAB2_LIB.BASEBOARD_FAB2(SCH_1):PAGE124_I16@MSTR_U_PROC.LBG_CORE_QAT_EXT_D(CHIPS)':
 'VSS'<138>: CDS_PINID='VSS(138)';
NODE_NAME     U7C1 BB5
 '@BASEBOARD_FAB2_LIB.BASEBOARD_FAB2(SCH_1):PAGE124_I16@MSTR_U_PROC.LBG_CORE_QAT_EXT_D(CHIPS)':
 'VSS'<139>: CDS_PINID='VSS(139)';
NODE_NAME     U7C1 BA58
 '@BASEBOARD_FAB2_LIB.BASEBOARD_FAB2(SCH_1):PAGE124_I16@MSTR_U_PROC.LBG_CORE_QAT_EXT_D(CHIPS)':
 'VSS'<140>: CDS_PINID='VSS(140)';
NODE_NAME     U7C1 BA54
 '@BASEBOARD_FAB2_LIB.BASEBOARD_FAB2(SCH_1):PAGE124_I16@MSTR_U_PROC.LBG_CORE_QAT_EXT_D(CHIPS)':
 'VSS'<141>: CDS_PINID='VSS(141)';
NODE_NAME     U7C1 BA50
 '@BASEBOARD_FAB2_LIB.BASEBOARD_FAB2(SCH_1):PAGE124_I16@MSTR_U_PROC.LBG_CORE_QAT_EXT_D(CHIPS)':
 'VSS'<142>: CDS_PINID='VSS(142)';
NODE_NAME     U7C1 AY68
 '@BASEBOARD_FAB2_LIB.BASEBOARD_FAB2(SCH_1):PAGE124_I16@MSTR_U_PROC.LBG_CORE_QAT_EXT_D(CHIPS)':
 'VSS'<143>: CDS_PINID='VSS(143)';
NODE_NAME     U7C1 AY63
 '@BASEBOARD_FAB2_LIB.BASEBOARD_FAB2(SCH_1):PAGE124_I16@MSTR_U_PROC.LBG_CORE_QAT_EXT_D(CHIPS)':
 'VSS'<144>: CDS_PINID='VSS(144)';
NODE_NAME     U7C1 AY56
 '@BASEBOARD_FAB2_LIB.BASEBOARD_FAB2(SCH_1):PAGE124_I16@MSTR_U_PROC.LBG_CORE_QAT_EXT_D(CHIPS)':
 'VSS'<145>: CDS_PINID='VSS(145)';
NODE_NAME     U7C1 AY22
 '@BASEBOARD_FAB2_LIB.BASEBOARD_FAB2(SCH_1):PAGE124_I16@MSTR_U_PROC.LBG_CORE_QAT_EXT_D(CHIPS)':
 'VSS'<146>: CDS_PINID='VSS(146)';
NODE_NAME     U7C1 AY5
 '@BASEBOARD_FAB2_LIB.BASEBOARD_FAB2(SCH_1):PAGE124_I16@MSTR_U_PROC.LBG_CORE_QAT_EXT_D(CHIPS)':
 'VSS'<147>: CDS_PINID='VSS(147)';
NODE_NAME     U7C1 AW61
 '@BASEBOARD_FAB2_LIB.BASEBOARD_FAB2(SCH_1):PAGE124_I16@MSTR_U_PROC.LBG_CORE_QAT_EXT_D(CHIPS)':
 'VSS'<148>: CDS_PINID='VSS(148)';
NODE_NAME     U7C1 AW58
 '@BASEBOARD_FAB2_LIB.BASEBOARD_FAB2(SCH_1):PAGE124_I16@MSTR_U_PROC.LBG_CORE_QAT_EXT_D(CHIPS)':
 'VSS'<149>: CDS_PINID='VSS(149)';
NODE_NAME     U7C1 AW50
 '@BASEBOARD_FAB2_LIB.BASEBOARD_FAB2(SCH_1):PAGE124_I16@MSTR_U_PROC.LBG_CORE_QAT_EXT_D(CHIPS)':
 'VSS'<150>: CDS_PINID='VSS(150)';
NODE_NAME     U7C1 AW46
 '@BASEBOARD_FAB2_LIB.BASEBOARD_FAB2(SCH_1):PAGE124_I16@MSTR_U_PROC.LBG_CORE_QAT_EXT_D(CHIPS)':
 'VSS'<151>: CDS_PINID='VSS(151)';
NODE_NAME     U7C1 AW41
 '@BASEBOARD_FAB2_LIB.BASEBOARD_FAB2(SCH_1):PAGE124_I16@MSTR_U_PROC.LBG_CORE_QAT_EXT_D(CHIPS)':
 'VSS'<152>: CDS_PINID='VSS(152)';
NODE_NAME     U7C1 AW39
 '@BASEBOARD_FAB2_LIB.BASEBOARD_FAB2(SCH_1):PAGE124_I16@MSTR_U_PROC.LBG_CORE_QAT_EXT_D(CHIPS)':
 'VSS'<153>: CDS_PINID='VSS(153)';
NODE_NAME     U7C1 AW37
 '@BASEBOARD_FAB2_LIB.BASEBOARD_FAB2(SCH_1):PAGE124_I16@MSTR_U_PROC.LBG_CORE_QAT_EXT_D(CHIPS)':
 'VSS'<154>: CDS_PINID='VSS(154)';
NODE_NAME     U7C1 AW36
 '@BASEBOARD_FAB2_LIB.BASEBOARD_FAB2(SCH_1):PAGE124_I16@MSTR_U_PROC.LBG_CORE_QAT_EXT_D(CHIPS)':
 'VSS'<155>: CDS_PINID='VSS(155)';
NODE_NAME     U7C1 AW34
 '@BASEBOARD_FAB2_LIB.BASEBOARD_FAB2(SCH_1):PAGE124_I16@MSTR_U_PROC.LBG_CORE_QAT_EXT_D(CHIPS)':
 'VSS'<156>: CDS_PINID='VSS(156)';
NODE_NAME     U7C1 AW32
 '@BASEBOARD_FAB2_LIB.BASEBOARD_FAB2(SCH_1):PAGE124_I16@MSTR_U_PROC.LBG_CORE_QAT_EXT_D(CHIPS)':
 'VSS'<157>: CDS_PINID='VSS(157)';
NODE_NAME     U7C1 AW30
 '@BASEBOARD_FAB2_LIB.BASEBOARD_FAB2(SCH_1):PAGE124_I16@MSTR_U_PROC.LBG_CORE_QAT_EXT_D(CHIPS)':
 'VSS'<158>: CDS_PINID='VSS(158)';
NODE_NAME     U7C1 AW26
 '@BASEBOARD_FAB2_LIB.BASEBOARD_FAB2(SCH_1):PAGE124_I16@MSTR_U_PROC.LBG_CORE_QAT_EXT_D(CHIPS)':
 'VSS'<159>: CDS_PINID='VSS(159)';
NODE_NAME     U7C1 AW17
 '@BASEBOARD_FAB2_LIB.BASEBOARD_FAB2(SCH_1):PAGE124_I16@MSTR_U_PROC.LBG_CORE_QAT_EXT_D(CHIPS)':
 'VSS'<160>: CDS_PINID='VSS(160)';
NODE_NAME     U7C1 AW13
 '@BASEBOARD_FAB2_LIB.BASEBOARD_FAB2(SCH_1):PAGE124_I16@MSTR_U_PROC.LBG_CORE_QAT_EXT_D(CHIPS)':
 'VSS'<161>: CDS_PINID='VSS(161)';
NODE_NAME     U7C1 AW9
 '@BASEBOARD_FAB2_LIB.BASEBOARD_FAB2(SCH_1):PAGE124_I16@MSTR_U_PROC.LBG_CORE_QAT_EXT_D(CHIPS)':
 'VSS'<162>: CDS_PINID='VSS(162)';
NODE_NAME     U7C1 AV68
 '@BASEBOARD_FAB2_LIB.BASEBOARD_FAB2(SCH_1):PAGE124_I16@MSTR_U_PROC.LBG_CORE_QAT_EXT_D(CHIPS)':
 'VSS'<163>: CDS_PINID='VSS(163)';
NODE_NAME     U7C1 AV59
 '@BASEBOARD_FAB2_LIB.BASEBOARD_FAB2(SCH_1):PAGE124_I16@MSTR_U_PROC.LBG_CORE_QAT_EXT_D(CHIPS)':
 'VSS'<164>: CDS_PINID='VSS(164)';
NODE_NAME     U7C1 AV22
 '@BASEBOARD_FAB2_LIB.BASEBOARD_FAB2(SCH_1):PAGE124_I16@MSTR_U_PROC.LBG_CORE_QAT_EXT_D(CHIPS)':
 'VSS'<165>: CDS_PINID='VSS(165)';
NODE_NAME     U7C1 AV5
 '@BASEBOARD_FAB2_LIB.BASEBOARD_FAB2(SCH_1):PAGE124_I16@MSTR_U_PROC.LBG_CORE_QAT_EXT_D(CHIPS)':
 'VSS'<166>: CDS_PINID='VSS(166)';
NODE_NAME     U7C1 AU61
 '@BASEBOARD_FAB2_LIB.BASEBOARD_FAB2(SCH_1):PAGE124_I16@MSTR_U_PROC.LBG_CORE_QAT_EXT_D(CHIPS)':
 'VSS'<167>: CDS_PINID='VSS(167)';
NODE_NAME     U7C1 AU54
 '@BASEBOARD_FAB2_LIB.BASEBOARD_FAB2(SCH_1):PAGE124_I16@MSTR_U_PROC.LBG_CORE_QAT_EXT_D(CHIPS)':
 'VSS'<168>: CDS_PINID='VSS(168)';
NODE_NAME     U7C1 AU50
 '@BASEBOARD_FAB2_LIB.BASEBOARD_FAB2(SCH_1):PAGE124_I16@MSTR_U_PROC.LBG_CORE_QAT_EXT_D(CHIPS)':
 'VSS'<169>: CDS_PINID='VSS(169)';
NODE_NAME     U7C1 AU46
 '@BASEBOARD_FAB2_LIB.BASEBOARD_FAB2(SCH_1):PAGE124_I16@MSTR_U_PROC.LBG_CORE_QAT_EXT_D(CHIPS)':
 'VSS'<170>: CDS_PINID='VSS(170)';
NODE_NAME     U7C1 AU41
 '@BASEBOARD_FAB2_LIB.BASEBOARD_FAB2(SCH_1):PAGE124_I16@MSTR_U_PROC.LBG_CORE_QAT_EXT_D(CHIPS)':
 'VSS'<171>: CDS_PINID='VSS(171)';
NODE_NAME     U7C1 AE22
 '@BASEBOARD_FAB2_LIB.BASEBOARD_FAB2(SCH_1):PAGE124_I16@MSTR_U_PROC.LBG_CORE_QAT_EXT_D(CHIPS)':
 'VSS'<172>: CDS_PINID='VSS(172)';
NODE_NAME     U7C1 AU30
 '@BASEBOARD_FAB2_LIB.BASEBOARD_FAB2(SCH_1):PAGE124_I16@MSTR_U_PROC.LBG_CORE_QAT_EXT_D(CHIPS)':
 'VSS'<173>: CDS_PINID='VSS(173)';
NODE_NAME     U7C1 AU26
 '@BASEBOARD_FAB2_LIB.BASEBOARD_FAB2(SCH_1):PAGE124_I16@MSTR_U_PROC.LBG_CORE_QAT_EXT_D(CHIPS)':
 'VSS'<174>: CDS_PINID='VSS(174)';
NODE_NAME     U7C1 AT59
 '@BASEBOARD_FAB2_LIB.BASEBOARD_FAB2(SCH_1):PAGE124_I16@MSTR_U_PROC.LBG_CORE_QAT_EXT_D(CHIPS)':
 'VSS'<175>: CDS_PINID='VSS(175)';
NODE_NAME     U7C1 AT46
 '@BASEBOARD_FAB2_LIB.BASEBOARD_FAB2(SCH_1):PAGE124_I16@MSTR_U_PROC.LBG_CORE_QAT_EXT_D(CHIPS)':
 'VSS'<176>: CDS_PINID='VSS(176)';
NODE_NAME     U7C1 AT41
 '@BASEBOARD_FAB2_LIB.BASEBOARD_FAB2(SCH_1):PAGE124_I16@MSTR_U_PROC.LBG_CORE_QAT_EXT_D(CHIPS)':
 'VSS'<177>: CDS_PINID='VSS(177)';
NODE_NAME     U7C1 AT30
 '@BASEBOARD_FAB2_LIB.BASEBOARD_FAB2(SCH_1):PAGE124_I16@MSTR_U_PROC.LBG_CORE_QAT_EXT_D(CHIPS)':
 'VSS'<178>: CDS_PINID='VSS(178)';
NODE_NAME     U7C1 AT26
 '@BASEBOARD_FAB2_LIB.BASEBOARD_FAB2(SCH_1):PAGE124_I16@MSTR_U_PROC.LBG_CORE_QAT_EXT_D(CHIPS)':
 'VSS'<179>: CDS_PINID='VSS(179)';
NODE_NAME     U7C1 AT22
 '@BASEBOARD_FAB2_LIB.BASEBOARD_FAB2(SCH_1):PAGE124_I16@MSTR_U_PROC.LBG_CORE_QAT_EXT_D(CHIPS)':
 'VSS'<180>: CDS_PINID='VSS(180)';
NODE_NAME     U7C1 AT18
 '@BASEBOARD_FAB2_LIB.BASEBOARD_FAB2(SCH_1):PAGE124_I16@MSTR_U_PROC.LBG_CORE_QAT_EXT_D(CHIPS)':
 'VSS'<181>: CDS_PINID='VSS(181)';
NODE_NAME     U7C1 AT15
 '@BASEBOARD_FAB2_LIB.BASEBOARD_FAB2(SCH_1):PAGE124_I16@MSTR_U_PROC.LBG_CORE_QAT_EXT_D(CHIPS)':
 'VSS'<182>: CDS_PINID='VSS(182)';
NODE_NAME     U7C1 AT11
 '@BASEBOARD_FAB2_LIB.BASEBOARD_FAB2(SCH_1):PAGE124_I16@MSTR_U_PROC.LBG_CORE_QAT_EXT_D(CHIPS)':
 'VSS'<183>: CDS_PINID='VSS(183)';
NODE_NAME     U7C1 AT7
 '@BASEBOARD_FAB2_LIB.BASEBOARD_FAB2(SCH_1):PAGE124_I16@MSTR_U_PROC.LBG_CORE_QAT_EXT_D(CHIPS)':
 'VSS'<184>: CDS_PINID='VSS(184)';
NODE_NAME     U7C1 AR72
 '@BASEBOARD_FAB2_LIB.BASEBOARD_FAB2(SCH_1):PAGE124_I16@MSTR_U_PROC.LBG_CORE_QAT_EXT_D(CHIPS)':
 'VSS'<185>: CDS_PINID='VSS(185)';
NODE_NAME     U7C1 AR70
 '@BASEBOARD_FAB2_LIB.BASEBOARD_FAB2(SCH_1):PAGE124_I16@MSTR_U_PROC.LBG_CORE_QAT_EXT_D(CHIPS)':
 'VSS'<186>: CDS_PINID='VSS(186)';
NODE_NAME     U7C1 AR68
 '@BASEBOARD_FAB2_LIB.BASEBOARD_FAB2(SCH_1):PAGE124_I16@MSTR_U_PROC.LBG_CORE_QAT_EXT_D(CHIPS)':
 'VSS'<187>: CDS_PINID='VSS(187)';
NODE_NAME     U7C1 AR65
 '@BASEBOARD_FAB2_LIB.BASEBOARD_FAB2(SCH_1):PAGE124_I16@MSTR_U_PROC.LBG_CORE_QAT_EXT_D(CHIPS)':
 'VSS'<188>: CDS_PINID='VSS(188)';
NODE_NAME     U7C1 AR58
 '@BASEBOARD_FAB2_LIB.BASEBOARD_FAB2(SCH_1):PAGE124_I16@MSTR_U_PROC.LBG_CORE_QAT_EXT_D(CHIPS)':
 'VSS'<189>: CDS_PINID='VSS(189)';
NODE_NAME     U7C1 AR50
 '@BASEBOARD_FAB2_LIB.BASEBOARD_FAB2(SCH_1):PAGE124_I16@MSTR_U_PROC.LBG_CORE_QAT_EXT_D(CHIPS)':
 'VSS'<190>: CDS_PINID='VSS(190)';
NODE_NAME     U7C1 AR5
 '@BASEBOARD_FAB2_LIB.BASEBOARD_FAB2(SCH_1):PAGE124_I16@MSTR_U_PROC.LBG_CORE_QAT_EXT_D(CHIPS)':
 'VSS'<191>: CDS_PINID='VSS(191)';
NODE_NAME     U7C1 AP66
 '@BASEBOARD_FAB2_LIB.BASEBOARD_FAB2(SCH_1):PAGE124_I16@MSTR_U_PROC.LBG_CORE_QAT_EXT_D(CHIPS)':
 'VSS'<192>: CDS_PINID='VSS(192)';
NODE_NAME     U7C1 AP52
 '@BASEBOARD_FAB2_LIB.BASEBOARD_FAB2(SCH_1):PAGE124_I16@MSTR_U_PROC.LBG_CORE_QAT_EXT_D(CHIPS)':
 'VSS'<193>: CDS_PINID='VSS(193)';
NODE_NAME     U7C1 AP46
 '@BASEBOARD_FAB2_LIB.BASEBOARD_FAB2(SCH_1):PAGE124_I16@MSTR_U_PROC.LBG_CORE_QAT_EXT_D(CHIPS)':
 'VSS'<194>: CDS_PINID='VSS(194)';
NODE_NAME     U7C1 AP41
 '@BASEBOARD_FAB2_LIB.BASEBOARD_FAB2(SCH_1):PAGE124_I16@MSTR_U_PROC.LBG_CORE_QAT_EXT_D(CHIPS)':
 'VSS'<195>: CDS_PINID='VSS(195)';
NODE_NAME     U7C1 AP4
 '@BASEBOARD_FAB2_LIB.BASEBOARD_FAB2(SCH_1):PAGE124_I16@MSTR_U_PROC.LBG_CORE_QAT_EXT_D(CHIPS)':
 'VSS'<196>: CDS_PINID='VSS(196)';
NODE_NAME     U7C1 AP30
 '@BASEBOARD_FAB2_LIB.BASEBOARD_FAB2(SCH_1):PAGE124_I16@MSTR_U_PROC.LBG_CORE_QAT_EXT_D(CHIPS)':
 'VSS'<197>: CDS_PINID='VSS(197)';
NODE_NAME     U7C1 AP26
 '@BASEBOARD_FAB2_LIB.BASEBOARD_FAB2(SCH_1):PAGE124_I16@MSTR_U_PROC.LBG_CORE_QAT_EXT_D(CHIPS)':
 'VSS'<198>: CDS_PINID='VSS(198)';
NODE_NAME     U7C1 AP2
 '@BASEBOARD_FAB2_LIB.BASEBOARD_FAB2(SCH_1):PAGE124_I16@MSTR_U_PROC.LBG_CORE_QAT_EXT_D(CHIPS)':
 'VSS'<199>: CDS_PINID='VSS(199)';
NODE_NAME     U7C1 AN9
 '@BASEBOARD_FAB2_LIB.BASEBOARD_FAB2(SCH_1):PAGE124_I16@MSTR_U_PROC.LBG_CORE_QAT_EXT_D(CHIPS)':
 'VSS'<200>: CDS_PINID='VSS(200)';
NODE_NAME     U7C1 AN58
 '@BASEBOARD_FAB2_LIB.BASEBOARD_FAB2(SCH_1):PAGE124_I16@MSTR_U_PROC.LBG_CORE_QAT_EXT_D(CHIPS)':
 'VSS'<201>: CDS_PINID='VSS(201)';
NODE_NAME     U7C1 AN5
 '@BASEBOARD_FAB2_LIB.BASEBOARD_FAB2(SCH_1):PAGE124_I16@MSTR_U_PROC.LBG_CORE_QAT_EXT_D(CHIPS)':
 'VSS'<202>: CDS_PINID='VSS(202)';
NODE_NAME     U7C1 AN20
 '@BASEBOARD_FAB2_LIB.BASEBOARD_FAB2(SCH_1):PAGE124_I16@MSTR_U_PROC.LBG_CORE_QAT_EXT_D(CHIPS)':
 'VSS'<203>: CDS_PINID='VSS(203)';
NODE_NAME     U7C1 AP22
 '@BASEBOARD_FAB2_LIB.BASEBOARD_FAB2(SCH_1):PAGE124_I16@MSTR_U_PROC.LBG_CORE_QAT_EXT_D(CHIPS)':
 'VSS'<204>: CDS_PINID='VSS(204)';
NODE_NAME     U7C1 AN68
 '@BASEBOARD_FAB2_LIB.BASEBOARD_FAB2(SCH_1):PAGE124_I16@MSTR_U_PROC.LBG_CORE_QAT_EXT_D(CHIPS)':
 'VSS'<205>: CDS_PINID='VSS(205)';
NODE_NAME     U7C1 AN17
 '@BASEBOARD_FAB2_LIB.BASEBOARD_FAB2(SCH_1):PAGE124_I16@MSTR_U_PROC.LBG_CORE_QAT_EXT_D(CHIPS)':
 'VSS'<206>: CDS_PINID='VSS(206)';
NODE_NAME     U7C1 AN13
 '@BASEBOARD_FAB2_LIB.BASEBOARD_FAB2(SCH_1):PAGE124_I16@MSTR_U_PROC.LBG_CORE_QAT_EXT_D(CHIPS)':
 'VSS'<207>: CDS_PINID='VSS(207)';
NODE_NAME     U7C1 AM46
 '@BASEBOARD_FAB2_LIB.BASEBOARD_FAB2(SCH_1):PAGE124_I16@MSTR_U_PROC.LBG_CORE_QAT_EXT_D(CHIPS)':
 'VSS'<208>: CDS_PINID='VSS(208)';
NODE_NAME     U7C1 AM41
 '@BASEBOARD_FAB2_LIB.BASEBOARD_FAB2(SCH_1):PAGE124_I16@MSTR_U_PROC.LBG_CORE_QAT_EXT_D(CHIPS)':
 'VSS'<209>: CDS_PINID='VSS(209)';
NODE_NAME     U7C1 AM30
 '@BASEBOARD_FAB2_LIB.BASEBOARD_FAB2(SCH_1):PAGE124_I16@MSTR_U_PROC.LBG_CORE_QAT_EXT_D(CHIPS)':
 'VSS'<210>: CDS_PINID='VSS(210)';
NODE_NAME     U7C1 AM26
 '@BASEBOARD_FAB2_LIB.BASEBOARD_FAB2(SCH_1):PAGE124_I16@MSTR_U_PROC.LBG_CORE_QAT_EXT_D(CHIPS)':
 'VSS'<211>: CDS_PINID='VSS(211)';
NODE_NAME     U7C1 AL72
 '@BASEBOARD_FAB2_LIB.BASEBOARD_FAB2(SCH_1):PAGE124_I16@MSTR_U_PROC.LBG_CORE_QAT_EXT_D(CHIPS)':
 'VSS'<212>: CDS_PINID='VSS(212)';
NODE_NAME     U7C1 AL70
 '@BASEBOARD_FAB2_LIB.BASEBOARD_FAB2(SCH_1):PAGE124_I16@MSTR_U_PROC.LBG_CORE_QAT_EXT_D(CHIPS)':
 'VSS'<213>: CDS_PINID='VSS(213)';
NODE_NAME     U7C1 AL68
 '@BASEBOARD_FAB2_LIB.BASEBOARD_FAB2(SCH_1):PAGE124_I16@MSTR_U_PROC.LBG_CORE_QAT_EXT_D(CHIPS)':
 'VSS'<214>: CDS_PINID='VSS(214)';
NODE_NAME     U7C1 AL59
 '@BASEBOARD_FAB2_LIB.BASEBOARD_FAB2(SCH_1):PAGE124_I17@MSTR_U_PROC.LBG_CORE_QAT_EXT_D(CHIPS)':
 'VSS'<215>: CDS_PINID='VSS(215)';
NODE_NAME     U7C1 AL52
 '@BASEBOARD_FAB2_LIB.BASEBOARD_FAB2(SCH_1):PAGE124_I17@MSTR_U_PROC.LBG_CORE_QAT_EXT_D(CHIPS)':
 'VSS'<216>: CDS_PINID='VSS(216)';
NODE_NAME     U7C1 AL5
 '@BASEBOARD_FAB2_LIB.BASEBOARD_FAB2(SCH_1):PAGE124_I17@MSTR_U_PROC.LBG_CORE_QAT_EXT_D(CHIPS)':
 'VSS'<217>: CDS_PINID='VSS(217)';
NODE_NAME     U7C1 AL22
 '@BASEBOARD_FAB2_LIB.BASEBOARD_FAB2(SCH_1):PAGE124_I17@MSTR_U_PROC.LBG_CORE_QAT_EXT_D(CHIPS)':
 'VSS'<218>: CDS_PINID='VSS(218)';
NODE_NAME     U7C1 AK71
 '@BASEBOARD_FAB2_LIB.BASEBOARD_FAB2(SCH_1):PAGE124_I17@MSTR_U_PROC.LBG_CORE_QAT_EXT_D(CHIPS)':
 'VSS'<219>: CDS_PINID='VSS(219)';
NODE_NAME     U7C1 AK69
 '@BASEBOARD_FAB2_LIB.BASEBOARD_FAB2(SCH_1):PAGE124_I17@MSTR_U_PROC.LBG_CORE_QAT_EXT_D(CHIPS)':
 'VSS'<220>: CDS_PINID='VSS(220)';
NODE_NAME     U7C1 AK61
 '@BASEBOARD_FAB2_LIB.BASEBOARD_FAB2(SCH_1):PAGE124_I17@MSTR_U_PROC.LBG_CORE_QAT_EXT_D(CHIPS)':
 'VSS'<221>: CDS_PINID='VSS(221)';
NODE_NAME     U7C1 AK58
 '@BASEBOARD_FAB2_LIB.BASEBOARD_FAB2(SCH_1):PAGE124_I17@MSTR_U_PROC.LBG_CORE_QAT_EXT_D(CHIPS)':
 'VSS'<222>: CDS_PINID='VSS(222)';
NODE_NAME     U7C1 AK48
 '@BASEBOARD_FAB2_LIB.BASEBOARD_FAB2(SCH_1):PAGE124_I17@MSTR_U_PROC.LBG_CORE_QAT_EXT_D(CHIPS)':
 'VSS'<223>: CDS_PINID='VSS(223)';
NODE_NAME     U7C1 AK46
 '@BASEBOARD_FAB2_LIB.BASEBOARD_FAB2(SCH_1):PAGE124_I17@MSTR_U_PROC.LBG_CORE_QAT_EXT_D(CHIPS)':
 'VSS'<224>: CDS_PINID='VSS(224)';
NODE_NAME     U7C1 AK41
 '@BASEBOARD_FAB2_LIB.BASEBOARD_FAB2(SCH_1):PAGE124_I17@MSTR_U_PROC.LBG_CORE_QAT_EXT_D(CHIPS)':
 'VSS'<225>: CDS_PINID='VSS(225)';
NODE_NAME     U7C1 AK26
 '@BASEBOARD_FAB2_LIB.BASEBOARD_FAB2(SCH_1):PAGE124_I17@MSTR_U_PROC.LBG_CORE_QAT_EXT_D(CHIPS)':
 'VSS'<226>: CDS_PINID='VSS(226)';
NODE_NAME     U7C1 AJ7
 '@BASEBOARD_FAB2_LIB.BASEBOARD_FAB2(SCH_1):PAGE124_I17@MSTR_U_PROC.LBG_CORE_QAT_EXT_D(CHIPS)':
 'VSS'<227>: CDS_PINID='VSS(227)';
NODE_NAME     U7C1 AJ68
 '@BASEBOARD_FAB2_LIB.BASEBOARD_FAB2(SCH_1):PAGE124_I17@MSTR_U_PROC.LBG_CORE_QAT_EXT_D(CHIPS)':
 'VSS'<228>: CDS_PINID='VSS(228)';
NODE_NAME     U7C1 AJ66
 '@BASEBOARD_FAB2_LIB.BASEBOARD_FAB2(SCH_1):PAGE124_I17@MSTR_U_PROC.LBG_CORE_QAT_EXT_D(CHIPS)':
 'VSS'<229>: CDS_PINID='VSS(229)';
NODE_NAME     U7C1 AJ59
 '@BASEBOARD_FAB2_LIB.BASEBOARD_FAB2(SCH_1):PAGE124_I17@MSTR_U_PROC.LBG_CORE_QAT_EXT_D(CHIPS)':
 'VSS'<230>: CDS_PINID='VSS(230)';
NODE_NAME     U7C1 AJ52
 '@BASEBOARD_FAB2_LIB.BASEBOARD_FAB2(SCH_1):PAGE124_I17@MSTR_U_PROC.LBG_CORE_QAT_EXT_D(CHIPS)':
 'VSS'<231>: CDS_PINID='VSS(231)';
NODE_NAME     U7C1 AJ5
 '@BASEBOARD_FAB2_LIB.BASEBOARD_FAB2(SCH_1):PAGE124_I17@MSTR_U_PROC.LBG_CORE_QAT_EXT_D(CHIPS)':
 'VSS'<232>: CDS_PINID='VSS(232)';
NODE_NAME     U7C1 AJ41
 '@BASEBOARD_FAB2_LIB.BASEBOARD_FAB2(SCH_1):PAGE124_I17@MSTR_U_PROC.LBG_CORE_QAT_EXT_D(CHIPS)':
 'VSS'<233>: CDS_PINID='VSS(233)';
NODE_NAME     U7C1 AJ39
 '@BASEBOARD_FAB2_LIB.BASEBOARD_FAB2(SCH_1):PAGE124_I17@MSTR_U_PROC.LBG_CORE_QAT_EXT_D(CHIPS)':
 'VSS'<234>: CDS_PINID='VSS(234)';
NODE_NAME     U7C1 AJ37
 '@BASEBOARD_FAB2_LIB.BASEBOARD_FAB2(SCH_1):PAGE124_I17@MSTR_U_PROC.LBG_CORE_QAT_EXT_D(CHIPS)':
 'VSS'<235>: CDS_PINID='VSS(235)';
NODE_NAME     U7C1 AJ36
 '@BASEBOARD_FAB2_LIB.BASEBOARD_FAB2(SCH_1):PAGE124_I17@MSTR_U_PROC.LBG_CORE_QAT_EXT_D(CHIPS)':
 'VSS'<236>: CDS_PINID='VSS(236)';
NODE_NAME     U7C1 AJ34
 '@BASEBOARD_FAB2_LIB.BASEBOARD_FAB2(SCH_1):PAGE124_I17@MSTR_U_PROC.LBG_CORE_QAT_EXT_D(CHIPS)':
 'VSS'<237>: CDS_PINID='VSS(237)';
NODE_NAME     U7C1 AJ30
 '@BASEBOARD_FAB2_LIB.BASEBOARD_FAB2(SCH_1):PAGE124_I17@MSTR_U_PROC.LBG_CORE_QAT_EXT_D(CHIPS)':
 'VSS'<238>: CDS_PINID='VSS(238)';
NODE_NAME     U7C1 AJ26
 '@BASEBOARD_FAB2_LIB.BASEBOARD_FAB2(SCH_1):PAGE124_I17@MSTR_U_PROC.LBG_CORE_QAT_EXT_D(CHIPS)':
 'VSS'<239>: CDS_PINID='VSS(239)';
NODE_NAME     U7C1 AJ22
 '@BASEBOARD_FAB2_LIB.BASEBOARD_FAB2(SCH_1):PAGE124_I17@MSTR_U_PROC.LBG_CORE_QAT_EXT_D(CHIPS)':
 'VSS'<240>: CDS_PINID='VSS(240)';
NODE_NAME     U7C1 AJ18
 '@BASEBOARD_FAB2_LIB.BASEBOARD_FAB2(SCH_1):PAGE124_I17@MSTR_U_PROC.LBG_CORE_QAT_EXT_D(CHIPS)':
 'VSS'<241>: CDS_PINID='VSS(241)';
NODE_NAME     U7C1 AJ15
 '@BASEBOARD_FAB2_LIB.BASEBOARD_FAB2(SCH_1):PAGE124_I17@MSTR_U_PROC.LBG_CORE_QAT_EXT_D(CHIPS)':
 'VSS'<242>: CDS_PINID='VSS(242)';
NODE_NAME     U7C1 AK30
 '@BASEBOARD_FAB2_LIB.BASEBOARD_FAB2(SCH_1):PAGE124_I17@MSTR_U_PROC.LBG_CORE_QAT_EXT_D(CHIPS)':
 'VSS'<243>: CDS_PINID='VSS(243)';
NODE_NAME     U7C1 AJ56
 '@BASEBOARD_FAB2_LIB.BASEBOARD_FAB2(SCH_1):PAGE124_I17@MSTR_U_PROC.LBG_CORE_QAT_EXT_D(CHIPS)':
 'VSS'<244>: CDS_PINID='VSS(244)';
NODE_NAME     U7C1 AJ32
 '@BASEBOARD_FAB2_LIB.BASEBOARD_FAB2(SCH_1):PAGE124_I17@MSTR_U_PROC.LBG_CORE_QAT_EXT_D(CHIPS)':
 'VSS'<245>: CDS_PINID='VSS(245)';
NODE_NAME     U7C1 AJ11
 '@BASEBOARD_FAB2_LIB.BASEBOARD_FAB2(SCH_1):PAGE124_I17@MSTR_U_PROC.LBG_CORE_QAT_EXT_D(CHIPS)':
 'VSS'<246>: CDS_PINID='VSS(246)';
NODE_NAME     U7C1 AH20
 '@BASEBOARD_FAB2_LIB.BASEBOARD_FAB2(SCH_1):PAGE124_I17@MSTR_U_PROC.LBG_CORE_QAT_EXT_D(CHIPS)':
 'VSS'<247>: CDS_PINID='VSS(247)';
NODE_NAME     U7C1 AG66
 '@BASEBOARD_FAB2_LIB.BASEBOARD_FAB2(SCH_1):PAGE124_I17@MSTR_U_PROC.LBG_CORE_QAT_EXT_D(CHIPS)':
 'VSS'<248>: CDS_PINID='VSS(248)';
NODE_NAME     U7C1 AG59
 '@BASEBOARD_FAB2_LIB.BASEBOARD_FAB2(SCH_1):PAGE124_I17@MSTR_U_PROC.LBG_CORE_QAT_EXT_D(CHIPS)':
 'VSS'<249>: CDS_PINID='VSS(249)';
NODE_NAME     U7C1 AG56
 '@BASEBOARD_FAB2_LIB.BASEBOARD_FAB2(SCH_1):PAGE124_I17@MSTR_U_PROC.LBG_CORE_QAT_EXT_D(CHIPS)':
 'VSS'<250>: CDS_PINID='VSS(250)';
NODE_NAME     U7C1 AG52
 '@BASEBOARD_FAB2_LIB.BASEBOARD_FAB2(SCH_1):PAGE124_I17@MSTR_U_PROC.LBG_CORE_QAT_EXT_D(CHIPS)':
 'VSS'<251>: CDS_PINID='VSS(251)';
NODE_NAME     U7C1 AG43
 '@BASEBOARD_FAB2_LIB.BASEBOARD_FAB2(SCH_1):PAGE124_I17@MSTR_U_PROC.LBG_CORE_QAT_EXT_D(CHIPS)':
 'VSS'<252>: CDS_PINID='VSS(252)';
NODE_NAME     U7C1 AG41
 '@BASEBOARD_FAB2_LIB.BASEBOARD_FAB2(SCH_1):PAGE124_I17@MSTR_U_PROC.LBG_CORE_QAT_EXT_D(CHIPS)':
 'VSS'<253>: CDS_PINID='VSS(253)';
NODE_NAME     U7C1 AG30
 '@BASEBOARD_FAB2_LIB.BASEBOARD_FAB2(SCH_1):PAGE124_I17@MSTR_U_PROC.LBG_CORE_QAT_EXT_D(CHIPS)':
 'VSS'<254>: CDS_PINID='VSS(254)';
NODE_NAME     U7C1 AG26
 '@BASEBOARD_FAB2_LIB.BASEBOARD_FAB2(SCH_1):PAGE124_I17@MSTR_U_PROC.LBG_CORE_QAT_EXT_D(CHIPS)':
 'VSS'<255>: CDS_PINID='VSS(255)';
NODE_NAME     U7C1 AF68
 '@BASEBOARD_FAB2_LIB.BASEBOARD_FAB2(SCH_1):PAGE124_I17@MSTR_U_PROC.LBG_CORE_QAT_EXT_D(CHIPS)':
 'VSS'<256>: CDS_PINID='VSS(256)';
NODE_NAME     U7C1 AF3
 '@BASEBOARD_FAB2_LIB.BASEBOARD_FAB2(SCH_1):PAGE124_I17@MSTR_U_PROC.LBG_CORE_QAT_EXT_D(CHIPS)':
 'VSS'<257>: CDS_PINID='VSS(257)';
NODE_NAME     U7C1 AF24
 '@BASEBOARD_FAB2_LIB.BASEBOARD_FAB2(SCH_1):PAGE124_I17@MSTR_U_PROC.LBG_CORE_QAT_EXT_D(CHIPS)':
 'VSS'<258>: CDS_PINID='VSS(258)';
NODE_NAME     U7C1 AF17
 '@BASEBOARD_FAB2_LIB.BASEBOARD_FAB2(SCH_1):PAGE124_I17@MSTR_U_PROC.LBG_CORE_QAT_EXT_D(CHIPS)':
 'VSS'<259>: CDS_PINID='VSS(259)';
NODE_NAME     U7C1 AF9
 '@BASEBOARD_FAB2_LIB.BASEBOARD_FAB2(SCH_1):PAGE124_I17@MSTR_U_PROC.LBG_CORE_QAT_EXT_D(CHIPS)':
 'VSS'<260>: CDS_PINID='VSS(260)';
NODE_NAME     U7C1 AF5
 '@BASEBOARD_FAB2_LIB.BASEBOARD_FAB2(SCH_1):PAGE124_I17@MSTR_U_PROC.LBG_CORE_QAT_EXT_D(CHIPS)':
 'VSS'<261>: CDS_PINID='VSS(261)';
NODE_NAME     U7C1 AF13
 '@BASEBOARD_FAB2_LIB.BASEBOARD_FAB2(SCH_1):PAGE124_I17@MSTR_U_PROC.LBG_CORE_QAT_EXT_D(CHIPS)':
 'VSS'<262>: CDS_PINID='VSS(262)';
NODE_NAME     U7C1 AF1
 '@BASEBOARD_FAB2_LIB.BASEBOARD_FAB2(SCH_1):PAGE124_I17@MSTR_U_PROC.LBG_CORE_QAT_EXT_D(CHIPS)':
 'VSS'<263>: CDS_PINID='VSS(263)';
NODE_NAME     U7C1 AE66
 '@BASEBOARD_FAB2_LIB.BASEBOARD_FAB2(SCH_1):PAGE124_I17@MSTR_U_PROC.LBG_CORE_QAT_EXT_D(CHIPS)':
 'VSS'<264>: CDS_PINID='VSS(264)';
NODE_NAME     U7C1 AE63
 '@BASEBOARD_FAB2_LIB.BASEBOARD_FAB2(SCH_1):PAGE124_I17@MSTR_U_PROC.LBG_CORE_QAT_EXT_D(CHIPS)':
 'VSS'<265>: CDS_PINID='VSS(265)';
NODE_NAME     U7C1 AE59
 '@BASEBOARD_FAB2_LIB.BASEBOARD_FAB2(SCH_1):PAGE124_I17@MSTR_U_PROC.LBG_CORE_QAT_EXT_D(CHIPS)':
 'VSS'<266>: CDS_PINID='VSS(266)';
NODE_NAME     U7C1 AE56
 '@BASEBOARD_FAB2_LIB.BASEBOARD_FAB2(SCH_1):PAGE124_I17@MSTR_U_PROC.LBG_CORE_QAT_EXT_D(CHIPS)':
 'VSS'<267>: CDS_PINID='VSS(267)';
NODE_NAME     U7C1 AE52
 '@BASEBOARD_FAB2_LIB.BASEBOARD_FAB2(SCH_1):PAGE124_I17@MSTR_U_PROC.LBG_CORE_QAT_EXT_D(CHIPS)':
 'VSS'<268>: CDS_PINID='VSS(268)';
NODE_NAME     U7C1 AE48
 '@BASEBOARD_FAB2_LIB.BASEBOARD_FAB2(SCH_1):PAGE124_I17@MSTR_U_PROC.LBG_CORE_QAT_EXT_D(CHIPS)':
 'VSS'<269>: CDS_PINID='VSS(269)';
NODE_NAME     U7C1 J18
 '@BASEBOARD_FAB2_LIB.BASEBOARD_FAB2(SCH_1):PAGE124_I17@MSTR_U_PROC.LBG_CORE_QAT_EXT_D(CHIPS)':
 'VSS'<270>: CDS_PINID='VSS(270)';
NODE_NAME     U7C1 AE29
 '@BASEBOARD_FAB2_LIB.BASEBOARD_FAB2(SCH_1):PAGE124_I17@MSTR_U_PROC.LBG_CORE_QAT_EXT_D(CHIPS)':
 'VSS'<271>: CDS_PINID='VSS(271)';
NODE_NAME     U7C1 AD68
 '@BASEBOARD_FAB2_LIB.BASEBOARD_FAB2(SCH_1):PAGE124_I17@MSTR_U_PROC.LBG_CORE_QAT_EXT_D(CHIPS)':
 'VSS'<272>: CDS_PINID='VSS(272)';
NODE_NAME     U7C1 AD65
 '@BASEBOARD_FAB2_LIB.BASEBOARD_FAB2(SCH_1):PAGE124_I17@MSTR_U_PROC.LBG_CORE_QAT_EXT_D(CHIPS)':
 'VSS'<273>: CDS_PINID='VSS(273)';
NODE_NAME     U7C1 AD5
 '@BASEBOARD_FAB2_LIB.BASEBOARD_FAB2(SCH_1):PAGE124_I17@MSTR_U_PROC.LBG_CORE_QAT_EXT_D(CHIPS)':
 'VSS'<274>: CDS_PINID='VSS(274)';
NODE_NAME     U7C1 AC7
 '@BASEBOARD_FAB2_LIB.BASEBOARD_FAB2(SCH_1):PAGE124_I17@MSTR_U_PROC.LBG_CORE_QAT_EXT_D(CHIPS)':
 'VSS'<275>: CDS_PINID='VSS(275)';
NODE_NAME     U7C1 AC66
 '@BASEBOARD_FAB2_LIB.BASEBOARD_FAB2(SCH_1):PAGE124_I17@MSTR_U_PROC.LBG_CORE_QAT_EXT_D(CHIPS)':
 'VSS'<276>: CDS_PINID='VSS(276)';
NODE_NAME     U7C1 AC63
 '@BASEBOARD_FAB2_LIB.BASEBOARD_FAB2(SCH_1):PAGE124_I17@MSTR_U_PROC.LBG_CORE_QAT_EXT_D(CHIPS)':
 'VSS'<277>: CDS_PINID='VSS(277)';
NODE_NAME     U7C1 AC59
 '@BASEBOARD_FAB2_LIB.BASEBOARD_FAB2(SCH_1):PAGE124_I17@MSTR_U_PROC.LBG_CORE_QAT_EXT_D(CHIPS)':
 'VSS'<278>: CDS_PINID='VSS(278)';
NODE_NAME     U7C1 AC52
 '@BASEBOARD_FAB2_LIB.BASEBOARD_FAB2(SCH_1):PAGE124_I17@MSTR_U_PROC.LBG_CORE_QAT_EXT_D(CHIPS)':
 'VSS'<279>: CDS_PINID='VSS(279)';
NODE_NAME     U7C1 AC48
 '@BASEBOARD_FAB2_LIB.BASEBOARD_FAB2(SCH_1):PAGE124_I17@MSTR_U_PROC.LBG_CORE_QAT_EXT_D(CHIPS)':
 'VSS'<280>: CDS_PINID='VSS(280)';
NODE_NAME     U7C1 AC46
 '@BASEBOARD_FAB2_LIB.BASEBOARD_FAB2(SCH_1):PAGE124_I17@MSTR_U_PROC.LBG_CORE_QAT_EXT_D(CHIPS)':
 'VSS'<281>: CDS_PINID='VSS(281)';
NODE_NAME     U7C1 AC43
 '@BASEBOARD_FAB2_LIB.BASEBOARD_FAB2(SCH_1):PAGE124_I17@MSTR_U_PROC.LBG_CORE_QAT_EXT_D(CHIPS)':
 'VSS'<282>: CDS_PINID='VSS(282)';
NODE_NAME     U7C1 AC27
 '@BASEBOARD_FAB2_LIB.BASEBOARD_FAB2(SCH_1):PAGE124_I17@MSTR_U_PROC.LBG_CORE_QAT_EXT_D(CHIPS)':
 'VSS'<283>: CDS_PINID='VSS(283)';
NODE_NAME     U7C1 AD58
 '@BASEBOARD_FAB2_LIB.BASEBOARD_FAB2(SCH_1):PAGE124_I17@MSTR_U_PROC.LBG_CORE_QAT_EXT_D(CHIPS)':
 'VSS'<284>: CDS_PINID='VSS(284)';
NODE_NAME     U7C1 AC45
 '@BASEBOARD_FAB2_LIB.BASEBOARD_FAB2(SCH_1):PAGE124_I17@MSTR_U_PROC.LBG_CORE_QAT_EXT_D(CHIPS)':
 'VSS'<285>: CDS_PINID='VSS(285)';
NODE_NAME     U7C1 AC22
 '@BASEBOARD_FAB2_LIB.BASEBOARD_FAB2(SCH_1):PAGE124_I17@MSTR_U_PROC.LBG_CORE_QAT_EXT_D(CHIPS)':
 'VSS'<286>: CDS_PINID='VSS(286)';
NODE_NAME     U7C1 AC18
 '@BASEBOARD_FAB2_LIB.BASEBOARD_FAB2(SCH_1):PAGE124_I17@MSTR_U_PROC.LBG_CORE_QAT_EXT_D(CHIPS)':
 'VSS'<287>: CDS_PINID='VSS(287)';
NODE_NAME     U7C1 AC15
 '@BASEBOARD_FAB2_LIB.BASEBOARD_FAB2(SCH_1):PAGE124_I17@MSTR_U_PROC.LBG_CORE_QAT_EXT_D(CHIPS)':
 'VSS'<288>: CDS_PINID='VSS(288)';
NODE_NAME     U7C1 AC11
 '@BASEBOARD_FAB2_LIB.BASEBOARD_FAB2(SCH_1):PAGE124_I17@MSTR_U_PROC.LBG_CORE_QAT_EXT_D(CHIPS)':
 'VSS'<289>: CDS_PINID='VSS(289)';
NODE_NAME     U7C1 AB72
 '@BASEBOARD_FAB2_LIB.BASEBOARD_FAB2(SCH_1):PAGE124_I17@MSTR_U_PROC.LBG_CORE_QAT_EXT_D(CHIPS)':
 'VSS'<290>: CDS_PINID='VSS(290)';
NODE_NAME     U7C1 AB70
 '@BASEBOARD_FAB2_LIB.BASEBOARD_FAB2(SCH_1):PAGE124_I17@MSTR_U_PROC.LBG_CORE_QAT_EXT_D(CHIPS)':
 'VSS'<291>: CDS_PINID='VSS(291)';
NODE_NAME     U7C1 AB68
 '@BASEBOARD_FAB2_LIB.BASEBOARD_FAB2(SCH_1):PAGE124_I17@MSTR_U_PROC.LBG_CORE_QAT_EXT_D(CHIPS)':
 'VSS'<292>: CDS_PINID='VSS(292)';
NODE_NAME     U7C1 AB5
 '@BASEBOARD_FAB2_LIB.BASEBOARD_FAB2(SCH_1):PAGE124_I17@MSTR_U_PROC.LBG_CORE_QAT_EXT_D(CHIPS)':
 'VSS'<293>: CDS_PINID='VSS(293)';
NODE_NAME     U7C1 AA48
 '@BASEBOARD_FAB2_LIB.BASEBOARD_FAB2(SCH_1):PAGE124_I17@MSTR_U_PROC.LBG_CORE_QAT_EXT_D(CHIPS)':
 'VSS'<294>: CDS_PINID='VSS(294)';
NODE_NAME     U7C1 AA43
 '@BASEBOARD_FAB2_LIB.BASEBOARD_FAB2(SCH_1):PAGE124_I17@MSTR_U_PROC.LBG_CORE_QAT_EXT_D(CHIPS)':
 'VSS'<295>: CDS_PINID='VSS(295)';
NODE_NAME     U7C1 AA27
 '@BASEBOARD_FAB2_LIB.BASEBOARD_FAB2(SCH_1):PAGE124_I17@MSTR_U_PROC.LBG_CORE_QAT_EXT_D(CHIPS)':
 'VSS'<296>: CDS_PINID='VSS(296)';
NODE_NAME     U7C1 AA26
 '@BASEBOARD_FAB2_LIB.BASEBOARD_FAB2(SCH_1):PAGE124_I17@MSTR_U_PROC.LBG_CORE_QAT_EXT_D(CHIPS)':
 'VSS'<297>: CDS_PINID='VSS(297)';
NODE_NAME     U7C1 Y68
 '@BASEBOARD_FAB2_LIB.BASEBOARD_FAB2(SCH_1):PAGE124_I17@MSTR_U_PROC.LBG_CORE_QAT_EXT_D(CHIPS)':
 'VSS'<298>: CDS_PINID='VSS(298)';
NODE_NAME     U7C1 Y63
 '@BASEBOARD_FAB2_LIB.BASEBOARD_FAB2(SCH_1):PAGE124_I17@MSTR_U_PROC.LBG_CORE_QAT_EXT_D(CHIPS)':
 'VSS'<299>: CDS_PINID='VSS(299)';
NODE_NAME     U7C1 Y59
 '@BASEBOARD_FAB2_LIB.BASEBOARD_FAB2(SCH_1):PAGE124_I17@MSTR_U_PROC.LBG_CORE_QAT_EXT_D(CHIPS)':
 'VSS'<300>: CDS_PINID='VSS(300)';
NODE_NAME     U7C1 Y52
 '@BASEBOARD_FAB2_LIB.BASEBOARD_FAB2(SCH_1):PAGE124_I17@MSTR_U_PROC.LBG_CORE_QAT_EXT_D(CHIPS)':
 'VSS'<301>: CDS_PINID='VSS(301)';
NODE_NAME     U7C1 Y5
 '@BASEBOARD_FAB2_LIB.BASEBOARD_FAB2(SCH_1):PAGE124_I17@MSTR_U_PROC.LBG_CORE_QAT_EXT_D(CHIPS)':
 'VSS'<302>: CDS_PINID='VSS(302)';
NODE_NAME     U7C1 Y48
 '@BASEBOARD_FAB2_LIB.BASEBOARD_FAB2(SCH_1):PAGE124_I17@MSTR_U_PROC.LBG_CORE_QAT_EXT_D(CHIPS)':
 'VSS'<303>: CDS_PINID='VSS(303)';
NODE_NAME     U7C1 Y27
 '@BASEBOARD_FAB2_LIB.BASEBOARD_FAB2(SCH_1):PAGE124_I17@MSTR_U_PROC.LBG_CORE_QAT_EXT_D(CHIPS)':
 'VSS'<304>: CDS_PINID='VSS(304)';
NODE_NAME     U7C1 Y22
 '@BASEBOARD_FAB2_LIB.BASEBOARD_FAB2(SCH_1):PAGE124_I17@MSTR_U_PROC.LBG_CORE_QAT_EXT_D(CHIPS)':
 'VSS'<305>: CDS_PINID='VSS(305)';
NODE_NAME     U7C1 W9
 '@BASEBOARD_FAB2_LIB.BASEBOARD_FAB2(SCH_1):PAGE124_I17@MSTR_U_PROC.LBG_CORE_QAT_EXT_D(CHIPS)':
 'VSS'<306>: CDS_PINID='VSS(306)';
NODE_NAME     U7C1 W61
 '@BASEBOARD_FAB2_LIB.BASEBOARD_FAB2(SCH_1):PAGE124_I17@MSTR_U_PROC.LBG_CORE_QAT_EXT_D(CHIPS)':
 'VSS'<307>: CDS_PINID='VSS(307)';
NODE_NAME     U7C1 Y43
 '@BASEBOARD_FAB2_LIB.BASEBOARD_FAB2(SCH_1):PAGE124_I17@MSTR_U_PROC.LBG_CORE_QAT_EXT_D(CHIPS)':
 'VSS'<308>: CDS_PINID='VSS(308)';
NODE_NAME     U7C1 AA50
 '@BASEBOARD_FAB2_LIB.BASEBOARD_FAB2(SCH_1):PAGE124_I17@MSTR_U_PROC.LBG_CORE_QAT_EXT_D(CHIPS)':
 'VSS'<309>: CDS_PINID='VSS(309)';
NODE_NAME     U7C1 W24
 '@BASEBOARD_FAB2_LIB.BASEBOARD_FAB2(SCH_1):PAGE124_I17@MSTR_U_PROC.LBG_CORE_QAT_EXT_D(CHIPS)':
 'VSS'<310>: CDS_PINID='VSS(310)';
NODE_NAME     U7C1 W20
 '@BASEBOARD_FAB2_LIB.BASEBOARD_FAB2(SCH_1):PAGE124_I17@MSTR_U_PROC.LBG_CORE_QAT_EXT_D(CHIPS)':
 'VSS'<311>: CDS_PINID='VSS(311)';
NODE_NAME     U7C1 W17
 '@BASEBOARD_FAB2_LIB.BASEBOARD_FAB2(SCH_1):PAGE124_I17@MSTR_U_PROC.LBG_CORE_QAT_EXT_D(CHIPS)':
 'VSS'<312>: CDS_PINID='VSS(312)';
NODE_NAME     U7C1 W13
 '@BASEBOARD_FAB2_LIB.BASEBOARD_FAB2(SCH_1):PAGE124_I17@MSTR_U_PROC.LBG_CORE_QAT_EXT_D(CHIPS)':
 'VSS'<313>: CDS_PINID='VSS(313)';
NODE_NAME     U7C1 V68
 '@BASEBOARD_FAB2_LIB.BASEBOARD_FAB2(SCH_1):PAGE124_I17@MSTR_U_PROC.LBG_CORE_QAT_EXT_D(CHIPS)':
 'VSS'<314>: CDS_PINID='VSS(314)';
NODE_NAME     U7C1 V66
 '@BASEBOARD_FAB2_LIB.BASEBOARD_FAB2(SCH_1):PAGE124_I17@MSTR_U_PROC.LBG_CORE_QAT_EXT_D(CHIPS)':
 'VSS'<315>: CDS_PINID='VSS(315)';
NODE_NAME     U7C1 W58
 '@BASEBOARD_FAB2_LIB.BASEBOARD_FAB2(SCH_1):PAGE124_I17@MSTR_U_PROC.LBG_CORE_QAT_EXT_D(CHIPS)':
 'VSS'<316>: CDS_PINID='VSS(316)';
NODE_NAME     U7C1 V52
 '@BASEBOARD_FAB2_LIB.BASEBOARD_FAB2(SCH_1):PAGE124_I17@MSTR_U_PROC.LBG_CORE_QAT_EXT_D(CHIPS)':
 'VSS'<317>: CDS_PINID='VSS(317)';
NODE_NAME     U7C1 V5
 '@BASEBOARD_FAB2_LIB.BASEBOARD_FAB2(SCH_1):PAGE124_I17@MSTR_U_PROC.LBG_CORE_QAT_EXT_D(CHIPS)':
 'VSS'<318>: CDS_PINID='VSS(318)';
NODE_NAME     U7C1 V48
 '@BASEBOARD_FAB2_LIB.BASEBOARD_FAB2(SCH_1):PAGE124_I17@MSTR_U_PROC.LBG_CORE_QAT_EXT_D(CHIPS)':
 'VSS'<319>: CDS_PINID='VSS(319)';
NODE_NAME     U7C1 V26
 '@BASEBOARD_FAB2_LIB.BASEBOARD_FAB2(SCH_1):PAGE124_I17@MSTR_U_PROC.LBG_CORE_QAT_EXT_D(CHIPS)':
 'VSS'<320>: CDS_PINID='VSS(320)';
NODE_NAME     U7C1 U58
 '@BASEBOARD_FAB2_LIB.BASEBOARD_FAB2(SCH_1):PAGE124_I17@MSTR_U_PROC.LBG_CORE_QAT_EXT_D(CHIPS)':
 'VSS'<321>: CDS_PINID='VSS(321)';
NODE_NAME     U7C1 AG46
 '@BASEBOARD_FAB2_LIB.BASEBOARD_FAB2(SCH_1):PAGE124_I17@MSTR_U_PROC.LBG_CORE_QAT_EXT_D(CHIPS)':
 'VSS'<322>: CDS_PINID='VSS(322)';
NODE_NAME     U7C1 AF50
 '@BASEBOARD_FAB2_LIB.BASEBOARD_FAB2(SCH_1):PAGE124_I17@MSTR_U_PROC.LBG_CORE_QAT_EXT_D(CHIPS)':
 'VSS'<323>: CDS_PINID='VSS(323)';
NODE_NAME     U7C1 T7
 '@BASEBOARD_FAB2_LIB.BASEBOARD_FAB2(SCH_1):PAGE124_I17@MSTR_U_PROC.LBG_CORE_QAT_EXT_D(CHIPS)':
 'VSS'<324>: CDS_PINID='VSS(324)';
NODE_NAME     U7C1 T66
 '@BASEBOARD_FAB2_LIB.BASEBOARD_FAB2(SCH_1):PAGE124_I17@MSTR_U_PROC.LBG_CORE_QAT_EXT_D(CHIPS)':
 'VSS'<325>: CDS_PINID='VSS(325)';
NODE_NAME     U7C1 T52
 '@BASEBOARD_FAB2_LIB.BASEBOARD_FAB2(SCH_1):PAGE124_I17@MSTR_U_PROC.LBG_CORE_QAT_EXT_D(CHIPS)':
 'VSS'<326>: CDS_PINID='VSS(326)';
NODE_NAME     U7C1 T48
 '@BASEBOARD_FAB2_LIB.BASEBOARD_FAB2(SCH_1):PAGE124_I17@MSTR_U_PROC.LBG_CORE_QAT_EXT_D(CHIPS)':
 'VSS'<327>: CDS_PINID='VSS(327)';
NODE_NAME     U7C1 AJ45
 '@BASEBOARD_FAB2_LIB.BASEBOARD_FAB2(SCH_1):PAGE124_I17@MSTR_U_PROC.LBG_CORE_QAT_EXT_D(CHIPS)':
 'VSS'<328>: CDS_PINID='VSS(328)';
NODE_NAME     U7C1 T40
 '@BASEBOARD_FAB2_LIB.BASEBOARD_FAB2(SCH_1):PAGE124_I17@MSTR_U_PROC.LBG_CORE_QAT_EXT_D(CHIPS)':
 'VSS'<329>: CDS_PINID='VSS(329)';
NODE_NAME     U7C1 T37
 '@BASEBOARD_FAB2_LIB.BASEBOARD_FAB2(SCH_1):PAGE124_I17@MSTR_U_PROC.LBG_CORE_QAT_EXT_D(CHIPS)':
 'VSS'<330>: CDS_PINID='VSS(330)';
NODE_NAME     U7C1 T33
 '@BASEBOARD_FAB2_LIB.BASEBOARD_FAB2(SCH_1):PAGE124_I17@MSTR_U_PROC.LBG_CORE_QAT_EXT_D(CHIPS)':
 'VSS'<331>: CDS_PINID='VSS(331)';
NODE_NAME     U7C1 T29
 '@BASEBOARD_FAB2_LIB.BASEBOARD_FAB2(SCH_1):PAGE124_I17@MSTR_U_PROC.LBG_CORE_QAT_EXT_D(CHIPS)':
 'VSS'<332>: CDS_PINID='VSS(332)';
NODE_NAME     U7C1 T26
 '@BASEBOARD_FAB2_LIB.BASEBOARD_FAB2(SCH_1):PAGE124_I17@MSTR_U_PROC.LBG_CORE_QAT_EXT_D(CHIPS)':
 'VSS'<333>: CDS_PINID='VSS(333)';
NODE_NAME     U7C1 T22
 '@BASEBOARD_FAB2_LIB.BASEBOARD_FAB2(SCH_1):PAGE124_I17@MSTR_U_PROC.LBG_CORE_QAT_EXT_D(CHIPS)':
 'VSS'<334>: CDS_PINID='VSS(334)';
NODE_NAME     U7C1 T18
 '@BASEBOARD_FAB2_LIB.BASEBOARD_FAB2(SCH_1):PAGE124_I17@MSTR_U_PROC.LBG_CORE_QAT_EXT_D(CHIPS)':
 'VSS'<335>: CDS_PINID='VSS(335)';
NODE_NAME     U7C1 T15
 '@BASEBOARD_FAB2_LIB.BASEBOARD_FAB2(SCH_1):PAGE124_I17@MSTR_U_PROC.LBG_CORE_QAT_EXT_D(CHIPS)':
 'VSS'<336>: CDS_PINID='VSS(336)';
NODE_NAME     U7C1 T11
 '@BASEBOARD_FAB2_LIB.BASEBOARD_FAB2(SCH_1):PAGE124_I17@MSTR_U_PROC.LBG_CORE_QAT_EXT_D(CHIPS)':
 'VSS'<337>: CDS_PINID='VSS(337)';
NODE_NAME     U7C1 R68
 '@BASEBOARD_FAB2_LIB.BASEBOARD_FAB2(SCH_1):PAGE124_I17@MSTR_U_PROC.LBG_CORE_QAT_EXT_D(CHIPS)':
 'VSS'<338>: CDS_PINID='VSS(338)';
NODE_NAME     U7C1 R58
 '@BASEBOARD_FAB2_LIB.BASEBOARD_FAB2(SCH_1):PAGE124_I17@MSTR_U_PROC.LBG_CORE_QAT_EXT_D(CHIPS)':
 'VSS'<339>: CDS_PINID='VSS(339)';
NODE_NAME     U7C1 T56
 '@BASEBOARD_FAB2_LIB.BASEBOARD_FAB2(SCH_1):PAGE124_I17@MSTR_U_PROC.LBG_CORE_QAT_EXT_D(CHIPS)':
 'VSS'<340>: CDS_PINID='VSS(340)';
NODE_NAME     U7C1 R54
 '@BASEBOARD_FAB2_LIB.BASEBOARD_FAB2(SCH_1):PAGE124_I17@MSTR_U_PROC.LBG_CORE_QAT_EXT_D(CHIPS)':
 'VSS'<341>: CDS_PINID='VSS(341)';
NODE_NAME     U7C1 R50
 '@BASEBOARD_FAB2_LIB.BASEBOARD_FAB2(SCH_1):PAGE124_I17@MSTR_U_PROC.LBG_CORE_QAT_EXT_D(CHIPS)':
 'VSS'<342>: CDS_PINID='VSS(342)';
NODE_NAME     U7C1 R5
 '@BASEBOARD_FAB2_LIB.BASEBOARD_FAB2(SCH_1):PAGE124_I17@MSTR_U_PROC.LBG_CORE_QAT_EXT_D(CHIPS)':
 'VSS'<343>: CDS_PINID='VSS(343)';
NODE_NAME     U7C1 U42
 '@BASEBOARD_FAB2_LIB.BASEBOARD_FAB2(SCH_1):PAGE124_I17@MSTR_U_PROC.LBG_CORE_QAT_EXT_D(CHIPS)':
 'VSS'<344>: CDS_PINID='VSS(344)';
NODE_NAME     U7C1 R27
 '@BASEBOARD_FAB2_LIB.BASEBOARD_FAB2(SCH_1):PAGE124_I17@MSTR_U_PROC.LBG_CORE_QAT_EXT_D(CHIPS)':
 'VSS'<345>: CDS_PINID='VSS(345)';
NODE_NAME     U7C1 P63
 '@BASEBOARD_FAB2_LIB.BASEBOARD_FAB2(SCH_1):PAGE124_I17@MSTR_U_PROC.LBG_CORE_QAT_EXT_D(CHIPS)':
 'VSS'<346>: CDS_PINID='VSS(346)';
NODE_NAME     U7C1 AE43
 '@BASEBOARD_FAB2_LIB.BASEBOARD_FAB2(SCH_1):PAGE124_I17@MSTR_U_PROC.LBG_CORE_QAT_EXT_D(CHIPS)':
 'VSS'<347>: CDS_PINID='VSS(347)';
NODE_NAME     U7C1 N9
 '@BASEBOARD_FAB2_LIB.BASEBOARD_FAB2(SCH_1):PAGE124_I17@MSTR_U_PROC.LBG_CORE_QAT_EXT_D(CHIPS)':
 'VSS'<348>: CDS_PINID='VSS(348)';
NODE_NAME     U7C1 N68
 '@BASEBOARD_FAB2_LIB.BASEBOARD_FAB2(SCH_1):PAGE124_I17@MSTR_U_PROC.LBG_CORE_QAT_EXT_D(CHIPS)':
 'VSS'<349>: CDS_PINID='VSS(349)';
NODE_NAME     U7C1 R38
 '@BASEBOARD_FAB2_LIB.BASEBOARD_FAB2(SCH_1):PAGE124_I17@MSTR_U_PROC.LBG_CORE_QAT_EXT_D(CHIPS)':
 'VSS'<350>: CDS_PINID='VSS(350)';
NODE_NAME     U7C1 N5
 '@BASEBOARD_FAB2_LIB.BASEBOARD_FAB2(SCH_1):PAGE124_I17@MSTR_U_PROC.LBG_CORE_QAT_EXT_D(CHIPS)':
 'VSS'<351>: CDS_PINID='VSS(351)';
NODE_NAME     U7C1 N46
 '@BASEBOARD_FAB2_LIB.BASEBOARD_FAB2(SCH_1):PAGE124_I17@MSTR_U_PROC.LBG_CORE_QAT_EXT_D(CHIPS)':
 'VSS'<352>: CDS_PINID='VSS(352)';
NODE_NAME     U7C1 N38
 '@BASEBOARD_FAB2_LIB.BASEBOARD_FAB2(SCH_1):PAGE124_I17@MSTR_U_PROC.LBG_CORE_QAT_EXT_D(CHIPS)':
 'VSS'<353>: CDS_PINID='VSS(353)';
NODE_NAME     U7C1 N35
 '@BASEBOARD_FAB2_LIB.BASEBOARD_FAB2(SCH_1):PAGE124_I17@MSTR_U_PROC.LBG_CORE_QAT_EXT_D(CHIPS)':
 'VSS'<354>: CDS_PINID='VSS(354)';
NODE_NAME     R2R11 2
 '@BASEBOARD_FAB2_LIB.BASEBOARD_FAB2(SCH_1):PAGE125_I11@MSTR_DISCRETE.RES(CHIPS)':
 'B': CDS_PINID='B';
NODE_NAME     R8E4 2
 '@BASEBOARD_FAB2_LIB.BASEBOARD_FAB2(SCH_1):PAGE125_I24@MSTR_DISCRETE.RES(CHIPS)':
 'B': CDS_PINID='B';
NODE_NAME     R8C17 2
 '@BASEBOARD_FAB2_LIB.BASEBOARD_FAB2(SCH_1):PAGE125_I41@MSTR_DISCRETE.RES(CHIPS)':
 'B': CDS_PINID='B';
NODE_NAME     R8D5 2
 '@BASEBOARD_FAB2_LIB.BASEBOARD_FAB2(SCH_1):PAGE125_I50@MSTR_DISCRETE.RES(CHIPS)':
 'B': CDS_PINID='B';
NODE_NAME     R7D19 2
 '@BASEBOARD_FAB2_LIB.BASEBOARD_FAB2(SCH_1):PAGE126_I6@MSTR_DISCRETE.RES(CHIPS)':
 'B': CDS_PINID='B';
NODE_NAME     Q8E2 2
 '@BASEBOARD_FAB2_LIB.BASEBOARD_FAB2(SCH_1):PAGE126_I13@MSTR_DISCRETE.FET_N(CHIPS)':
 'SRC': CDS_PINID='SRC';
NODE_NAME     R3P64 2
 '@BASEBOARD_FAB2_LIB.BASEBOARD_FAB2(SCH_1):PAGE126_I23@MSTR_DISCRETE.RES(CHIPS)':
 'B': CDS_PINID='B';
NODE_NAME     C3M21 2
 '@BASEBOARD_FAB2_LIB.BASEBOARD_FAB2(SCH_1):PAGE127_I9@DEV_DISCRETE.CAP_A(CHIPS)':
 'B': CDS_PINID='B';
NODE_NAME     C3M22 2
 '@BASEBOARD_FAB2_LIB.BASEBOARD_FAB2(SCH_1):PAGE127_I18@DEV_DISCRETE.CAP_A(CHIPS)':
 'B': CDS_PINID='B';
NODE_NAME     C3M30 2
 '@BASEBOARD_FAB2_LIB.BASEBOARD_FAB2(SCH_1):PAGE127_I27@DEV_DISCRETE.CAP_A(CHIPS)':
 'B': CDS_PINID='B';
NODE_NAME     C2M5 2
 '@BASEBOARD_FAB2_LIB.BASEBOARD_FAB2(SCH_1):PAGE127_I43@MSTR_DISCRETE.CAP(CHIPS)':
 'B': CDS_PINID='B';
NODE_NAME     C2M7 2
 '@BASEBOARD_FAB2_LIB.BASEBOARD_FAB2(SCH_1):PAGE127_I44@DEV_DISCRETE.CAP_A(CHIPS)':
 'B': CDS_PINID='B';
NODE_NAME     C2M10 2
 '@BASEBOARD_FAB2_LIB.BASEBOARD_FAB2(SCH_1):PAGE127_I49@MSTR_DISCRETE.CAP(CHIPS)':
 'B': CDS_PINID='B';
NODE_NAME     C2M9 2
 '@BASEBOARD_FAB2_LIB.BASEBOARD_FAB2(SCH_1):PAGE127_I50@DEV_DISCRETE.CAP_A(CHIPS)':
 'B': CDS_PINID='B';
NODE_NAME     C3M31 2
 '@BASEBOARD_FAB2_LIB.BASEBOARD_FAB2(SCH_1):PAGE127_I57@DEV_DISCRETE.CAP_A(CHIPS)':
 'B': CDS_PINID='B';
NODE_NAME     C2N6 2
 '@BASEBOARD_FAB2_LIB.BASEBOARD_FAB2(SCH_1):PAGE127_I64@MSTR_DISCRETE.CAP(CHIPS)':
 'B': CDS_PINID='B';
NODE_NAME     C2N5 2
 '@BASEBOARD_FAB2_LIB.BASEBOARD_FAB2(SCH_1):PAGE127_I65@DEV_DISCRETE.CAP_A(CHIPS)':
 'B': CDS_PINID='B';
NODE_NAME     C2M8 2
 '@BASEBOARD_FAB2_LIB.BASEBOARD_FAB2(SCH_1):PAGE127_I74@DEV_DISCRETE.CAP_A(CHIPS)':
 'B': CDS_PINID='B';
NODE_NAME     C2M6 2
 '@BASEBOARD_FAB2_LIB.BASEBOARD_FAB2(SCH_1):PAGE127_I76@DEV_DISCRETE.CAP_A(CHIPS)':
 'B': CDS_PINID='B';
NODE_NAME     C2M25 2
 '@BASEBOARD_FAB2_LIB.BASEBOARD_FAB2(SCH_1):PAGE127_I78@DEV_DISCRETE.CAP_A(CHIPS)':
 'B': CDS_PINID='B';
NODE_NAME     C3M29 2
 '@BASEBOARD_FAB2_LIB.BASEBOARD_FAB2(SCH_1):PAGE127_I80@DEV_DISCRETE.CAP_A(CHIPS)':
 'B': CDS_PINID='B';
NODE_NAME     C3M24 2
 '@BASEBOARD_FAB2_LIB.BASEBOARD_FAB2(SCH_1):PAGE127_I81@MSTR_DISCRETE.CAP(CHIPS)':
 'B': CDS_PINID='B';
NODE_NAME     C3M23 2
 '@BASEBOARD_FAB2_LIB.BASEBOARD_FAB2(SCH_1):PAGE127_I82@MSTR_DISCRETE.CAP(CHIPS)':
 'B': CDS_PINID='B';
NODE_NAME     C3M27 2
 '@BASEBOARD_FAB2_LIB.BASEBOARD_FAB2(SCH_1):PAGE127_I83@DEV_DISCRETE.CAP_A(CHIPS)':
 'B': CDS_PINID='B';
NODE_NAME     C3M20 2
 '@BASEBOARD_FAB2_LIB.BASEBOARD_FAB2(SCH_1):PAGE127_I84@DEV_DISCRETE.CAP_A(CHIPS)':
 'B': CDS_PINID='B';
NODE_NAME     C3M18 2
 '@BASEBOARD_FAB2_LIB.BASEBOARD_FAB2(SCH_1):PAGE127_I85@MSTR_DISCRETE.CAP(CHIPS)':
 'B': CDS_PINID='B';
NODE_NAME     C3M17 2
 '@BASEBOARD_FAB2_LIB.BASEBOARD_FAB2(SCH_1):PAGE127_I86@MSTR_DISCRETE.CAP(CHIPS)':
 'B': CDS_PINID='B';
NODE_NAME     C3M19 2
 '@BASEBOARD_FAB2_LIB.BASEBOARD_FAB2(SCH_1):PAGE127_I87@DEV_DISCRETE.CAP_A(CHIPS)':
 'B': CDS_PINID='B';
NODE_NAME     C7D2 2
 '@BASEBOARD_FAB2_LIB.BASEBOARD_FAB2(SCH_1):PAGE130_I2@MSTR_DISCRETE.CAP(CHIPS)':
 'B': CDS_PINID='B';
NODE_NAME     C2N26 2
 '@BASEBOARD_FAB2_LIB.BASEBOARD_FAB2(SCH_1):PAGE130_I4@DEV_DISCRETE.CAP_A(CHIPS)':
 'B': CDS_PINID='B';
NODE_NAME     C2N19 2
 '@BASEBOARD_FAB2_LIB.BASEBOARD_FAB2(SCH_1):PAGE130_I7@DEV_DISCRETE.CAP_A(CHIPS)':
 'B': CDS_PINID='B';
NODE_NAME     C2N24 2
 '@BASEBOARD_FAB2_LIB.BASEBOARD_FAB2(SCH_1):PAGE130_I8@MSTR_DISCRETE.CAP(CHIPS)':
 'B': CDS_PINID='B';
NODE_NAME     C2N22 2
 '@BASEBOARD_FAB2_LIB.BASEBOARD_FAB2(SCH_1):PAGE130_I9@MSTR_DISCRETE.CAP(CHIPS)':
 'B': CDS_PINID='B';
NODE_NAME     C2N20 2
 '@BASEBOARD_FAB2_LIB.BASEBOARD_FAB2(SCH_1):PAGE130_I12@DEV_DISCRETE.CAP_A(CHIPS)':
 'B': CDS_PINID='B';
NODE_NAME     C2N21 2
 '@BASEBOARD_FAB2_LIB.BASEBOARD_FAB2(SCH_1):PAGE130_I15@MSTR_DISCRETE.CAP(CHIPS)':
 'B': CDS_PINID='B';
NODE_NAME     C3N29 2
 '@BASEBOARD_FAB2_LIB.BASEBOARD_FAB2(SCH_1):PAGE130_I16@DEV_DISCRETE.CAP_A(CHIPS)':
 'B': CDS_PINID='B';
NODE_NAME     C8C3 2
 '@BASEBOARD_FAB2_LIB.BASEBOARD_FAB2(SCH_1):PAGE130_I19@MSTR_DISCRETE.CAP(CHIPS)':
 'B': CDS_PINID='B';
NODE_NAME     C8C4 2
 '@BASEBOARD_FAB2_LIB.BASEBOARD_FAB2(SCH_1):PAGE130_I20@MSTR_DISCRETE.CAP(CHIPS)':
 'B': CDS_PINID='B';
NODE_NAME     C8C5 2
 '@BASEBOARD_FAB2_LIB.BASEBOARD_FAB2(SCH_1):PAGE130_I21@MSTR_DISCRETE.CAP(CHIPS)':
 'B': CDS_PINID='B';
NODE_NAME     C8C6 2
 '@BASEBOARD_FAB2_LIB.BASEBOARD_FAB2(SCH_1):PAGE130_I22@MSTR_DISCRETE.CAP(CHIPS)':
 'B': CDS_PINID='B';
NODE_NAME     C2N23 2
 '@BASEBOARD_FAB2_LIB.BASEBOARD_FAB2(SCH_1):PAGE130_I24@MSTR_DISCRETE.CAP(CHIPS)':
 'B': CDS_PINID='B';
NODE_NAME     C2N14 2
 '@BASEBOARD_FAB2_LIB.BASEBOARD_FAB2(SCH_1):PAGE130_I25@MSTR_DISCRETE.CAP(CHIPS)':
 'B': CDS_PINID='B';
NODE_NAME     C2N17 2
 '@BASEBOARD_FAB2_LIB.BASEBOARD_FAB2(SCH_1):PAGE130_I28@MSTR_DISCRETE.CAP(CHIPS)':
 'B': CDS_PINID='B';
NODE_NAME     C2N18 2
 '@BASEBOARD_FAB2_LIB.BASEBOARD_FAB2(SCH_1):PAGE130_I29@DEV_DISCRETE.CAP_A(CHIPS)':
 'B': CDS_PINID='B';
NODE_NAME     C8B2 2
 '@BASEBOARD_FAB2_LIB.BASEBOARD_FAB2(SCH_1):PAGE130_I30@DEV_DISCRETE.CAP_A(CHIPS)':
 'B': CDS_PINID='B';
NODE_NAME     C8B3 2
 '@BASEBOARD_FAB2_LIB.BASEBOARD_FAB2(SCH_1):PAGE130_I32@DEV_DISCRETE.CAP_A(CHIPS)':
 'B': CDS_PINID='B';
NODE_NAME     C2N25 2
 '@BASEBOARD_FAB2_LIB.BASEBOARD_FAB2(SCH_1):PAGE130_I34@DEV_DISCRETE.CAP_A(CHIPS)':
 'B': CDS_PINID='B';
NODE_NAME     C2M16 2
 '@BASEBOARD_FAB2_LIB.BASEBOARD_FAB2(SCH_1):PAGE130_I37@DEV_DISCRETE.CAP_A(CHIPS)':
 'B': CDS_PINID='B';
NODE_NAME     C7D3 2
 '@BASEBOARD_FAB2_LIB.BASEBOARD_FAB2(SCH_1):PAGE130_I38@DEV_DISCRETE.CAP_A(CHIPS)':
 'B': CDS_PINID='B';
NODE_NAME     C8B4 2
 '@BASEBOARD_FAB2_LIB.BASEBOARD_FAB2(SCH_1):PAGE130_I39@DEV_DISCRETE.CAP_A(CHIPS)':
 'B': CDS_PINID='B';
NODE_NAME     C8B1 2
 '@BASEBOARD_FAB2_LIB.BASEBOARD_FAB2(SCH_1):PAGE130_I41@DEV_DISCRETE.CAP_A(CHIPS)':
 'B': CDS_PINID='B';
NODE_NAME     C3N23 2
 '@BASEBOARD_FAB2_LIB.BASEBOARD_FAB2(SCH_1):PAGE130_I42@DEV_DISCRETE.CAP_A(CHIPS)':
 'B': CDS_PINID='B';
NODE_NAME     C2M1 2
 '@BASEBOARD_FAB2_LIB.BASEBOARD_FAB2(SCH_1):PAGE130_I43@DEV_DISCRETE.CAP_A(CHIPS)':
 'B': CDS_PINID='B';
NODE_NAME     C2M2 2
 '@BASEBOARD_FAB2_LIB.BASEBOARD_FAB2(SCH_1):PAGE130_I45@DEV_DISCRETE.CAP_A(CHIPS)':
 'B': CDS_PINID='B';
NODE_NAME     C2N15 2
 '@BASEBOARD_FAB2_LIB.BASEBOARD_FAB2(SCH_1):PAGE130_I47@DEV_DISCRETE.CAP_A(CHIPS)':
 'B': CDS_PINID='B';
NODE_NAME     C3N21 2
 '@BASEBOARD_FAB2_LIB.BASEBOARD_FAB2(SCH_1):PAGE130_I49@DEV_DISCRETE.CAP_A(CHIPS)':
 'B': CDS_PINID='B';
NODE_NAME     C3N25 2
 '@BASEBOARD_FAB2_LIB.BASEBOARD_FAB2(SCH_1):PAGE130_I50@DEV_DISCRETE.CAP_A(CHIPS)':
 'B': CDS_PINID='B';
NODE_NAME     C2N16 2
 '@BASEBOARD_FAB2_LIB.BASEBOARD_FAB2(SCH_1):PAGE130_I52@DEV_DISCRETE.CAP_A(CHIPS)':
 'B': CDS_PINID='B';
NODE_NAME     C3N22 2
 '@BASEBOARD_FAB2_LIB.BASEBOARD_FAB2(SCH_1):PAGE130_I53@DEV_DISCRETE.CAP_A(CHIPS)':
 'B': CDS_PINID='B';
NODE_NAME     C7B15 2
 '@BASEBOARD_FAB2_LIB.BASEBOARD_FAB2(SCH_1):PAGE131_I1@DEV_DISCRETE.CAP_A(CHIPS)':
 'B': CDS_PINID='B';
NODE_NAME     C7B19 2
 '@BASEBOARD_FAB2_LIB.BASEBOARD_FAB2(SCH_1):PAGE131_I2@DEV_DISCRETE.CAP_A(CHIPS)':
 'B': CDS_PINID='B';
NODE_NAME     C7B16 2
 '@BASEBOARD_FAB2_LIB.BASEBOARD_FAB2(SCH_1):PAGE131_I3@DEV_DISCRETE.CAP_A(CHIPS)':
 'B': CDS_PINID='B';
NODE_NAME     C7B21 2
 '@BASEBOARD_FAB2_LIB.BASEBOARD_FAB2(SCH_1):PAGE131_I4@DEV_DISCRETE.CAP_A(CHIPS)':
 'B': CDS_PINID='B';
NODE_NAME     C7B20 2
 '@BASEBOARD_FAB2_LIB.BASEBOARD_FAB2(SCH_1):PAGE131_I6@DEV_DISCRETE.CAP_A(CHIPS)':
 'B': CDS_PINID='B';
NODE_NAME     C7B23 2
 '@BASEBOARD_FAB2_LIB.BASEBOARD_FAB2(SCH_1):PAGE131_I7@DEV_DISCRETE.CAP_A(CHIPS)':
 'B': CDS_PINID='B';
NODE_NAME     C8B10 2
 '@BASEBOARD_FAB2_LIB.BASEBOARD_FAB2(SCH_1):PAGE131_I8@DEV_DISCRETE.CAP_A(CHIPS)':
 'B': CDS_PINID='B';
NODE_NAME     C7B22 2
 '@BASEBOARD_FAB2_LIB.BASEBOARD_FAB2(SCH_1):PAGE131_I10@DEV_DISCRETE.CAP_A(CHIPS)':
 'B': CDS_PINID='B';
NODE_NAME     C7B24 2
 '@BASEBOARD_FAB2_LIB.BASEBOARD_FAB2(SCH_1):PAGE131_I11@DEV_DISCRETE.CAP_A(CHIPS)':
 'B': CDS_PINID='B';
NODE_NAME     C7B18 2
 '@BASEBOARD_FAB2_LIB.BASEBOARD_FAB2(SCH_1):PAGE131_I12@DEV_DISCRETE.CAP_A(CHIPS)':
 'B': CDS_PINID='B';
NODE_NAME     C8B9 2
 '@BASEBOARD_FAB2_LIB.BASEBOARD_FAB2(SCH_1):PAGE131_I14@DEV_DISCRETE.CAP_A(CHIPS)':
 'B': CDS_PINID='B';
NODE_NAME     C8B11 2
 '@BASEBOARD_FAB2_LIB.BASEBOARD_FAB2(SCH_1):PAGE131_I15@DEV_DISCRETE.CAP_A(CHIPS)':
 'B': CDS_PINID='B';
NODE_NAME     C8B14 2
 '@BASEBOARD_FAB2_LIB.BASEBOARD_FAB2(SCH_1):PAGE131_I16@DEV_DISCRETE.CAP_A(CHIPS)':
 'B': CDS_PINID='B';
NODE_NAME     C7B17 2
 '@BASEBOARD_FAB2_LIB.BASEBOARD_FAB2(SCH_1):PAGE131_I18@DEV_DISCRETE.CAP_A(CHIPS)':
 'B': CDS_PINID='B';
NODE_NAME     C8B13 2
 '@BASEBOARD_FAB2_LIB.BASEBOARD_FAB2(SCH_1):PAGE131_I20@DEV_DISCRETE.CAP_A(CHIPS)':
 'B': CDS_PINID='B';
NODE_NAME     C8B16 2
 '@BASEBOARD_FAB2_LIB.BASEBOARD_FAB2(SCH_1):PAGE131_I22@MSTR_DISCRETE.CAP(CHIPS)':
 'B': CDS_PINID='B';
NODE_NAME     C8B15 2
 '@BASEBOARD_FAB2_LIB.BASEBOARD_FAB2(SCH_1):PAGE131_I24@MSTR_DISCRETE.CAP(CHIPS)':
 'B': CDS_PINID='B';
NODE_NAME     C2M22 2
 '@BASEBOARD_FAB2_LIB.BASEBOARD_FAB2(SCH_1):PAGE131_I27@DEV_DISCRETE.CAP_A(CHIPS)':
 'B': CDS_PINID='B';
NODE_NAME     C2M21 2
 '@BASEBOARD_FAB2_LIB.BASEBOARD_FAB2(SCH_1):PAGE131_I28@DEV_DISCRETE.CAP_A(CHIPS)':
 'B': CDS_PINID='B';
NODE_NAME     C2M18 2
 '@BASEBOARD_FAB2_LIB.BASEBOARD_FAB2(SCH_1):PAGE131_I29@DEV_DISCRETE.CAP_A(CHIPS)':
 'B': CDS_PINID='B';
NODE_NAME     C2M19 2
 '@BASEBOARD_FAB2_LIB.BASEBOARD_FAB2(SCH_1):PAGE131_I31@DEV_DISCRETE.CAP_A(CHIPS)':
 'B': CDS_PINID='B';
NODE_NAME     C3M38 2
 '@BASEBOARD_FAB2_LIB.BASEBOARD_FAB2(SCH_1):PAGE131_I32@DEV_DISCRETE.CAP_A(CHIPS)':
 'B': CDS_PINID='B';
NODE_NAME     C2M17 2
 '@BASEBOARD_FAB2_LIB.BASEBOARD_FAB2(SCH_1):PAGE131_I34@MSTR_DISCRETE.CAP(CHIPS)':
 'B': CDS_PINID='B';
NODE_NAME     C2M11 2
 '@BASEBOARD_FAB2_LIB.BASEBOARD_FAB2(SCH_1):PAGE131_I35@MSTR_DISCRETE.CAP(CHIPS)':
 'B': CDS_PINID='B';
NODE_NAME     C8A13 2
 '@BASEBOARD_FAB2_LIB.BASEBOARD_FAB2(SCH_1):PAGE131_I37@MSTR_DISCRETE.CAP(CHIPS)':
 'B': CDS_PINID='B';
NODE_NAME     C2M20 2
 '@BASEBOARD_FAB2_LIB.BASEBOARD_FAB2(SCH_1):PAGE131_I39@DEV_DISCRETE.CAP_A(CHIPS)':
 'B': CDS_PINID='B';
NODE_NAME     C2N13 2
 '@BASEBOARD_FAB2_LIB.BASEBOARD_FAB2(SCH_1):PAGE131_I40@DEV_DISCRETE.CAP_A(CHIPS)':
 'B': CDS_PINID='B';
NODE_NAME     C2N2 2
 '@BASEBOARD_FAB2_LIB.BASEBOARD_FAB2(SCH_1):PAGE131_I41@DEV_DISCRETE.CAP_A(CHIPS)':
 'B': CDS_PINID='B';
NODE_NAME     C3M43 2
 '@BASEBOARD_FAB2_LIB.BASEBOARD_FAB2(SCH_1):PAGE131_I42@DEV_DISCRETE.CAP_A(CHIPS)':
 'B': CDS_PINID='B';
NODE_NAME     C2N7 2
 '@BASEBOARD_FAB2_LIB.BASEBOARD_FAB2(SCH_1):PAGE131_I43@DEV_DISCRETE.CAP_A(CHIPS)':
 'B': CDS_PINID='B';
NODE_NAME     C3M39 2
 '@BASEBOARD_FAB2_LIB.BASEBOARD_FAB2(SCH_1):PAGE131_I44@DEV_DISCRETE.CAP_A(CHIPS)':
 'B': CDS_PINID='B';
NODE_NAME     C3M42 2
 '@BASEBOARD_FAB2_LIB.BASEBOARD_FAB2(SCH_1):PAGE131_I45@DEV_DISCRETE.CAP_A(CHIPS)':
 'B': CDS_PINID='B';
NODE_NAME     C2N8 2
 '@BASEBOARD_FAB2_LIB.BASEBOARD_FAB2(SCH_1):PAGE131_I47@DEV_DISCRETE.CAP_A(CHIPS)':
 'B': CDS_PINID='B';
NODE_NAME     C2M13 2
 '@BASEBOARD_FAB2_LIB.BASEBOARD_FAB2(SCH_1):PAGE131_I48@DEV_DISCRETE.CAP_A(CHIPS)':
 'B': CDS_PINID='B';
NODE_NAME     C2N10 2
 '@BASEBOARD_FAB2_LIB.BASEBOARD_FAB2(SCH_1):PAGE131_I50@DEV_DISCRETE.CAP_A(CHIPS)':
 'B': CDS_PINID='B';
NODE_NAME     C2M12 2
 '@BASEBOARD_FAB2_LIB.BASEBOARD_FAB2(SCH_1):PAGE131_I52@DEV_DISCRETE.CAP_A(CHIPS)':
 'B': CDS_PINID='B';
NODE_NAME     C3L25 2
 '@BASEBOARD_FAB2_LIB.BASEBOARD_FAB2(SCH_1):PAGE132_I1@DEV_DISCRETE.CAP_A(CHIPS)':
 'B': CDS_PINID='B';
NODE_NAME     C3M7 2
 '@BASEBOARD_FAB2_LIB.BASEBOARD_FAB2(SCH_1):PAGE132_I2@DEV_DISCRETE.CAP_A(CHIPS)':
 'B': CDS_PINID='B';
NODE_NAME     C3L26 2
 '@BASEBOARD_FAB2_LIB.BASEBOARD_FAB2(SCH_1):PAGE132_I3@DEV_DISCRETE.CAP_A(CHIPS)':
 'B': CDS_PINID='B';
NODE_NAME     C3L27 2
 '@BASEBOARD_FAB2_LIB.BASEBOARD_FAB2(SCH_1):PAGE132_I4@DEV_DISCRETE.CAP_A(CHIPS)':
 'B': CDS_PINID='B';
NODE_NAME     C3M6 2
 '@BASEBOARD_FAB2_LIB.BASEBOARD_FAB2(SCH_1):PAGE132_I6@DEV_DISCRETE.CAP_A(CHIPS)':
 'B': CDS_PINID='B';
NODE_NAME     C7C9 2
 '@BASEBOARD_FAB2_LIB.BASEBOARD_FAB2(SCH_1):PAGE132_I7@DEV_DISCRETE.CAP_A(CHIPS)':
 'B': CDS_PINID='B';
NODE_NAME     C3N27 2
 '@BASEBOARD_FAB2_LIB.BASEBOARD_FAB2(SCH_1):PAGE132_I8@DEV_DISCRETE.CAP_A(CHIPS)':
 'B': CDS_PINID='B';
NODE_NAME     C3N30 2
 '@BASEBOARD_FAB2_LIB.BASEBOARD_FAB2(SCH_1):PAGE132_I9@DEV_DISCRETE.CAP_A(CHIPS)':
 'B': CDS_PINID='B';
NODE_NAME     C7A36 2
 '@BASEBOARD_FAB2_LIB.BASEBOARD_FAB2(SCH_1):PAGE132_I11@DEV_DISCRETE.CAP_A(CHIPS)':
 'B': CDS_PINID='B';
NODE_NAME     C3N12 2
 '@BASEBOARD_FAB2_LIB.BASEBOARD_FAB2(SCH_1):PAGE132_I12@DEV_DISCRETE.CAP_A(CHIPS)':
 'B': CDS_PINID='B';
NODE_NAME     C3N10 2
 '@BASEBOARD_FAB2_LIB.BASEBOARD_FAB2(SCH_1):PAGE132_I13@DEV_DISCRETE.CAP_A(CHIPS)':
 'B': CDS_PINID='B';
NODE_NAME     C3N24 2
 '@BASEBOARD_FAB2_LIB.BASEBOARD_FAB2(SCH_1):PAGE132_I16@DEV_DISCRETE.CAP_A(CHIPS)':
 'B': CDS_PINID='B';
NODE_NAME     C3N28 2
 '@BASEBOARD_FAB2_LIB.BASEBOARD_FAB2(SCH_1):PAGE132_I17@DEV_DISCRETE.CAP_A(CHIPS)':
 'B': CDS_PINID='B';
NODE_NAME     C3N11 2
 '@BASEBOARD_FAB2_LIB.BASEBOARD_FAB2(SCH_1):PAGE132_I19@DEV_DISCRETE.CAP_A(CHIPS)':
 'B': CDS_PINID='B';
NODE_NAME     C3N31 2
 '@BASEBOARD_FAB2_LIB.BASEBOARD_FAB2(SCH_1):PAGE132_I20@DEV_DISCRETE.CAP_A(CHIPS)':
 'B': CDS_PINID='B';
NODE_NAME     C7A33 2
 '@BASEBOARD_FAB2_LIB.BASEBOARD_FAB2(SCH_1):PAGE132_I23@MSTR_DISCRETE.CAP(CHIPS)':
 'B': CDS_PINID='B';
NODE_NAME     C7B4 2
 '@BASEBOARD_FAB2_LIB.BASEBOARD_FAB2(SCH_1):PAGE132_I24@MSTR_DISCRETE.CAP(CHIPS)':
 'B': CDS_PINID='B';
NODE_NAME     C2N9 2
 '@BASEBOARD_FAB2_LIB.BASEBOARD_FAB2(SCH_1):PAGE132_I26@DEV_DISCRETE.CAP_A(CHIPS)':
 'B': CDS_PINID='B';
NODE_NAME     C2N3 2
 '@BASEBOARD_FAB2_LIB.BASEBOARD_FAB2(SCH_1):PAGE132_I27@DEV_DISCRETE.CAP_A(CHIPS)':
 'B': CDS_PINID='B';
NODE_NAME     C2N4 2
 '@BASEBOARD_FAB2_LIB.BASEBOARD_FAB2(SCH_1):PAGE132_I28@DEV_DISCRETE.CAP_A(CHIPS)':
 'B': CDS_PINID='B';
NODE_NAME     C2N12 2
 '@BASEBOARD_FAB2_LIB.BASEBOARD_FAB2(SCH_1):PAGE132_I29@DEV_DISCRETE.CAP_A(CHIPS)':
 'B': CDS_PINID='B';
NODE_NAME     C2N11 2
 '@BASEBOARD_FAB2_LIB.BASEBOARD_FAB2(SCH_1):PAGE132_I30@DEV_DISCRETE.CAP_A(CHIPS)':
 'B': CDS_PINID='B';
NODE_NAME     C3N19 2
 '@BASEBOARD_FAB2_LIB.BASEBOARD_FAB2(SCH_1):PAGE132_I31@DEV_DISCRETE.CAP_A(CHIPS)':
 'B': CDS_PINID='B';
NODE_NAME     C3N3 2
 '@BASEBOARD_FAB2_LIB.BASEBOARD_FAB2(SCH_1):PAGE132_I32@DEV_DISCRETE.CAP_A(CHIPS)':
 'B': CDS_PINID='B';
NODE_NAME     C3N1 2
 '@BASEBOARD_FAB2_LIB.BASEBOARD_FAB2(SCH_1):PAGE132_I34@DEV_DISCRETE.CAP_A(CHIPS)':
 'B': CDS_PINID='B';
NODE_NAME     C3N7 2
 '@BASEBOARD_FAB2_LIB.BASEBOARD_FAB2(SCH_1):PAGE132_I35@DEV_DISCRETE.CAP_A(CHIPS)':
 'B': CDS_PINID='B';
NODE_NAME     C3N16 2
 '@BASEBOARD_FAB2_LIB.BASEBOARD_FAB2(SCH_1):PAGE132_I36@DEV_DISCRETE.CAP_A(CHIPS)':
 'B': CDS_PINID='B';
NODE_NAME     C7A32 2
 '@BASEBOARD_FAB2_LIB.BASEBOARD_FAB2(SCH_1):PAGE132_I38@MSTR_DISCRETE.CAP(CHIPS)':
 'B': CDS_PINID='B';
NODE_NAME     C7A31 2
 '@BASEBOARD_FAB2_LIB.BASEBOARD_FAB2(SCH_1):PAGE132_I40@MSTR_DISCRETE.CAP(CHIPS)':
 'B': CDS_PINID='B';
NODE_NAME     C3N18 2
 '@BASEBOARD_FAB2_LIB.BASEBOARD_FAB2(SCH_1):PAGE132_I42@DEV_DISCRETE.CAP_A(CHIPS)':
 'B': CDS_PINID='B';
NODE_NAME     C3N2 2
 '@BASEBOARD_FAB2_LIB.BASEBOARD_FAB2(SCH_1):PAGE132_I43@DEV_DISCRETE.CAP_A(CHIPS)':
 'B': CDS_PINID='B';
NODE_NAME     C3N6 2
 '@BASEBOARD_FAB2_LIB.BASEBOARD_FAB2(SCH_1):PAGE132_I44@DEV_DISCRETE.CAP_A(CHIPS)':
 'B': CDS_PINID='B';
NODE_NAME     C3N17 2
 '@BASEBOARD_FAB2_LIB.BASEBOARD_FAB2(SCH_1):PAGE132_I45@DEV_DISCRETE.CAP_A(CHIPS)':
 'B': CDS_PINID='B';
NODE_NAME     C3N4 2
 '@BASEBOARD_FAB2_LIB.BASEBOARD_FAB2(SCH_1):PAGE132_I46@DEV_DISCRETE.CAP_A(CHIPS)':
 'B': CDS_PINID='B';
NODE_NAME     C3N5 2
 '@BASEBOARD_FAB2_LIB.BASEBOARD_FAB2(SCH_1):PAGE132_I48@DEV_DISCRETE.CAP_A(CHIPS)':
 'B': CDS_PINID='B';
NODE_NAME     C3N15 2
 '@BASEBOARD_FAB2_LIB.BASEBOARD_FAB2(SCH_1):PAGE132_I49@DEV_DISCRETE.CAP_A(CHIPS)':
 'B': CDS_PINID='B';
NODE_NAME     C3N20 2
 '@BASEBOARD_FAB2_LIB.BASEBOARD_FAB2(SCH_1):PAGE132_I51@DEV_DISCRETE.CAP_A(CHIPS)':
 'B': CDS_PINID='B';
NODE_NAME     C3L23 2
 '@BASEBOARD_FAB2_LIB.BASEBOARD_FAB2(SCH_1):PAGE132_I52@DEV_DISCRETE.CAP_A(CHIPS)':
 'B': CDS_PINID='B';
NODE_NAME     C3L22 2
 '@BASEBOARD_FAB2_LIB.BASEBOARD_FAB2(SCH_1):PAGE132_I54@DEV_DISCRETE.CAP_A(CHIPS)':
 'B': CDS_PINID='B';
NODE_NAME     C3L24 2
 '@BASEBOARD_FAB2_LIB.BASEBOARD_FAB2(SCH_1):PAGE132_I56@DEV_DISCRETE.CAP_A(CHIPS)':
 'B': CDS_PINID='B';
NODE_NAME     R3N3 1
 '@BASEBOARD_FAB2_LIB.BASEBOARD_FAB2(SCH_1):PAGE133_I120@MSTR_DISCRETE.RES(CHIPS)':
 'A': CDS_PINID='A';
NODE_NAME     R2N12 1
 '@BASEBOARD_FAB2_LIB.BASEBOARD_FAB2(SCH_1):PAGE133_I122@MSTR_DISCRETE.RES(CHIPS)':
 'A': CDS_PINID='A';
NODE_NAME     R2N24 2
 '@BASEBOARD_FAB2_LIB.BASEBOARD_FAB2(SCH_1):PAGE135_I113@MSTR_DISCRETE.RES(CHIPS)':
 'B': CDS_PINID='B';
NODE_NAME     J8G2 5
 '@BASEBOARD_FAB2_LIB.BASEBOARD_FAB2(SCH_1):PAGE135_I124@MSTR_CONN.CONN12_C73564003(CHIPS)':
 'IO5': CDS_PINID='IO5';
NODE_NAME     J8G2 6
 '@BASEBOARD_FAB2_LIB.BASEBOARD_FAB2(SCH_1):PAGE135_I124@MSTR_CONN.CONN12_C73564003(CHIPS)':
 'IO6': CDS_PINID='IO6';
NODE_NAME     J8G2 11
 '@BASEBOARD_FAB2_LIB.BASEBOARD_FAB2(SCH_1):PAGE135_I124@MSTR_CONN.CONN12_C73564003(CHIPS)':
 'IO11': CDS_PINID='IO11';
NODE_NAME     J8G2 12
 '@BASEBOARD_FAB2_LIB.BASEBOARD_FAB2(SCH_1):PAGE135_I124@MSTR_CONN.CONN12_C73564003(CHIPS)':
 'IO12': CDS_PINID='IO12';
NODE_NAME     J9A1 1
 '@BASEBOARD_FAB2_LIB.BASEBOARD_FAB2(SCH_1):PAGE135_I131@MSTR_CONN.CONN4_D42317002(CHIPS)':
 'IO1': CDS_PINID='IO1';
NODE_NAME     J9A1 3
 '@BASEBOARD_FAB2_LIB.BASEBOARD_FAB2(SCH_1):PAGE135_I131@MSTR_CONN.CONN4_D42317002(CHIPS)':
 'IO3': CDS_PINID='IO3';
NODE_NAME     R7G28 2
 '@BASEBOARD_FAB2_LIB.BASEBOARD_FAB2(SCH_1):PAGE136_I102@MSTR_DISCRETE.RES(CHIPS)':
 'B': CDS_PINID='B';
NODE_NAME     C8E8 2
 '@BASEBOARD_FAB2_LIB.BASEBOARD_FAB2(SCH_1):PAGE136_I128@DEV_DISCRETE.CAP_A(CHIPS)':
 'B': CDS_PINID='B';
NODE_NAME     Q8E1 2
 '@BASEBOARD_FAB2_LIB.BASEBOARD_FAB2(SCH_1):PAGE136_I134@MSTR_DISCRETE.FET_N(CHIPS)':
 'SRC': CDS_PINID='SRC';
NODE_NAME     R8E16 2
 '@BASEBOARD_FAB2_LIB.BASEBOARD_FAB2(SCH_1):PAGE136_I140@MSTR_DISCRETE.RES(CHIPS)':
 'B': CDS_PINID='B';
NODE_NAME     R7G29 2
 '@BASEBOARD_FAB2_LIB.BASEBOARD_FAB2(SCH_1):PAGE136_I148@MSTR_DISCRETE.RES(CHIPS)':
 'B': CDS_PINID='B';
NODE_NAME     R3T14 2
 '@BASEBOARD_FAB2_LIB.BASEBOARD_FAB2(SCH_1):PAGE136_I156@MSTR_DISCRETE.RES(CHIPS)':
 'B': CDS_PINID='B';
NODE_NAME     R7C11 1
 '@BASEBOARD_FAB2_LIB.BASEBOARD_FAB2(SCH_1):PAGE137_I11@MSTR_DISCRETE.RES(CHIPS)':
 'A': CDS_PINID='A';
NODE_NAME     C7C19 2
 '@BASEBOARD_FAB2_LIB.BASEBOARD_FAB2(SCH_1):PAGE137_I14@DEV_DISCRETE.CAP_A(CHIPS)':
 'B': CDS_PINID='B';
NODE_NAME     R1U63 2
 '@BASEBOARD_FAB2_LIB.BASEBOARD_FAB2(SCH_1):PAGE137_I15@MSTR_DISCRETE.RES(CHIPS)':
 'B': CDS_PINID='B';
NODE_NAME     C3N32 2
 '@BASEBOARD_FAB2_LIB.BASEBOARD_FAB2(SCH_1):PAGE137_I20@DEV_DISCRETE.CAP_A(CHIPS)':
 'B': CDS_PINID='B';
NODE_NAME     R1U64 2
 '@BASEBOARD_FAB2_LIB.BASEBOARD_FAB2(SCH_1):PAGE137_I69@MSTR_DISCRETE.RES(CHIPS)':
 'B': CDS_PINID='B';
NODE_NAME     EU9E1 65
 '@BASEBOARD_FAB2_LIB.BASEBOARD_FAB2(SCH_1):PAGE139_I72@MSTR_INTEL.SPRINGVILLE(CHIPS)':
 'GND': CDS_PINID='GND';
NODE_NAME     C1T4 2
 '@BASEBOARD_FAB2_LIB.BASEBOARD_FAB2(SCH_1):PAGE139_I134@MSTR_DISCRETE.CAP(CHIPS)':
 'B': CDS_PINID='B';
NODE_NAME     C1R30 2
 '@BASEBOARD_FAB2_LIB.BASEBOARD_FAB2(SCH_1):PAGE139_I135@MSTR_DISCRETE.CAP(CHIPS)':
 'B': CDS_PINID='B';
NODE_NAME     C1R22 2
 '@BASEBOARD_FAB2_LIB.BASEBOARD_FAB2(SCH_1):PAGE139_I136@MSTR_DISCRETE.CAP(CHIPS)':
 'B': CDS_PINID='B';
NODE_NAME     C1R13 2
 '@BASEBOARD_FAB2_LIB.BASEBOARD_FAB2(SCH_1):PAGE139_I142@MSTR_DISCRETE.CAP(CHIPS)':
 'B': CDS_PINID='B';
NODE_NAME     C1R20 2
 '@BASEBOARD_FAB2_LIB.BASEBOARD_FAB2(SCH_1):PAGE139_I143@DEV_DISCRETE.CAP_A(CHIPS)':
 'B': CDS_PINID='B';
NODE_NAME     C1T3 2
 '@BASEBOARD_FAB2_LIB.BASEBOARD_FAB2(SCH_1):PAGE139_I144@DEV_DISCRETE.CAP_A(CHIPS)':
 'B': CDS_PINID='B';
NODE_NAME     C1R14 2
 '@BASEBOARD_FAB2_LIB.BASEBOARD_FAB2(SCH_1):PAGE139_I145@DEV_DISCRETE.CAP_A(CHIPS)':
 'B': CDS_PINID='B';
NODE_NAME     C1R21 2
 '@BASEBOARD_FAB2_LIB.BASEBOARD_FAB2(SCH_1):PAGE139_I146@DEV_DISCRETE.CAP_A(CHIPS)':
 'B': CDS_PINID='B';
NODE_NAME     C1R26 2
 '@BASEBOARD_FAB2_LIB.BASEBOARD_FAB2(SCH_1):PAGE139_I149@DEV_DISCRETE.CAP_A(CHIPS)':
 'B': CDS_PINID='B';
NODE_NAME     C1R29 2
 '@BASEBOARD_FAB2_LIB.BASEBOARD_FAB2(SCH_1):PAGE139_I150@DEV_DISCRETE.CAP_A(CHIPS)':
 'B': CDS_PINID='B';
NODE_NAME     C1R19 2
 '@BASEBOARD_FAB2_LIB.BASEBOARD_FAB2(SCH_1):PAGE139_I151@DEV_DISCRETE.CAP_A(CHIPS)':
 'B': CDS_PINID='B';
NODE_NAME     C1R31 2
 '@BASEBOARD_FAB2_LIB.BASEBOARD_FAB2(SCH_1):PAGE139_I152@DEV_DISCRETE.CAP_A(CHIPS)':
 'B': CDS_PINID='B';
NODE_NAME     C1R17 2
 '@BASEBOARD_FAB2_LIB.BASEBOARD_FAB2(SCH_1):PAGE139_I153@MSTR_DISCRETE.CAP(CHIPS)':
 'B': CDS_PINID='B';
NODE_NAME     C1R18 2
 '@BASEBOARD_FAB2_LIB.BASEBOARD_FAB2(SCH_1):PAGE139_I157@DEV_DISCRETE.CAP_A(CHIPS)':
 'B': CDS_PINID='B';
NODE_NAME     C1T5 2
 '@BASEBOARD_FAB2_LIB.BASEBOARD_FAB2(SCH_1):PAGE139_I158@DEV_DISCRETE.CAP_A(CHIPS)':
 'B': CDS_PINID='B';
NODE_NAME     C1R24 2
 '@BASEBOARD_FAB2_LIB.BASEBOARD_FAB2(SCH_1):PAGE139_I159@DEV_DISCRETE.CAP_A(CHIPS)':
 'B': CDS_PINID='B';
NODE_NAME     C1R15 2
 '@BASEBOARD_FAB2_LIB.BASEBOARD_FAB2(SCH_1):PAGE139_I160@DEV_DISCRETE.CAP_A(CHIPS)':
 'B': CDS_PINID='B';
NODE_NAME     C1R16 2
 '@BASEBOARD_FAB2_LIB.BASEBOARD_FAB2(SCH_1):PAGE139_I161@MSTR_DISCRETE.CAP(CHIPS)':
 'B': CDS_PINID='B';
NODE_NAME     C9E1 2
 '@BASEBOARD_FAB2_LIB.BASEBOARD_FAB2(SCH_1):PAGE139_I163@DEV_DISCRETE.CAP_A(CHIPS)':
 'B': CDS_PINID='B';
NODE_NAME     R9E23 2
 '@BASEBOARD_FAB2_LIB.BASEBOARD_FAB2(SCH_1):PAGE139_I174@MSTR_DISCRETE.RES(CHIPS)':
 'B': CDS_PINID='B';
NODE_NAME     R9E13 2
 '@BASEBOARD_FAB2_LIB.BASEBOARD_FAB2(SCH_1):PAGE139_I212@MSTR_DISCRETE.RES(CHIPS)':
 'B': CDS_PINID='B';
NODE_NAME     R1R12 2
 '@BASEBOARD_FAB2_LIB.BASEBOARD_FAB2(SCH_1):PAGE139_I213@MSTR_DISCRETE.RES(CHIPS)':
 'B': CDS_PINID='B';
NODE_NAME     R1T1 2
 '@BASEBOARD_FAB2_LIB.BASEBOARD_FAB2(SCH_1):PAGE139_I214@MSTR_DISCRETE.RES(CHIPS)':
 'B': CDS_PINID='B';
NODE_NAME     C9E12 2
 '@BASEBOARD_FAB2_LIB.BASEBOARD_FAB2(SCH_1):PAGE139_I241@DEV_DISCRETE.CAP_A(CHIPS)':
 'B': CDS_PINID='B';
NODE_NAME     U9E1 4
 '@BASEBOARD_FAB2_LIB.BASEBOARD_FAB2(SCH_1):PAGE140_I1@MSTR_MEMORY.M25PE16(CHIPS)':
 'VSS': CDS_PINID='VSS';
NODE_NAME     C1R25 2
 '@BASEBOARD_FAB2_LIB.BASEBOARD_FAB2(SCH_1):PAGE140_I3@DEV_DISCRETE.CAP_A(CHIPS)':
 'B': CDS_PINID='B';
NODE_NAME     R1R6 2
 '@BASEBOARD_FAB2_LIB.BASEBOARD_FAB2(SCH_1):PAGE140_I14@MSTR_DISCRETE.RES(CHIPS)':
 'B': CDS_PINID='B';
NODE_NAME     C9G4 2
 '@BASEBOARD_FAB2_LIB.BASEBOARD_FAB2(SCH_1):PAGE141_I46@DEV_DISCRETE.CAP_A(CHIPS)':
 'B': CDS_PINID='B';
NODE_NAME     C9G6 2
 '@BASEBOARD_FAB2_LIB.BASEBOARD_FAB2(SCH_1):PAGE141_I47@DEV_DISCRETE.CAP_A(CHIPS)':
 'B': CDS_PINID='B';
NODE_NAME     C9G5 2
 '@BASEBOARD_FAB2_LIB.BASEBOARD_FAB2(SCH_1):PAGE141_I48@MSTR_DISCRETE.CAP(CHIPS)':
 'B': CDS_PINID='B';
NODE_NAME     C8E5 2
 '@BASEBOARD_FAB2_LIB.BASEBOARD_FAB2(SCH_1):PAGE142_I20@DEV_DISCRETE.CAP_A(CHIPS)':
 'B': CDS_PINID='B';
NODE_NAME     U9G1 7
 '@BASEBOARD_FAB2_LIB.BASEBOARD_FAB2(SCH_1):PAGE152_I1@MSTR_DIGITAL.GTL2014(CHIPS)':
 'GND'<0>: CDS_PINID='GND(0)';
NODE_NAME     U9G1 8
 '@BASEBOARD_FAB2_LIB.BASEBOARD_FAB2(SCH_1):PAGE152_I1@MSTR_DIGITAL.GTL2014(CHIPS)':
 'GND'<1>: CDS_PINID='GND(1)';
NODE_NAME     U9G1 11
 '@BASEBOARD_FAB2_LIB.BASEBOARD_FAB2(SCH_1):PAGE152_I1@MSTR_DIGITAL.GTL2014(CHIPS)':
 'GND'<2>: CDS_PINID='GND(2)';
NODE_NAME     R1U30 2
 '@BASEBOARD_FAB2_LIB.BASEBOARD_FAB2(SCH_1):PAGE152_I2@MSTR_DISCRETE.RES(CHIPS)':
 'B': CDS_PINID='B';
NODE_NAME     C1U19 2
 '@BASEBOARD_FAB2_LIB.BASEBOARD_FAB2(SCH_1):PAGE152_I18@MSTR_DISCRETE.CAP(CHIPS)':
 'B': CDS_PINID='B';
NODE_NAME     R1U37 2
 '@BASEBOARD_FAB2_LIB.BASEBOARD_FAB2(SCH_1):PAGE152_I26@MSTR_DISCRETE.RES(CHIPS)':
 'B': CDS_PINID='B';
NODE_NAME     C1U22 2
 '@BASEBOARD_FAB2_LIB.BASEBOARD_FAB2(SCH_1):PAGE152_I27@DEV_DISCRETE.CAP_A(CHIPS)':
 'B': CDS_PINID='B';
NODE_NAME     C7F2 2
 '@BASEBOARD_FAB2_LIB.BASEBOARD_FAB2(SCH_1):PAGE153_I130@DEV_DISCRETE.CAP_A(CHIPS)':
 'B': CDS_PINID='B';
NODE_NAME     C7F1 2
 '@BASEBOARD_FAB2_LIB.BASEBOARD_FAB2(SCH_1):PAGE153_I131@DEV_DISCRETE.CAP_A(CHIPS)':
 'B': CDS_PINID='B';
NODE_NAME     C3T5 2
 '@BASEBOARD_FAB2_LIB.BASEBOARD_FAB2(SCH_1):PAGE153_I136@DEV_DISCRETE.CAP_A(CHIPS)':
 'B': CDS_PINID='B';
NODE_NAME     C3T4 2
 '@BASEBOARD_FAB2_LIB.BASEBOARD_FAB2(SCH_1):PAGE153_I138@DEV_DISCRETE.CAP_A(CHIPS)':
 'B': CDS_PINID='B';
NODE_NAME     U7F1 10
 '@BASEBOARD_FAB2_LIB.BASEBOARD_FAB2(SCH_1):PAGE153_I146@MSTR_MEMORY.W25Q256(CHIPS)':
 'GND': CDS_PINID='GND';
NODE_NAME     R7F30 2
 '@BASEBOARD_FAB2_LIB.BASEBOARD_FAB2(SCH_1):PAGE153_I170@MSTR_DISCRETE.RES(CHIPS)':
 'B': CDS_PINID='B';
NODE_NAME     R3T9 2
 '@BASEBOARD_FAB2_LIB.BASEBOARD_FAB2(SCH_1):PAGE153_I179@MSTR_DISCRETE.RES(CHIPS)':
 'B': CDS_PINID='B';
NODE_NAME     C8E18 2
 '@BASEBOARD_FAB2_LIB.BASEBOARD_FAB2(SCH_1):PAGE154_I14@DEV_DISCRETE.CAP_A(CHIPS)':
 'B': CDS_PINID='B';
NODE_NAME     U8F1 15
 '@BASEBOARD_FAB2_LIB.BASEBOARD_FAB2(SCH_1):PAGE154_I74@MSTR_DIGITAL.PI3B3257A(CHIPS)':
 'EN': CDS_PINID='EN';
NODE_NAME     U8F1 8
 '@BASEBOARD_FAB2_LIB.BASEBOARD_FAB2(SCH_1):PAGE154_I74@MSTR_DIGITAL.PI3B3257A(CHIPS)':
 'GND': CDS_PINID='GND';
NODE_NAME     U2T1 15
 '@BASEBOARD_FAB2_LIB.BASEBOARD_FAB2(SCH_1):PAGE154_I75@MSTR_DIGITAL.PI3B3257A(CHIPS)':
 'EN': CDS_PINID='EN';
NODE_NAME     U2T1 8
 '@BASEBOARD_FAB2_LIB.BASEBOARD_FAB2(SCH_1):PAGE154_I75@MSTR_DIGITAL.PI3B3257A(CHIPS)':
 'GND': CDS_PINID='GND';
NODE_NAME     C2T1 2
 '@BASEBOARD_FAB2_LIB.BASEBOARD_FAB2(SCH_1):PAGE154_I94@DEV_DISCRETE.CAP_A(CHIPS)':
 'B': CDS_PINID='B';
NODE_NAME     Q8F1 2
 '@BASEBOARD_FAB2_LIB.BASEBOARD_FAB2(SCH_1):PAGE154_I126@MSTR_DISCRETE.FET_N(CHIPS)':
 'SRC': CDS_PINID='SRC';
NODE_NAME     R1U6 2
 '@BASEBOARD_FAB2_LIB.BASEBOARD_FAB2(SCH_1):PAGE154_I128@MSTR_DISCRETE.RES(CHIPS)':
 'B': CDS_PINID='B';
NODE_NAME     C2T12 2
 '@BASEBOARD_FAB2_LIB.BASEBOARD_FAB2(SCH_1):PAGE154_I132@DEV_DISCRETE.CAP_A(CHIPS)':
 'B': CDS_PINID='B';
NODE_NAME     C2T8 2
 '@BASEBOARD_FAB2_LIB.BASEBOARD_FAB2(SCH_1):PAGE154_I135@DEV_DISCRETE.CAP_A(CHIPS)':
 'B': CDS_PINID='B';
NODE_NAME     C9A1 2
 '@BASEBOARD_FAB2_LIB.BASEBOARD_FAB2(SCH_1):PAGE155_I127@DEV_DISCRETE.CAP_A(CHIPS)':
 'B': CDS_PINID='B';
NODE_NAME     J9A2 13
 '@BASEBOARD_FAB2_LIB.BASEBOARD_FAB2(SCH_1):PAGE155_I171@MSTR_CONN.CONN14_H54902001(CHIPS)':
 'IO13': CDS_PINID='IO13';
NODE_NAME     C1T56 2
 '@BASEBOARD_FAB2_LIB.BASEBOARD_FAB2(SCH_1):PAGE155_I184@DEV_DISCRETE.CAP_A(CHIPS)':
 'B': CDS_PINID='B';
NODE_NAME     Q1L2 4
 '@BASEBOARD_FAB2_LIB.BASEBOARD_FAB2(SCH_1):PAGE155_I187@MSTR_DISCRETE.FET_N_DUAL(CHIPS)':
 'SOURCE'<0>: CDS_PINID='SOURCE(0)';
NODE_NAME     C2T35 2
 '@BASEBOARD_FAB2_LIB.BASEBOARD_FAB2(SCH_1):PAGE156_I273@DEV_DISCRETE.CAP_A(CHIPS)':
 'B': CDS_PINID='B';
NODE_NAME     C8F16 2
 '@BASEBOARD_FAB2_LIB.BASEBOARD_FAB2(SCH_1):PAGE156_I275@DEV_DISCRETE.CAP_A(CHIPS)':
 'B': CDS_PINID='B';
NODE_NAME     J9B2 2
 '@BASEBOARD_FAB2_LIB.BASEBOARD_FAB2(SCH_1):PAGE156_I281@MSTR_CONN.CONN3_C95678002(CHIPS)':
 'IO2': CDS_PINID='IO2';
NODE_NAME     J8C1 2
 '@BASEBOARD_FAB2_LIB.BASEBOARD_FAB2(SCH_1):PAGE156_I285@MSTR_CONN.CONN3_C95678002(CHIPS)':
 'IO2': CDS_PINID='IO2';
NODE_NAME     R6N14 1
 '@BASEBOARD_FAB2_LIB.BASEBOARD_FAB2(SCH_1):PAGE156_I302@MSTR_DISCRETE.RES(CHIPS)':
 'A': CDS_PINID='A';
NODE_NAME     R6N13 1
 '@BASEBOARD_FAB2_LIB.BASEBOARD_FAB2(SCH_1):PAGE156_I303@MSTR_DISCRETE.RES(CHIPS)':
 'A': CDS_PINID='A';
NODE_NAME     R6N15 1
 '@BASEBOARD_FAB2_LIB.BASEBOARD_FAB2(SCH_1):PAGE156_I304@MSTR_DISCRETE.RES(CHIPS)':
 'A': CDS_PINID='A';
NODE_NAME     R1C32 1
 '@BASEBOARD_FAB2_LIB.BASEBOARD_FAB2(SCH_1):PAGE156_I312@MSTR_DISCRETE.RES(CHIPS)':
 'A': CDS_PINID='A';
NODE_NAME     R1C33 1
 '@BASEBOARD_FAB2_LIB.BASEBOARD_FAB2(SCH_1):PAGE156_I313@MSTR_DISCRETE.RES(CHIPS)':
 'A': CDS_PINID='A';
NODE_NAME     R3P56 2
 '@BASEBOARD_FAB2_LIB.BASEBOARD_FAB2(SCH_1):PAGE156_I333@MSTR_DISCRETE.RES(CHIPS)':
 'B': CDS_PINID='B';
NODE_NAME     R1C36 2
 '@BASEBOARD_FAB2_LIB.BASEBOARD_FAB2(SCH_1):PAGE156_I337@MSTR_DISCRETE.RES(CHIPS)':
 'B': CDS_PINID='B';
NODE_NAME     Q2T1 2
 '@BASEBOARD_FAB2_LIB.BASEBOARD_FAB2(SCH_1):PAGE157_I330@MSTR_DISCRETE.NPN(CHIPS)':
 'E': CDS_PINID='E';
NODE_NAME     Q2T2 2
 '@BASEBOARD_FAB2_LIB.BASEBOARD_FAB2(SCH_1):PAGE157_I340@MSTR_DISCRETE.FET_N(CHIPS)':
 'SRC': CDS_PINID='SRC';
NODE_NAME     S8E1 1
 '@BASEBOARD_FAB2_LIB.BASEBOARD_FAB2(SCH_1):PAGE157_I351@MSTR_MISC.SWITCH_D90553001(CHIPS)':
 'A': CDS_PINID='A';
NODE_NAME     C2R12 2
 '@BASEBOARD_FAB2_LIB.BASEBOARD_FAB2(SCH_1):PAGE157_I353@DEV_DISCRETE.CAP_A(CHIPS)':
 'B': CDS_PINID='B';
NODE_NAME     C2T3 2
 '@BASEBOARD_FAB2_LIB.BASEBOARD_FAB2(SCH_1):PAGE157_I370@DEV_DISCRETE.CAP_A(CHIPS)':
 'B': CDS_PINID='B';
NODE_NAME     C8D1 2
 '@BASEBOARD_FAB2_LIB.BASEBOARD_FAB2(SCH_1):PAGE157_I376@DEV_DISCRETE.CAP_A(CHIPS)':
 'B': CDS_PINID='B';
NODE_NAME     C1T10 2
 '@BASEBOARD_FAB2_LIB.BASEBOARD_FAB2(SCH_1):PAGE158_I70@DEV_DISCRETE.CAP_A(CHIPS)':
 'B': CDS_PINID='B';
NODE_NAME     U9F2 4
 '@BASEBOARD_FAB2_LIB.BASEBOARD_FAB2(SCH_1):PAGE158_I74@MSTR_ANALOG.FSA3357(CHIPS)':
 'GND': CDS_PINID='GND';
NODE_NAME     U9F1 4
 '@BASEBOARD_FAB2_LIB.BASEBOARD_FAB2(SCH_1):PAGE158_I75@MSTR_ANALOG.FSA3357(CHIPS)':
 'GND': CDS_PINID='GND';
NODE_NAME     C1T11 2
 '@BASEBOARD_FAB2_LIB.BASEBOARD_FAB2(SCH_1):PAGE158_I97@DEV_DISCRETE.CAP_A(CHIPS)':
 'B': CDS_PINID='B';
NODE_NAME     C1E21 2
 '@BASEBOARD_FAB2_LIB.BASEBOARD_FAB2(SCH_1):PAGE161_I3@MSTR_DISCRETE.CAP(CHIPS)':
 'B': CDS_PINID='B';
NODE_NAME     C1E20 2
 '@BASEBOARD_FAB2_LIB.BASEBOARD_FAB2(SCH_1):PAGE161_I4@DEV_DISCRETE.CAP_A(CHIPS)':
 'B': CDS_PINID='B';
NODE_NAME     C9M5 2
 '@BASEBOARD_FAB2_LIB.BASEBOARD_FAB2(SCH_1):PAGE161_I26@DEV_DISCRETE.CAP_A(CHIPS)':
 'B': CDS_PINID='B';
NODE_NAME     C9M4 2
 '@BASEBOARD_FAB2_LIB.BASEBOARD_FAB2(SCH_1):PAGE161_I27@MSTR_DISCRETE.CAP(CHIPS)':
 'B': CDS_PINID='B';
NODE_NAME     C1F9 2
 '@BASEBOARD_FAB2_LIB.BASEBOARD_FAB2(SCH_1):PAGE161_I46@DEV_DISCRETE.CAP_A(CHIPS)':
 'B': CDS_PINID='B';
NODE_NAME     C1B15 2
 '@BASEBOARD_FAB2_LIB.BASEBOARD_FAB2(SCH_1):PAGE161_I68@DEV_DISCRETE.CAP_A(CHIPS)':
 'B': CDS_PINID='B';
NODE_NAME     C2U27 2
 '@BASEBOARD_FAB2_LIB.BASEBOARD_FAB2(SCH_1):PAGE161_I90@DEV_DISCRETE.CAP_A(CHIPS)':
 'B': CDS_PINID='B';
NODE_NAME     C2U28 2
 '@BASEBOARD_FAB2_LIB.BASEBOARD_FAB2(SCH_1):PAGE161_I93@DEV_DISCRETE.CAP_A(CHIPS)':
 'B': CDS_PINID='B';
NODE_NAME     C1E22 2
 '@BASEBOARD_FAB2_LIB.BASEBOARD_FAB2(SCH_1):PAGE161_I113@DEV_DISCRETE.CAP_A(CHIPS)':
 'B': CDS_PINID='B';
NODE_NAME     R8F35 2
 '@BASEBOARD_FAB2_LIB.BASEBOARD_FAB2(SCH_1):PAGE162_I24@MSTR_DISCRETE.RES(CHIPS)':
 'B': CDS_PINID='B';
NODE_NAME     C8F5 2
 '@BASEBOARD_FAB2_LIB.BASEBOARD_FAB2(SCH_1):PAGE162_I28@DEV_DISCRETE.CAP_A(CHIPS)':
 'B': CDS_PINID='B';
NODE_NAME     C8F4 2
 '@BASEBOARD_FAB2_LIB.BASEBOARD_FAB2(SCH_1):PAGE162_I30@DEV_DISCRETE.CAP_A(CHIPS)':
 'B': CDS_PINID='B';
NODE_NAME     U8F2 10
 '@BASEBOARD_FAB2_LIB.BASEBOARD_FAB2(SCH_1):PAGE162_I32@MSTR_MEMORY.W25Q128(CHIPS)':
 'GND': CDS_PINID='GND';
NODE_NAME     C9M8 2
 '@BASEBOARD_FAB2_LIB.BASEBOARD_FAB2(SCH_1):PAGE163_I10@DEV_DISCRETE.CAP_A(CHIPS)':
 'B': CDS_PINID='B';
NODE_NAME     C9M7 2
 '@BASEBOARD_FAB2_LIB.BASEBOARD_FAB2(SCH_1):PAGE163_I12@DEV_DISCRETE.CAP_A(CHIPS)':
 'B': CDS_PINID='B';
NODE_NAME     R1T11 2
 '@BASEBOARD_FAB2_LIB.BASEBOARD_FAB2(SCH_1):PAGE164_I7@MSTR_DISCRETE.RES(CHIPS)':
 'B': CDS_PINID='B';
NODE_NAME     R1U17 2
 '@BASEBOARD_FAB2_LIB.BASEBOARD_FAB2(SCH_1):PAGE164_I21@MSTR_DISCRETE.RES(CHIPS)':
 'B': CDS_PINID='B';
NODE_NAME     R2N18 2
 '@BASEBOARD_FAB2_LIB.BASEBOARD_FAB2(SCH_1):PAGE164_I32@MSTR_DISCRETE.RES(CHIPS)':
 'B': CDS_PINID='B';
NODE_NAME     R7D15 2
 '@BASEBOARD_FAB2_LIB.BASEBOARD_FAB2(SCH_1):PAGE166_I32@MSTR_DISCRETE.RES(CHIPS)':
 'B': CDS_PINID='B';
NODE_NAME     U9B4 5
 '@BASEBOARD_FAB2_LIB.BASEBOARD_FAB2(SCH_1):PAGE167_I1@MSTR_ANALOG.TMP421(CHIPS)':
 'GND': CDS_PINID='GND';
NODE_NAME     R9B8 2
 '@BASEBOARD_FAB2_LIB.BASEBOARD_FAB2(SCH_1):PAGE167_I10@MSTR_DISCRETE.RES(CHIPS)':
 'B': CDS_PINID='B';
NODE_NAME     U1E1 5
 '@BASEBOARD_FAB2_LIB.BASEBOARD_FAB2(SCH_1):PAGE167_I30@MSTR_ANALOG.TMP421(CHIPS)':
 'GND': CDS_PINID='GND';
NODE_NAME     C9B7 2
 '@BASEBOARD_FAB2_LIB.BASEBOARD_FAB2(SCH_1):PAGE167_I39@DEV_DISCRETE.CAP_A(CHIPS)':
 'B': CDS_PINID='B';
NODE_NAME     C9R14 2
 '@BASEBOARD_FAB2_LIB.BASEBOARD_FAB2(SCH_1):PAGE167_I41@DEV_DISCRETE.CAP_A(CHIPS)':
 'B': CDS_PINID='B';
NODE_NAME     C9R13 2
 '@BASEBOARD_FAB2_LIB.BASEBOARD_FAB2(SCH_1):PAGE167_I42@DEV_DISCRETE.CAP_A(CHIPS)':
 'B': CDS_PINID='B';
NODE_NAME     U8D4 1
 '@BASEBOARD_FAB2_LIB.BASEBOARD_FAB2(SCH_1):PAGE167_I49@MSTR_MEMORY.AT24C64(CHIPS)':
 'A0': CDS_PINID='A0';
NODE_NAME     U8D4 2
 '@BASEBOARD_FAB2_LIB.BASEBOARD_FAB2(SCH_1):PAGE167_I49@MSTR_MEMORY.AT24C64(CHIPS)':
 'A1': CDS_PINID='A1';
NODE_NAME     R8D27 2
 '@BASEBOARD_FAB2_LIB.BASEBOARD_FAB2(SCH_1):PAGE167_I50@MSTR_DISCRETE.RES(CHIPS)':
 'B': CDS_PINID='B';
NODE_NAME     Q1L3 2
 '@BASEBOARD_FAB2_LIB.BASEBOARD_FAB2(SCH_1):PAGE168_I8@MSTR_DISCRETE.NPN(CHIPS)':
 'E': CDS_PINID='E';
NODE_NAME     Q1L4 1
 '@BASEBOARD_FAB2_LIB.BASEBOARD_FAB2(SCH_1):PAGE168_I19@MSTR_DISCRETE.FET_N_DUAL(CHIPS)':
 'SOURCE'<0>: CDS_PINID='SOURCE(0)';
NODE_NAME     C1U21 2
 '@BASEBOARD_FAB2_LIB.BASEBOARD_FAB2(SCH_1):PAGE169_I56@MSTR_DISCRETE.CAP(CHIPS)':
 'B': CDS_PINID='B';
NODE_NAME     C9G21 2
 '@BASEBOARD_FAB2_LIB.BASEBOARD_FAB2(SCH_1):PAGE169_I68@MSTR_DISCRETE.CAP(CHIPS)':
 'B': CDS_PINID='B';
NODE_NAME     C9G17 2
 '@BASEBOARD_FAB2_LIB.BASEBOARD_FAB2(SCH_1):PAGE169_I80@MSTR_DISCRETE.CAP(CHIPS)':
 'B': CDS_PINID='B';
NODE_NAME     C9G20 2
 '@BASEBOARD_FAB2_LIB.BASEBOARD_FAB2(SCH_1):PAGE169_I86@MSTR_DISCRETE.CAP(CHIPS)':
 'B': CDS_PINID='B';
NODE_NAME     R9G26 2
 '@BASEBOARD_FAB2_LIB.BASEBOARD_FAB2(SCH_1):PAGE169_I106@MSTR_DISCRETE.RES(CHIPS)':
 'B': CDS_PINID='B';
NODE_NAME     C9G22 2
 '@BASEBOARD_FAB2_LIB.BASEBOARD_FAB2(SCH_1):PAGE169_I108@MSTR_DISCRETE.CAP(CHIPS)':
 'B': CDS_PINID='B';
NODE_NAME     C9G15 2
 '@BASEBOARD_FAB2_LIB.BASEBOARD_FAB2(SCH_1):PAGE169_I139@MSTR_DISCRETE.CAP(CHIPS)':
 'B': CDS_PINID='B';
NODE_NAME     C9G14 2
 '@BASEBOARD_FAB2_LIB.BASEBOARD_FAB2(SCH_1):PAGE169_I146@MSTR_DISCRETE.CAP(CHIPS)':
 'B': CDS_PINID='B';
NODE_NAME     C9G18 2
 '@BASEBOARD_FAB2_LIB.BASEBOARD_FAB2(SCH_1):PAGE169_I153@MSTR_DISCRETE.CAP(CHIPS)':
 'B': CDS_PINID='B';
NODE_NAME     Q9G1 1
 '@BASEBOARD_FAB2_LIB.BASEBOARD_FAB2(SCH_1):PAGE169_I162@MSTR_DISCRETE.FET_N_DUAL(CHIPS)':
 'SOURCE'<0>: CDS_PINID='SOURCE(0)';
NODE_NAME     C2P1 2
 '@BASEBOARD_FAB2_LIB.BASEBOARD_FAB2(SCH_1):PAGE170_I8@DEV_DISCRETE.CAP_A(CHIPS)':
 'B': CDS_PINID='B';
NODE_NAME     C1R27 2
 '@BASEBOARD_FAB2_LIB.BASEBOARD_FAB2(SCH_1):PAGE170_I30@DEV_DISCRETE.CAP_A(CHIPS)':
 'B': CDS_PINID='B';
NODE_NAME     C8D2 2
 '@BASEBOARD_FAB2_LIB.BASEBOARD_FAB2(SCH_1):PAGE170_I33@DEV_DISCRETE.CAP_A(CHIPS)':
 'B': CDS_PINID='B';
NODE_NAME     C8E2 2
 '@BASEBOARD_FAB2_LIB.BASEBOARD_FAB2(SCH_1):PAGE170_I40@DEV_DISCRETE.CAP_A(CHIPS)':
 'B': CDS_PINID='B';
NODE_NAME     C8D3 2
 '@BASEBOARD_FAB2_LIB.BASEBOARD_FAB2(SCH_1):PAGE170_I42@MSTR_DISCRETE.CAP(CHIPS)':
 'B': CDS_PINID='B';
NODE_NAME     C1R28 2
 '@BASEBOARD_FAB2_LIB.BASEBOARD_FAB2(SCH_1):PAGE170_I49@DEV_DISCRETE.CAP_A(CHIPS)':
 'B': CDS_PINID='B';
NODE_NAME     Q2P1 2
 '@BASEBOARD_FAB2_LIB.BASEBOARD_FAB2(SCH_1):PAGE170_I58@MSTR_DISCRETE.FET_N(CHIPS)':
 'SRC': CDS_PINID='SRC';
NODE_NAME     R2P11 2
 '@BASEBOARD_FAB2_LIB.BASEBOARD_FAB2(SCH_1):PAGE170_I63@MSTR_DISCRETE.RES(CHIPS)':
 'B': CDS_PINID='B';
NODE_NAME     Q8F2 2
 '@BASEBOARD_FAB2_LIB.BASEBOARD_FAB2(SCH_1):PAGE170_I67@MSTR_DISCRETE.FET_N(CHIPS)':
 'SRC': CDS_PINID='SRC';
NODE_NAME     C9B2 2
 '@BASEBOARD_FAB2_LIB.BASEBOARD_FAB2(SCH_1):PAGE172_I36@MSTR_DISCRETE.CAP(CHIPS)':
 'B': CDS_PINID='B';
NODE_NAME     C9B1 2
 '@BASEBOARD_FAB2_LIB.BASEBOARD_FAB2(SCH_1):PAGE172_I39@MSTR_DISCRETE.CAP(CHIPS)':
 'B': CDS_PINID='B';
NODE_NAME     J8A1 2D9
 '@BASEBOARD_FAB2_LIB.BASEBOARD_FAB2(SCH_1):PAGE173_I163@MSTR_CONN.CONN72_G97614002_A(CHIPS)':
 'GND'<0>: CDS_PINID='GND(0)';
NODE_NAME     J8A1 2D6
 '@BASEBOARD_FAB2_LIB.BASEBOARD_FAB2(SCH_1):PAGE173_I163@MSTR_CONN.CONN72_G97614002_A(CHIPS)':
 'GND'<1>: CDS_PINID='GND(1)';
NODE_NAME     J8A1 2D3
 '@BASEBOARD_FAB2_LIB.BASEBOARD_FAB2(SCH_1):PAGE173_I163@MSTR_CONN.CONN72_G97614002_A(CHIPS)':
 'GND'<2>: CDS_PINID='GND(2)';
NODE_NAME     J8A1 2C9
 '@BASEBOARD_FAB2_LIB.BASEBOARD_FAB2(SCH_1):PAGE173_I163@MSTR_CONN.CONN72_G97614002_A(CHIPS)':
 'GND'<3>: CDS_PINID='GND(3)';
NODE_NAME     J8A1 2C6
 '@BASEBOARD_FAB2_LIB.BASEBOARD_FAB2(SCH_1):PAGE173_I163@MSTR_CONN.CONN72_G97614002_A(CHIPS)':
 'GND'<4>: CDS_PINID='GND(4)';
NODE_NAME     J8A1 2C3
 '@BASEBOARD_FAB2_LIB.BASEBOARD_FAB2(SCH_1):PAGE173_I163@MSTR_CONN.CONN72_G97614002_A(CHIPS)':
 'GND'<5>: CDS_PINID='GND(5)';
NODE_NAME     J8A1 2B9
 '@BASEBOARD_FAB2_LIB.BASEBOARD_FAB2(SCH_1):PAGE173_I163@MSTR_CONN.CONN72_G97614002_A(CHIPS)':
 'GND'<6>: CDS_PINID='GND(6)';
NODE_NAME     J8A1 2B6
 '@BASEBOARD_FAB2_LIB.BASEBOARD_FAB2(SCH_1):PAGE173_I163@MSTR_CONN.CONN72_G97614002_A(CHIPS)':
 'GND'<7>: CDS_PINID='GND(7)';
NODE_NAME     J8A1 2B3
 '@BASEBOARD_FAB2_LIB.BASEBOARD_FAB2(SCH_1):PAGE173_I163@MSTR_CONN.CONN72_G97614002_A(CHIPS)':
 'GND'<8>: CDS_PINID='GND(8)';
NODE_NAME     J8A1 2A9
 '@BASEBOARD_FAB2_LIB.BASEBOARD_FAB2(SCH_1):PAGE173_I163@MSTR_CONN.CONN72_G97614002_A(CHIPS)':
 'GND'<9>: CDS_PINID='GND(9)';
NODE_NAME     J8A1 2A6
 '@BASEBOARD_FAB2_LIB.BASEBOARD_FAB2(SCH_1):PAGE173_I163@MSTR_CONN.CONN72_G97614002_A(CHIPS)':
 'GND'<10>: CDS_PINID='GND(10)';
NODE_NAME     J8A1 2A3
 '@BASEBOARD_FAB2_LIB.BASEBOARD_FAB2(SCH_1):PAGE173_I163@MSTR_CONN.CONN72_G97614002_A(CHIPS)':
 'GND'<11>: CDS_PINID='GND(11)';
NODE_NAME     J8A1 1D9
 '@BASEBOARD_FAB2_LIB.BASEBOARD_FAB2(SCH_1):PAGE173_I163@MSTR_CONN.CONN72_G97614002_A(CHIPS)':
 'GND'<12>: CDS_PINID='GND(12)';
NODE_NAME     J8A1 1D6
 '@BASEBOARD_FAB2_LIB.BASEBOARD_FAB2(SCH_1):PAGE173_I163@MSTR_CONN.CONN72_G97614002_A(CHIPS)':
 'GND'<13>: CDS_PINID='GND(13)';
NODE_NAME     J8A1 1D3
 '@BASEBOARD_FAB2_LIB.BASEBOARD_FAB2(SCH_1):PAGE173_I163@MSTR_CONN.CONN72_G97614002_A(CHIPS)':
 'GND'<14>: CDS_PINID='GND(14)';
NODE_NAME     J8A1 1C9
 '@BASEBOARD_FAB2_LIB.BASEBOARD_FAB2(SCH_1):PAGE173_I163@MSTR_CONN.CONN72_G97614002_A(CHIPS)':
 'GND'<15>: CDS_PINID='GND(15)';
NODE_NAME     J8A1 1C6
 '@BASEBOARD_FAB2_LIB.BASEBOARD_FAB2(SCH_1):PAGE173_I163@MSTR_CONN.CONN72_G97614002_A(CHIPS)':
 'GND'<16>: CDS_PINID='GND(16)';
NODE_NAME     J8A1 1C3
 '@BASEBOARD_FAB2_LIB.BASEBOARD_FAB2(SCH_1):PAGE173_I163@MSTR_CONN.CONN72_G97614002_A(CHIPS)':
 'GND'<17>: CDS_PINID='GND(17)';
NODE_NAME     J8A1 1B9
 '@BASEBOARD_FAB2_LIB.BASEBOARD_FAB2(SCH_1):PAGE173_I163@MSTR_CONN.CONN72_G97614002_A(CHIPS)':
 'GND'<18>: CDS_PINID='GND(18)';
NODE_NAME     J8A1 1B6
 '@BASEBOARD_FAB2_LIB.BASEBOARD_FAB2(SCH_1):PAGE173_I163@MSTR_CONN.CONN72_G97614002_A(CHIPS)':
 'GND'<19>: CDS_PINID='GND(19)';
NODE_NAME     J8A1 1B3
 '@BASEBOARD_FAB2_LIB.BASEBOARD_FAB2(SCH_1):PAGE173_I163@MSTR_CONN.CONN72_G97614002_A(CHIPS)':
 'GND'<20>: CDS_PINID='GND(20)';
NODE_NAME     J8A1 1A9
 '@BASEBOARD_FAB2_LIB.BASEBOARD_FAB2(SCH_1):PAGE173_I163@MSTR_CONN.CONN72_G97614002_A(CHIPS)':
 'GND'<21>: CDS_PINID='GND(21)';
NODE_NAME     J8A1 1A6
 '@BASEBOARD_FAB2_LIB.BASEBOARD_FAB2(SCH_1):PAGE173_I163@MSTR_CONN.CONN72_G97614002_A(CHIPS)':
 'GND'<22>: CDS_PINID='GND(22)';
NODE_NAME     J8A1 1A3
 '@BASEBOARD_FAB2_LIB.BASEBOARD_FAB2(SCH_1):PAGE173_I163@MSTR_CONN.CONN72_G97614002_A(CHIPS)':
 'GND'<23>: CDS_PINID='GND(23)';
NODE_NAME     J8A1 1C2
 '@BASEBOARD_FAB2_LIB.BASEBOARD_FAB2(SCH_1):PAGE173_I163@MSTR_CONN.CONN72_G97614002_A(CHIPS)':
 'SIDEBANDA_2': CDS_PINID='SIDEBANDA_2';
NODE_NAME     J8A1 1B1
 '@BASEBOARD_FAB2_LIB.BASEBOARD_FAB2(SCH_1):PAGE173_I163@MSTR_CONN.CONN72_G97614002_A(CHIPS)':
 'SIDEBANDA_3': CDS_PINID='SIDEBANDA_3';
NODE_NAME     J8A1 2C2
 '@BASEBOARD_FAB2_LIB.BASEBOARD_FAB2(SCH_1):PAGE173_I163@MSTR_CONN.CONN72_G97614002_A(CHIPS)':
 'SIDEBANDB_2': CDS_PINID='SIDEBANDB_2';
NODE_NAME     J8A1 2B1
 '@BASEBOARD_FAB2_LIB.BASEBOARD_FAB2(SCH_1):PAGE173_I163@MSTR_CONN.CONN72_G97614002_A(CHIPS)':
 'SIDEBANDB_3': CDS_PINID='SIDEBANDB_3';
NODE_NAME     R2L22 2
 '@BASEBOARD_FAB2_LIB.BASEBOARD_FAB2(SCH_1):PAGE173_I264@MSTR_DISCRETE.RES(CHIPS)':
 'B': CDS_PINID='B';
NODE_NAME     R2L18 2
 '@BASEBOARD_FAB2_LIB.BASEBOARD_FAB2(SCH_1):PAGE173_I266@MSTR_DISCRETE.RES(CHIPS)':
 'B': CDS_PINID='B';
NODE_NAME     C1L18 2
 '@BASEBOARD_FAB2_LIB.BASEBOARD_FAB2(SCH_1):PAGE175_I11@DEV_DISCRETE.CAP_A(CHIPS)':
 'B': CDS_PINID='B';
NODE_NAME     C1L10 2
 '@BASEBOARD_FAB2_LIB.BASEBOARD_FAB2(SCH_1):PAGE175_I19@DEV_DISCRETE.CAP_A(CHIPS)':
 'B': CDS_PINID='B';
NODE_NAME     C1L17 2
 '@BASEBOARD_FAB2_LIB.BASEBOARD_FAB2(SCH_1):PAGE175_I37@DEV_DISCRETE.CAP_A(CHIPS)':
 'B': CDS_PINID='B';
NODE_NAME     C1L9 2
 '@BASEBOARD_FAB2_LIB.BASEBOARD_FAB2(SCH_1):PAGE175_I38@DEV_DISCRETE.CAP_A(CHIPS)':
 'B': CDS_PINID='B';
NODE_NAME     C9A3 2
 '@BASEBOARD_FAB2_LIB.BASEBOARD_FAB2(SCH_1):PAGE175_I40@DEV_DISCRETE.CAP_A(CHIPS)':
 'B': CDS_PINID='B';
NODE_NAME     Q9A3 2
 '@BASEBOARD_FAB2_LIB.BASEBOARD_FAB2(SCH_1):PAGE175_I49@MSTR_DISCRETE.FET_N(CHIPS)':
 'SRC': CDS_PINID='SRC';
NODE_NAME     C1L4 2
 '@BASEBOARD_FAB2_LIB.BASEBOARD_FAB2(SCH_1):PAGE175_I64@DEV_DISCRETE.CAP_A(CHIPS)':
 'B': CDS_PINID='B';
NODE_NAME     S9A1 3
 '@BASEBOARD_FAB2_LIB.BASEBOARD_FAB2(SCH_1):PAGE175_I78@MSTR_MISC.SWITCH_D37771002(CHIPS)':
 'PIN3': CDS_PINID='PIN3';
NODE_NAME     S9A1 4
 '@BASEBOARD_FAB2_LIB.BASEBOARD_FAB2(SCH_1):PAGE175_I78@MSTR_MISC.SWITCH_D37771002(CHIPS)':
 'PIN4': CDS_PINID='PIN4';
NODE_NAME     J9B1 4
 '@BASEBOARD_FAB2_LIB.BASEBOARD_FAB2(SCH_1):PAGE176_I69@MSTR_CONN.CONN9_H51826001(CHIPS)':
 'GND': CDS_PINID='GND';
NODE_NAME     J9B1 MH1
 '@BASEBOARD_FAB2_LIB.BASEBOARD_FAB2(SCH_1):PAGE176_I69@MSTR_CONN.CONN9_H51826001(CHIPS)':
 'MH1': CDS_PINID='MH1';
NODE_NAME     J9B1 MH2
 '@BASEBOARD_FAB2_LIB.BASEBOARD_FAB2(SCH_1):PAGE176_I69@MSTR_CONN.CONN9_H51826001(CHIPS)':
 'MH2': CDS_PINID='MH2';
NODE_NAME     J9B1 MH3
 '@BASEBOARD_FAB2_LIB.BASEBOARD_FAB2(SCH_1):PAGE176_I69@MSTR_CONN.CONN9_H51826001(CHIPS)':
 'MH3': CDS_PINID='MH3';
NODE_NAME     J9B1 MH4
 '@BASEBOARD_FAB2_LIB.BASEBOARD_FAB2(SCH_1):PAGE176_I69@MSTR_CONN.CONN9_H51826001(CHIPS)':
 'MH4': CDS_PINID='MH4';
NODE_NAME     CR1M2 3
 '@BASEBOARD_FAB2_LIB.BASEBOARD_FAB2(SCH_1):PAGE176_I98@MSTR_DISCRETE.DIODEAC_DUAL_ARRAY(CHIPS)':
 'GND'<0>: CDS_PINID='GND(0)';
NODE_NAME     U1M3 2
 '@BASEBOARD_FAB2_LIB.BASEBOARD_FAB2(SCH_1):PAGE176_I100@MSTR_VREG.TPS2061(CHIPS)':
 'GND': CDS_PINID='GND';
NODE_NAME     C1M38 2
 '@BASEBOARD_FAB2_LIB.BASEBOARD_FAB2(SCH_1):PAGE176_I108@DEV_DISCRETE.CAP_A(CHIPS)':
 'B': CDS_PINID='B';
NODE_NAME     R1M25 2
 '@BASEBOARD_FAB2_LIB.BASEBOARD_FAB2(SCH_1):PAGE176_I111@MSTR_DISCRETE.RES(CHIPS)':
 'B': CDS_PINID='B';
NODE_NAME     C9B8 2
 '@BASEBOARD_FAB2_LIB.BASEBOARD_FAB2(SCH_1):PAGE176_I113@MSTR_DISCRETE.CAPP(CHIPS)':
 'B': CDS_PINID='B';
NODE_NAME     C1M3 2
 '@BASEBOARD_FAB2_LIB.BASEBOARD_FAB2(SCH_1):PAGE177_I20@DEV_DISCRETE.CAP_A(CHIPS)':
 'B': CDS_PINID='B';
NODE_NAME     DS9A6 2
 '@BASEBOARD_FAB2_LIB.BASEBOARD_FAB2(SCH_1):PAGE177_I31@MSTR_DISCRETE.LED(CHIPS)':
 'C': CDS_PINID='C';
NODE_NAME     Q9F1 4
 '@BASEBOARD_FAB2_LIB.BASEBOARD_FAB2(SCH_1):PAGE177_I79@MSTR_DISCRETE.FET_N_DUAL(CHIPS)':
 'SOURCE'<0>: CDS_PINID='SOURCE(0)';
NODE_NAME     Q9F1 1
 '@BASEBOARD_FAB2_LIB.BASEBOARD_FAB2(SCH_1):PAGE177_I80@MSTR_DISCRETE.FET_N_DUAL(CHIPS)':
 'SOURCE'<0>: CDS_PINID='SOURCE(0)';
NODE_NAME     J8E1 11
 '@BASEBOARD_FAB2_LIB.BASEBOARD_FAB2(SCH_1):PAGE184_I87@MSTR_SCONN.SCONN11_H67026001(CHIPS)':
 'IO11': CDS_PINID='IO11';
NODE_NAME     J8E1 MP1
 '@BASEBOARD_FAB2_LIB.BASEBOARD_FAB2(SCH_1):PAGE184_I87@MSTR_SCONN.SCONN11_H67026001(CHIPS)':
 'MP1': CDS_PINID='MP1';
NODE_NAME     J8E1 MP2
 '@BASEBOARD_FAB2_LIB.BASEBOARD_FAB2(SCH_1):PAGE184_I87@MSTR_SCONN.SCONN11_H67026001(CHIPS)':
 'MP2': CDS_PINID='MP2';
NODE_NAME     RM8D1 1
 '@BASEBOARD_FAB2_LIB.BASEBOARD_FAB2(SCH_1):PAGE184_I104@MSTR_MISC.STANDOFF(CHIPS)':
 'IO1': CDS_PINID='IO1';
NODE_NAME     C2P9 2
 '@BASEBOARD_FAB2_LIB.BASEBOARD_FAB2(SCH_1):PAGE185_I117@DEV_DISCRETE.CAP_A(CHIPS)':
 'B': CDS_PINID='B';
NODE_NAME     C2T29 2
 '@BASEBOARD_FAB2_LIB.BASEBOARD_FAB2(SCH_1):PAGE185_I120@DEV_DISCRETE.CAP_A(CHIPS)':
 'B': CDS_PINID='B';
NODE_NAME     C2T26 2
 '@BASEBOARD_FAB2_LIB.BASEBOARD_FAB2(SCH_1):PAGE185_I123@DEV_DISCRETE.CAP_A(CHIPS)':
 'B': CDS_PINID='B';
NODE_NAME     C2T21 2
 '@BASEBOARD_FAB2_LIB.BASEBOARD_FAB2(SCH_1):PAGE185_I124@DEV_DISCRETE.CAP_A(CHIPS)':
 'B': CDS_PINID='B';
NODE_NAME     C2T16 2
 '@BASEBOARD_FAB2_LIB.BASEBOARD_FAB2(SCH_1):PAGE185_I126@DEV_DISCRETE.CAP_A(CHIPS)':
 'B': CDS_PINID='B';
NODE_NAME     C2T15 2
 '@BASEBOARD_FAB2_LIB.BASEBOARD_FAB2(SCH_1):PAGE185_I127@DEV_DISCRETE.CAP_A(CHIPS)':
 'B': CDS_PINID='B';
NODE_NAME     C2T24 2
 '@BASEBOARD_FAB2_LIB.BASEBOARD_FAB2(SCH_1):PAGE185_I129@DEV_DISCRETE.CAP_A(CHIPS)':
 'B': CDS_PINID='B';
NODE_NAME     C2T2 2
 '@BASEBOARD_FAB2_LIB.BASEBOARD_FAB2(SCH_1):PAGE185_I131@DEV_DISCRETE.CAP_A(CHIPS)':
 'B': CDS_PINID='B';
NODE_NAME     C2T4 2
 '@BASEBOARD_FAB2_LIB.BASEBOARD_FAB2(SCH_1):PAGE185_I132@DEV_DISCRETE.CAP_A(CHIPS)':
 'B': CDS_PINID='B';
NODE_NAME     C2T5 2
 '@BASEBOARD_FAB2_LIB.BASEBOARD_FAB2(SCH_1):PAGE185_I135@DEV_DISCRETE.CAP_A(CHIPS)':
 'B': CDS_PINID='B';
NODE_NAME     C1M27 2
 '@BASEBOARD_FAB2_LIB.BASEBOARD_FAB2(SCH_1):PAGE186_I3@MSTR_DISCRETE.CAP(CHIPS)':
 'B': CDS_PINID='B';
NODE_NAME     C1M26 2
 '@BASEBOARD_FAB2_LIB.BASEBOARD_FAB2(SCH_1):PAGE186_I6@MSTR_DISCRETE.CAP(CHIPS)':
 'B': CDS_PINID='B';
NODE_NAME     C1M23 2
 '@BASEBOARD_FAB2_LIB.BASEBOARD_FAB2(SCH_1):PAGE186_I7@DEV_DISCRETE.CAP_A(CHIPS)':
 'B': CDS_PINID='B';
NODE_NAME     C1M22 2
 '@BASEBOARD_FAB2_LIB.BASEBOARD_FAB2(SCH_1):PAGE186_I8@DEV_DISCRETE.CAP_A(CHIPS)':
 'B': CDS_PINID='B';
NODE_NAME     C1M24 2
 '@BASEBOARD_FAB2_LIB.BASEBOARD_FAB2(SCH_1):PAGE186_I10@DEV_DISCRETE.CAP_A(CHIPS)':
 'B': CDS_PINID='B';
NODE_NAME     C1M20 2
 '@BASEBOARD_FAB2_LIB.BASEBOARD_FAB2(SCH_1):PAGE186_I270@DEV_DISCRETE.CAP_A(CHIPS)':
 'B': CDS_PINID='B';
NODE_NAME     C1M21 2
 '@BASEBOARD_FAB2_LIB.BASEBOARD_FAB2(SCH_1):PAGE186_I334@DEV_DISCRETE.CAP_A(CHIPS)':
 'B': CDS_PINID='B';
NODE_NAME     C1M25 2
 '@BASEBOARD_FAB2_LIB.BASEBOARD_FAB2(SCH_1):PAGE186_I335@DEV_DISCRETE.CAP_A(CHIPS)':
 'B': CDS_PINID='B';
NODE_NAME     J9B3 8
 '@BASEBOARD_FAB2_LIB.BASEBOARD_FAB2(SCH_1):PAGE186_I336@MSTR_SCONN.SCONN120_A28699018(CHIPS)':
 'IO8': CDS_PINID='IO8';
NODE_NAME     J9B3 9
 '@BASEBOARD_FAB2_LIB.BASEBOARD_FAB2(SCH_1):PAGE186_I336@MSTR_SCONN.SCONN120_A28699018(CHIPS)':
 'IO9': CDS_PINID='IO9';
NODE_NAME     J9B3 10
 '@BASEBOARD_FAB2_LIB.BASEBOARD_FAB2(SCH_1):PAGE186_I336@MSTR_SCONN.SCONN120_A28699018(CHIPS)':
 'IO10': CDS_PINID='IO10';
NODE_NAME     J9B3 11
 '@BASEBOARD_FAB2_LIB.BASEBOARD_FAB2(SCH_1):PAGE186_I336@MSTR_SCONN.SCONN120_A28699018(CHIPS)':
 'IO11': CDS_PINID='IO11';
NODE_NAME     J9B3 14
 '@BASEBOARD_FAB2_LIB.BASEBOARD_FAB2(SCH_1):PAGE186_I336@MSTR_SCONN.SCONN120_A28699018(CHIPS)':
 'IO14': CDS_PINID='IO14';
NODE_NAME     J9B3 15
 '@BASEBOARD_FAB2_LIB.BASEBOARD_FAB2(SCH_1):PAGE186_I336@MSTR_SCONN.SCONN120_A28699018(CHIPS)':
 'IO15': CDS_PINID='IO15';
NODE_NAME     J9B3 16
 '@BASEBOARD_FAB2_LIB.BASEBOARD_FAB2(SCH_1):PAGE186_I336@MSTR_SCONN.SCONN120_A28699018(CHIPS)':
 'IO16': CDS_PINID='IO16';
NODE_NAME     J9B3 17
 '@BASEBOARD_FAB2_LIB.BASEBOARD_FAB2(SCH_1):PAGE186_I336@MSTR_SCONN.SCONN120_A28699018(CHIPS)':
 'IO17': CDS_PINID='IO17';
NODE_NAME     J9B3 26
 '@BASEBOARD_FAB2_LIB.BASEBOARD_FAB2(SCH_1):PAGE186_I336@MSTR_SCONN.SCONN120_A28699018(CHIPS)':
 'IO26': CDS_PINID='IO26';
NODE_NAME     J9B3 38
 '@BASEBOARD_FAB2_LIB.BASEBOARD_FAB2(SCH_1):PAGE186_I336@MSTR_SCONN.SCONN120_A28699018(CHIPS)':
 'IO38': CDS_PINID='IO38';
NODE_NAME     J9B3 39
 '@BASEBOARD_FAB2_LIB.BASEBOARD_FAB2(SCH_1):PAGE186_I336@MSTR_SCONN.SCONN120_A28699018(CHIPS)':
 'IO39': CDS_PINID='IO39';
NODE_NAME     J9B3 41
 '@BASEBOARD_FAB2_LIB.BASEBOARD_FAB2(SCH_1):PAGE186_I336@MSTR_SCONN.SCONN120_A28699018(CHIPS)':
 'IO41': CDS_PINID='IO41';
NODE_NAME     J9B3 44
 '@BASEBOARD_FAB2_LIB.BASEBOARD_FAB2(SCH_1):PAGE186_I336@MSTR_SCONN.SCONN120_A28699018(CHIPS)':
 'IO44': CDS_PINID='IO44';
NODE_NAME     J9B3 46
 '@BASEBOARD_FAB2_LIB.BASEBOARD_FAB2(SCH_1):PAGE186_I336@MSTR_SCONN.SCONN120_A28699018(CHIPS)':
 'IO46': CDS_PINID='IO46';
NODE_NAME     J9B3 47
 '@BASEBOARD_FAB2_LIB.BASEBOARD_FAB2(SCH_1):PAGE186_I336@MSTR_SCONN.SCONN120_A28699018(CHIPS)':
 'IO47': CDS_PINID='IO47';
NODE_NAME     J9B3 49
 '@BASEBOARD_FAB2_LIB.BASEBOARD_FAB2(SCH_1):PAGE186_I336@MSTR_SCONN.SCONN120_A28699018(CHIPS)':
 'IO49': CDS_PINID='IO49';
NODE_NAME     J9B3 52
 '@BASEBOARD_FAB2_LIB.BASEBOARD_FAB2(SCH_1):PAGE186_I336@MSTR_SCONN.SCONN120_A28699018(CHIPS)':
 'IO52': CDS_PINID='IO52';
NODE_NAME     J9B3 54
 '@BASEBOARD_FAB2_LIB.BASEBOARD_FAB2(SCH_1):PAGE186_I336@MSTR_SCONN.SCONN120_A28699018(CHIPS)':
 'IO54': CDS_PINID='IO54';
NODE_NAME     J9B3 55
 '@BASEBOARD_FAB2_LIB.BASEBOARD_FAB2(SCH_1):PAGE186_I336@MSTR_SCONN.SCONN120_A28699018(CHIPS)':
 'IO55': CDS_PINID='IO55';
NODE_NAME     J9B3 57
 '@BASEBOARD_FAB2_LIB.BASEBOARD_FAB2(SCH_1):PAGE186_I336@MSTR_SCONN.SCONN120_A28699018(CHIPS)':
 'IO57': CDS_PINID='IO57';
NODE_NAME     J9B3 60
 '@BASEBOARD_FAB2_LIB.BASEBOARD_FAB2(SCH_1):PAGE186_I336@MSTR_SCONN.SCONN120_A28699018(CHIPS)':
 'IO60': CDS_PINID='IO60';
NODE_NAME     J9B3 62
 '@BASEBOARD_FAB2_LIB.BASEBOARD_FAB2(SCH_1):PAGE186_I336@MSTR_SCONN.SCONN120_A28699018(CHIPS)':
 'IO62': CDS_PINID='IO62';
NODE_NAME     J9B3 63
 '@BASEBOARD_FAB2_LIB.BASEBOARD_FAB2(SCH_1):PAGE186_I336@MSTR_SCONN.SCONN120_A28699018(CHIPS)':
 'IO63': CDS_PINID='IO63';
NODE_NAME     J9B3 65
 '@BASEBOARD_FAB2_LIB.BASEBOARD_FAB2(SCH_1):PAGE186_I336@MSTR_SCONN.SCONN120_A28699018(CHIPS)':
 'IO65': CDS_PINID='IO65';
NODE_NAME     J9B3 68
 '@BASEBOARD_FAB2_LIB.BASEBOARD_FAB2(SCH_1):PAGE186_I336@MSTR_SCONN.SCONN120_A28699018(CHIPS)':
 'IO68': CDS_PINID='IO68';
NODE_NAME     J9B3 70
 '@BASEBOARD_FAB2_LIB.BASEBOARD_FAB2(SCH_1):PAGE186_I336@MSTR_SCONN.SCONN120_A28699018(CHIPS)':
 'IO70': CDS_PINID='IO70';
NODE_NAME     J9B3 71
 '@BASEBOARD_FAB2_LIB.BASEBOARD_FAB2(SCH_1):PAGE186_I336@MSTR_SCONN.SCONN120_A28699018(CHIPS)':
 'IO71': CDS_PINID='IO71';
NODE_NAME     J9B3 73
 '@BASEBOARD_FAB2_LIB.BASEBOARD_FAB2(SCH_1):PAGE186_I336@MSTR_SCONN.SCONN120_A28699018(CHIPS)':
 'IO73': CDS_PINID='IO73';
NODE_NAME     J9B3 76
 '@BASEBOARD_FAB2_LIB.BASEBOARD_FAB2(SCH_1):PAGE186_I336@MSTR_SCONN.SCONN120_A28699018(CHIPS)':
 'IO76': CDS_PINID='IO76';
NODE_NAME     J9B3 78
 '@BASEBOARD_FAB2_LIB.BASEBOARD_FAB2(SCH_1):PAGE186_I336@MSTR_SCONN.SCONN120_A28699018(CHIPS)':
 'IO78': CDS_PINID='IO78';
NODE_NAME     J9B3 79
 '@BASEBOARD_FAB2_LIB.BASEBOARD_FAB2(SCH_1):PAGE186_I336@MSTR_SCONN.SCONN120_A28699018(CHIPS)':
 'IO79': CDS_PINID='IO79';
NODE_NAME     J9B3 81
 '@BASEBOARD_FAB2_LIB.BASEBOARD_FAB2(SCH_1):PAGE186_I336@MSTR_SCONN.SCONN120_A28699018(CHIPS)':
 'IO81': CDS_PINID='IO81';
NODE_NAME     J9B3 84
 '@BASEBOARD_FAB2_LIB.BASEBOARD_FAB2(SCH_1):PAGE186_I336@MSTR_SCONN.SCONN120_A28699018(CHIPS)':
 'IO84': CDS_PINID='IO84';
NODE_NAME     J9B3 86
 '@BASEBOARD_FAB2_LIB.BASEBOARD_FAB2(SCH_1):PAGE186_I336@MSTR_SCONN.SCONN120_A28699018(CHIPS)':
 'IO86': CDS_PINID='IO86';
NODE_NAME     J9B3 87
 '@BASEBOARD_FAB2_LIB.BASEBOARD_FAB2(SCH_1):PAGE186_I336@MSTR_SCONN.SCONN120_A28699018(CHIPS)':
 'IO87': CDS_PINID='IO87';
NODE_NAME     J9B3 89
 '@BASEBOARD_FAB2_LIB.BASEBOARD_FAB2(SCH_1):PAGE186_I336@MSTR_SCONN.SCONN120_A28699018(CHIPS)':
 'IO89': CDS_PINID='IO89';
NODE_NAME     J9B3 92
 '@BASEBOARD_FAB2_LIB.BASEBOARD_FAB2(SCH_1):PAGE186_I336@MSTR_SCONN.SCONN120_A28699018(CHIPS)':
 'IO92': CDS_PINID='IO92';
NODE_NAME     J9B3 94
 '@BASEBOARD_FAB2_LIB.BASEBOARD_FAB2(SCH_1):PAGE186_I336@MSTR_SCONN.SCONN120_A28699018(CHIPS)':
 'IO94': CDS_PINID='IO94';
NODE_NAME     J9B3 95
 '@BASEBOARD_FAB2_LIB.BASEBOARD_FAB2(SCH_1):PAGE186_I336@MSTR_SCONN.SCONN120_A28699018(CHIPS)':
 'IO95': CDS_PINID='IO95';
NODE_NAME     J9B3 97
 '@BASEBOARD_FAB2_LIB.BASEBOARD_FAB2(SCH_1):PAGE186_I336@MSTR_SCONN.SCONN120_A28699018(CHIPS)':
 'IO97': CDS_PINID='IO97';
NODE_NAME     J9B3 100
 '@BASEBOARD_FAB2_LIB.BASEBOARD_FAB2(SCH_1):PAGE186_I336@MSTR_SCONN.SCONN120_A28699018(CHIPS)':
 'IO100': CDS_PINID='IO100';
NODE_NAME     J9B3 102
 '@BASEBOARD_FAB2_LIB.BASEBOARD_FAB2(SCH_1):PAGE186_I336@MSTR_SCONN.SCONN120_A28699018(CHIPS)':
 'IO102': CDS_PINID='IO102';
NODE_NAME     J9B3 103
 '@BASEBOARD_FAB2_LIB.BASEBOARD_FAB2(SCH_1):PAGE186_I336@MSTR_SCONN.SCONN120_A28699018(CHIPS)':
 'IO103': CDS_PINID='IO103';
NODE_NAME     J9B3 105
 '@BASEBOARD_FAB2_LIB.BASEBOARD_FAB2(SCH_1):PAGE186_I336@MSTR_SCONN.SCONN120_A28699018(CHIPS)':
 'IO105': CDS_PINID='IO105';
NODE_NAME     J9B3 108
 '@BASEBOARD_FAB2_LIB.BASEBOARD_FAB2(SCH_1):PAGE186_I336@MSTR_SCONN.SCONN120_A28699018(CHIPS)':
 'IO108': CDS_PINID='IO108';
NODE_NAME     J9B3 110
 '@BASEBOARD_FAB2_LIB.BASEBOARD_FAB2(SCH_1):PAGE186_I336@MSTR_SCONN.SCONN120_A28699018(CHIPS)':
 'IO110': CDS_PINID='IO110';
NODE_NAME     J9B3 111
 '@BASEBOARD_FAB2_LIB.BASEBOARD_FAB2(SCH_1):PAGE186_I336@MSTR_SCONN.SCONN120_A28699018(CHIPS)':
 'IO111': CDS_PINID='IO111';
NODE_NAME     J9B3 113
 '@BASEBOARD_FAB2_LIB.BASEBOARD_FAB2(SCH_1):PAGE186_I336@MSTR_SCONN.SCONN120_A28699018(CHIPS)':
 'IO113': CDS_PINID='IO113';
NODE_NAME     J9B3 116
 '@BASEBOARD_FAB2_LIB.BASEBOARD_FAB2(SCH_1):PAGE186_I336@MSTR_SCONN.SCONN120_A28699018(CHIPS)':
 'IO116': CDS_PINID='IO116';
NODE_NAME     J9B3 118
 '@BASEBOARD_FAB2_LIB.BASEBOARD_FAB2(SCH_1):PAGE186_I336@MSTR_SCONN.SCONN120_A28699018(CHIPS)':
 'IO118': CDS_PINID='IO118';
NODE_NAME     J9B3 119
 '@BASEBOARD_FAB2_LIB.BASEBOARD_FAB2(SCH_1):PAGE186_I336@MSTR_SCONN.SCONN120_A28699018(CHIPS)':
 'IO119': CDS_PINID='IO119';
NODE_NAME     C9B10 2
 '@BASEBOARD_FAB2_LIB.BASEBOARD_FAB2(SCH_1):PAGE186_I345@DEV_DISCRETE.CAP_A(CHIPS)':
 'B': CDS_PINID='B';
NODE_NAME     J8E3 3
 '@BASEBOARD_FAB2_LIB.BASEBOARD_FAB2(SCH_1):PAGE187_I119@MSTR_SCONN.SCONN80_E67482007(CHIPS)':
 'IO3': CDS_PINID='IO3';
NODE_NAME     J8E3 8
 '@BASEBOARD_FAB2_LIB.BASEBOARD_FAB2(SCH_1):PAGE187_I119@MSTR_SCONN.SCONN80_E67482007(CHIPS)':
 'IO8': CDS_PINID='IO8';
NODE_NAME     J8E3 9
 '@BASEBOARD_FAB2_LIB.BASEBOARD_FAB2(SCH_1):PAGE187_I119@MSTR_SCONN.SCONN80_E67482007(CHIPS)':
 'IO9': CDS_PINID='IO9';
NODE_NAME     J8E3 11
 '@BASEBOARD_FAB2_LIB.BASEBOARD_FAB2(SCH_1):PAGE187_I119@MSTR_SCONN.SCONN80_E67482007(CHIPS)':
 'IO11': CDS_PINID='IO11';
NODE_NAME     J8E3 14
 '@BASEBOARD_FAB2_LIB.BASEBOARD_FAB2(SCH_1):PAGE187_I119@MSTR_SCONN.SCONN80_E67482007(CHIPS)':
 'IO14': CDS_PINID='IO14';
NODE_NAME     J8E3 16
 '@BASEBOARD_FAB2_LIB.BASEBOARD_FAB2(SCH_1):PAGE187_I119@MSTR_SCONN.SCONN80_E67482007(CHIPS)':
 'IO16': CDS_PINID='IO16';
NODE_NAME     J8E3 17
 '@BASEBOARD_FAB2_LIB.BASEBOARD_FAB2(SCH_1):PAGE187_I119@MSTR_SCONN.SCONN80_E67482007(CHIPS)':
 'IO17': CDS_PINID='IO17';
NODE_NAME     J8E3 19
 '@BASEBOARD_FAB2_LIB.BASEBOARD_FAB2(SCH_1):PAGE187_I119@MSTR_SCONN.SCONN80_E67482007(CHIPS)':
 'IO19': CDS_PINID='IO19';
NODE_NAME     J8E3 22
 '@BASEBOARD_FAB2_LIB.BASEBOARD_FAB2(SCH_1):PAGE187_I119@MSTR_SCONN.SCONN80_E67482007(CHIPS)':
 'IO22': CDS_PINID='IO22';
NODE_NAME     J8E3 24
 '@BASEBOARD_FAB2_LIB.BASEBOARD_FAB2(SCH_1):PAGE187_I119@MSTR_SCONN.SCONN80_E67482007(CHIPS)':
 'IO24': CDS_PINID='IO24';
NODE_NAME     J8E3 25
 '@BASEBOARD_FAB2_LIB.BASEBOARD_FAB2(SCH_1):PAGE187_I119@MSTR_SCONN.SCONN80_E67482007(CHIPS)':
 'IO25': CDS_PINID='IO25';
NODE_NAME     J8E3 27
 '@BASEBOARD_FAB2_LIB.BASEBOARD_FAB2(SCH_1):PAGE187_I119@MSTR_SCONN.SCONN80_E67482007(CHIPS)':
 'IO27': CDS_PINID='IO27';
NODE_NAME     J8E3 30
 '@BASEBOARD_FAB2_LIB.BASEBOARD_FAB2(SCH_1):PAGE187_I119@MSTR_SCONN.SCONN80_E67482007(CHIPS)':
 'IO30': CDS_PINID='IO30';
NODE_NAME     J8E3 32
 '@BASEBOARD_FAB2_LIB.BASEBOARD_FAB2(SCH_1):PAGE187_I119@MSTR_SCONN.SCONN80_E67482007(CHIPS)':
 'IO32': CDS_PINID='IO32';
NODE_NAME     J8E3 33
 '@BASEBOARD_FAB2_LIB.BASEBOARD_FAB2(SCH_1):PAGE187_I119@MSTR_SCONN.SCONN80_E67482007(CHIPS)':
 'IO33': CDS_PINID='IO33';
NODE_NAME     J8E3 35
 '@BASEBOARD_FAB2_LIB.BASEBOARD_FAB2(SCH_1):PAGE187_I119@MSTR_SCONN.SCONN80_E67482007(CHIPS)':
 'IO35': CDS_PINID='IO35';
NODE_NAME     J8E3 38
 '@BASEBOARD_FAB2_LIB.BASEBOARD_FAB2(SCH_1):PAGE187_I119@MSTR_SCONN.SCONN80_E67482007(CHIPS)':
 'IO38': CDS_PINID='IO38';
NODE_NAME     J8E3 40
 '@BASEBOARD_FAB2_LIB.BASEBOARD_FAB2(SCH_1):PAGE187_I119@MSTR_SCONN.SCONN80_E67482007(CHIPS)':
 'IO40': CDS_PINID='IO40';
NODE_NAME     J8E3 41
 '@BASEBOARD_FAB2_LIB.BASEBOARD_FAB2(SCH_1):PAGE187_I119@MSTR_SCONN.SCONN80_E67482007(CHIPS)':
 'IO41': CDS_PINID='IO41';
NODE_NAME     J8E3 43
 '@BASEBOARD_FAB2_LIB.BASEBOARD_FAB2(SCH_1):PAGE187_I119@MSTR_SCONN.SCONN80_E67482007(CHIPS)':
 'IO43': CDS_PINID='IO43';
NODE_NAME     J8E3 46
 '@BASEBOARD_FAB2_LIB.BASEBOARD_FAB2(SCH_1):PAGE187_I119@MSTR_SCONN.SCONN80_E67482007(CHIPS)':
 'IO46': CDS_PINID='IO46';
NODE_NAME     J8E3 48
 '@BASEBOARD_FAB2_LIB.BASEBOARD_FAB2(SCH_1):PAGE187_I119@MSTR_SCONN.SCONN80_E67482007(CHIPS)':
 'IO48': CDS_PINID='IO48';
NODE_NAME     J8E3 49
 '@BASEBOARD_FAB2_LIB.BASEBOARD_FAB2(SCH_1):PAGE187_I119@MSTR_SCONN.SCONN80_E67482007(CHIPS)':
 'IO49': CDS_PINID='IO49';
NODE_NAME     J8E3 51
 '@BASEBOARD_FAB2_LIB.BASEBOARD_FAB2(SCH_1):PAGE187_I119@MSTR_SCONN.SCONN80_E67482007(CHIPS)':
 'IO51': CDS_PINID='IO51';
NODE_NAME     J8E3 54
 '@BASEBOARD_FAB2_LIB.BASEBOARD_FAB2(SCH_1):PAGE187_I119@MSTR_SCONN.SCONN80_E67482007(CHIPS)':
 'IO54': CDS_PINID='IO54';
NODE_NAME     J8E3 56
 '@BASEBOARD_FAB2_LIB.BASEBOARD_FAB2(SCH_1):PAGE187_I119@MSTR_SCONN.SCONN80_E67482007(CHIPS)':
 'IO56': CDS_PINID='IO56';
NODE_NAME     J8E3 57
 '@BASEBOARD_FAB2_LIB.BASEBOARD_FAB2(SCH_1):PAGE187_I119@MSTR_SCONN.SCONN80_E67482007(CHIPS)':
 'IO57': CDS_PINID='IO57';
NODE_NAME     J8E3 59
 '@BASEBOARD_FAB2_LIB.BASEBOARD_FAB2(SCH_1):PAGE187_I119@MSTR_SCONN.SCONN80_E67482007(CHIPS)':
 'IO59': CDS_PINID='IO59';
NODE_NAME     J8E3 62
 '@BASEBOARD_FAB2_LIB.BASEBOARD_FAB2(SCH_1):PAGE187_I119@MSTR_SCONN.SCONN80_E67482007(CHIPS)':
 'IO62': CDS_PINID='IO62';
NODE_NAME     J8E3 64
 '@BASEBOARD_FAB2_LIB.BASEBOARD_FAB2(SCH_1):PAGE187_I119@MSTR_SCONN.SCONN80_E67482007(CHIPS)':
 'IO64': CDS_PINID='IO64';
NODE_NAME     J8E3 65
 '@BASEBOARD_FAB2_LIB.BASEBOARD_FAB2(SCH_1):PAGE187_I119@MSTR_SCONN.SCONN80_E67482007(CHIPS)':
 'IO65': CDS_PINID='IO65';
NODE_NAME     J8E3 67
 '@BASEBOARD_FAB2_LIB.BASEBOARD_FAB2(SCH_1):PAGE187_I119@MSTR_SCONN.SCONN80_E67482007(CHIPS)':
 'IO67': CDS_PINID='IO67';
NODE_NAME     J8E3 70
 '@BASEBOARD_FAB2_LIB.BASEBOARD_FAB2(SCH_1):PAGE187_I119@MSTR_SCONN.SCONN80_E67482007(CHIPS)':
 'IO70': CDS_PINID='IO70';
NODE_NAME     J8E3 72
 '@BASEBOARD_FAB2_LIB.BASEBOARD_FAB2(SCH_1):PAGE187_I119@MSTR_SCONN.SCONN80_E67482007(CHIPS)':
 'IO72': CDS_PINID='IO72';
NODE_NAME     J8E3 73
 '@BASEBOARD_FAB2_LIB.BASEBOARD_FAB2(SCH_1):PAGE187_I119@MSTR_SCONN.SCONN80_E67482007(CHIPS)':
 'IO73': CDS_PINID='IO73';
NODE_NAME     J8E3 78
 '@BASEBOARD_FAB2_LIB.BASEBOARD_FAB2(SCH_1):PAGE187_I119@MSTR_SCONN.SCONN80_E67482007(CHIPS)':
 'IO78': CDS_PINID='IO78';
NODE_NAME     C2R15 2
 '@BASEBOARD_FAB2_LIB.BASEBOARD_FAB2(SCH_1):PAGE188_I2@DEV_DISCRETE.CAP_A(CHIPS)':
 'B': CDS_PINID='B';
NODE_NAME     C2R18 2
 '@BASEBOARD_FAB2_LIB.BASEBOARD_FAB2(SCH_1):PAGE188_I3@DEV_DISCRETE.CAP_A(CHIPS)':
 'B': CDS_PINID='B';
NODE_NAME     C2P11 2
 '@BASEBOARD_FAB2_LIB.BASEBOARD_FAB2(SCH_1):PAGE188_I21@DEV_DISCRETE.CAP_A(CHIPS)':
 'B': CDS_PINID='B';
NODE_NAME     C2P12 2
 '@BASEBOARD_FAB2_LIB.BASEBOARD_FAB2(SCH_1):PAGE188_I23@DEV_DISCRETE.CAP_A(CHIPS)':
 'B': CDS_PINID='B';
NODE_NAME     C2R17 2
 '@BASEBOARD_FAB2_LIB.BASEBOARD_FAB2(SCH_1):PAGE188_I25@DEV_DISCRETE.CAP_A(CHIPS)':
 'B': CDS_PINID='B';
NODE_NAME     J8E4 4
 '@BASEBOARD_FAB2_LIB.BASEBOARD_FAB2(SCH_1):PAGE188_I27@MSTR_SCONN.SCONN64_H87568002_A(CHIPS)':
 'IO4': CDS_PINID='IO4';
NODE_NAME     J8E4 7
 '@BASEBOARD_FAB2_LIB.BASEBOARD_FAB2(SCH_1):PAGE188_I27@MSTR_SCONN.SCONN64_H87568002_A(CHIPS)':
 'IO7': CDS_PINID='IO7';
NODE_NAME     J8E4 10
 '@BASEBOARD_FAB2_LIB.BASEBOARD_FAB2(SCH_1):PAGE188_I27@MSTR_SCONN.SCONN64_H87568002_A(CHIPS)':
 'IO10': CDS_PINID='IO10';
NODE_NAME     J8E4 13
 '@BASEBOARD_FAB2_LIB.BASEBOARD_FAB2(SCH_1):PAGE188_I27@MSTR_SCONN.SCONN64_H87568002_A(CHIPS)':
 'IO13': CDS_PINID='IO13';
NODE_NAME     J8E4 16
 '@BASEBOARD_FAB2_LIB.BASEBOARD_FAB2(SCH_1):PAGE188_I27@MSTR_SCONN.SCONN64_H87568002_A(CHIPS)':
 'IO16': CDS_PINID='IO16';
NODE_NAME     J8E4 19
 '@BASEBOARD_FAB2_LIB.BASEBOARD_FAB2(SCH_1):PAGE188_I27@MSTR_SCONN.SCONN64_H87568002_A(CHIPS)':
 'IO19': CDS_PINID='IO19';
NODE_NAME     J8E4 22
 '@BASEBOARD_FAB2_LIB.BASEBOARD_FAB2(SCH_1):PAGE188_I27@MSTR_SCONN.SCONN64_H87568002_A(CHIPS)':
 'IO22': CDS_PINID='IO22';
NODE_NAME     J8E4 25
 '@BASEBOARD_FAB2_LIB.BASEBOARD_FAB2(SCH_1):PAGE188_I27@MSTR_SCONN.SCONN64_H87568002_A(CHIPS)':
 'IO25': CDS_PINID='IO25';
NODE_NAME     J8E4 28
 '@BASEBOARD_FAB2_LIB.BASEBOARD_FAB2(SCH_1):PAGE188_I27@MSTR_SCONN.SCONN64_H87568002_A(CHIPS)':
 'IO28': CDS_PINID='IO28';
NODE_NAME     J8E4 39
 '@BASEBOARD_FAB2_LIB.BASEBOARD_FAB2(SCH_1):PAGE188_I27@MSTR_SCONN.SCONN64_H87568002_A(CHIPS)':
 'IO39': CDS_PINID='IO39';
NODE_NAME     J8E4 42
 '@BASEBOARD_FAB2_LIB.BASEBOARD_FAB2(SCH_1):PAGE188_I27@MSTR_SCONN.SCONN64_H87568002_A(CHIPS)':
 'IO42': CDS_PINID='IO42';
NODE_NAME     J8E4 45
 '@BASEBOARD_FAB2_LIB.BASEBOARD_FAB2(SCH_1):PAGE188_I27@MSTR_SCONN.SCONN64_H87568002_A(CHIPS)':
 'IO45': CDS_PINID='IO45';
NODE_NAME     J8E4 48
 '@BASEBOARD_FAB2_LIB.BASEBOARD_FAB2(SCH_1):PAGE188_I27@MSTR_SCONN.SCONN64_H87568002_A(CHIPS)':
 'IO48': CDS_PINID='IO48';
NODE_NAME     J8E4 51
 '@BASEBOARD_FAB2_LIB.BASEBOARD_FAB2(SCH_1):PAGE188_I27@MSTR_SCONN.SCONN64_H87568002_A(CHIPS)':
 'IO51': CDS_PINID='IO51';
NODE_NAME     J8E4 54
 '@BASEBOARD_FAB2_LIB.BASEBOARD_FAB2(SCH_1):PAGE188_I27@MSTR_SCONN.SCONN64_H87568002_A(CHIPS)':
 'IO54': CDS_PINID='IO54';
NODE_NAME     J8E4 57
 '@BASEBOARD_FAB2_LIB.BASEBOARD_FAB2(SCH_1):PAGE188_I27@MSTR_SCONN.SCONN64_H87568002_A(CHIPS)':
 'IO57': CDS_PINID='IO57';
NODE_NAME     J8E4 60
 '@BASEBOARD_FAB2_LIB.BASEBOARD_FAB2(SCH_1):PAGE188_I27@MSTR_SCONN.SCONN64_H87568002_A(CHIPS)':
 'IO60': CDS_PINID='IO60';
NODE_NAME     J8E4 63
 '@BASEBOARD_FAB2_LIB.BASEBOARD_FAB2(SCH_1):PAGE188_I27@MSTR_SCONN.SCONN64_H87568002_A(CHIPS)':
 'IO63': CDS_PINID='IO63';
NODE_NAME     C2R16 2
 '@BASEBOARD_FAB2_LIB.BASEBOARD_FAB2(SCH_1):PAGE188_I40@DEV_DISCRETE.CAP_A(CHIPS)':
 'B': CDS_PINID='B';
NODE_NAME     C2P10 2
 '@BASEBOARD_FAB2_LIB.BASEBOARD_FAB2(SCH_1):PAGE188_I41@MSTR_DISCRETE.CAP(CHIPS)':
 'B': CDS_PINID='B';
NODE_NAME     C2P16 2
 '@BASEBOARD_FAB2_LIB.BASEBOARD_FAB2(SCH_1):PAGE188_I53@DEV_DISCRETE.CAP_A(CHIPS)':
 'B': CDS_PINID='B';
NODE_NAME     C2P15 2
 '@BASEBOARD_FAB2_LIB.BASEBOARD_FAB2(SCH_1):PAGE188_I55@DEV_DISCRETE.CAP_A(CHIPS)':
 'B': CDS_PINID='B';
NODE_NAME     C2P14 2
 '@BASEBOARD_FAB2_LIB.BASEBOARD_FAB2(SCH_1):PAGE188_I56@DEV_DISCRETE.CAP_A(CHIPS)':
 'B': CDS_PINID='B';
NODE_NAME     C2P13 2
 '@BASEBOARD_FAB2_LIB.BASEBOARD_FAB2(SCH_1):PAGE188_I57@DEV_DISCRETE.CAP_A(CHIPS)':
 'B': CDS_PINID='B';
NODE_NAME     R3R11 2
 '@BASEBOARD_FAB2_LIB.BASEBOARD_FAB2(SCH_1):PAGE189_I45@MSTR_DISCRETE.RES(CHIPS)':
 'B': CDS_PINID='B';
NODE_NAME     J7G2 7
 '@BASEBOARD_FAB2_LIB.BASEBOARD_FAB2(SCH_1):PAGE189_I47@MSTR_CONN.CONN8_C77962004(CHIPS)':
 'IO7': CDS_PINID='IO7';
NODE_NAME     R8G23 2
 '@BASEBOARD_FAB2_LIB.BASEBOARD_FAB2(SCH_1):PAGE189_I56@MSTR_DISCRETE.RES(CHIPS)':
 'B': CDS_PINID='B';
NODE_NAME     C2P8 2
 '@BASEBOARD_FAB2_LIB.BASEBOARD_FAB2(SCH_1):PAGE192_I1@DEV_DISCRETE.CAP_A(CHIPS)':
 'B': CDS_PINID='B';
NODE_NAME     C2P5 2
 '@BASEBOARD_FAB2_LIB.BASEBOARD_FAB2(SCH_1):PAGE192_I3@DEV_DISCRETE.CAP_A(CHIPS)':
 'B': CDS_PINID='B';
NODE_NAME     C3R1 2
 '@BASEBOARD_FAB2_LIB.BASEBOARD_FAB2(SCH_1):PAGE192_I4@DEV_DISCRETE.CAP_A(CHIPS)':
 'B': CDS_PINID='B';
NODE_NAME     C3P43 2
 '@BASEBOARD_FAB2_LIB.BASEBOARD_FAB2(SCH_1):PAGE192_I6@DEV_DISCRETE.CAP_A(CHIPS)':
 'B': CDS_PINID='B';
NODE_NAME     C3R3 2
 '@BASEBOARD_FAB2_LIB.BASEBOARD_FAB2(SCH_1):PAGE192_I7@DEV_DISCRETE.CAP_A(CHIPS)':
 'B': CDS_PINID='B';
NODE_NAME     C2R1 2
 '@BASEBOARD_FAB2_LIB.BASEBOARD_FAB2(SCH_1):PAGE192_I8@DEV_DISCRETE.CAP_A(CHIPS)':
 'B': CDS_PINID='B';
NODE_NAME     C2P2 2
 '@BASEBOARD_FAB2_LIB.BASEBOARD_FAB2(SCH_1):PAGE192_I9@DEV_DISCRETE.CAP_A(CHIPS)':
 'B': CDS_PINID='B';
NODE_NAME     C3R2 2
 '@BASEBOARD_FAB2_LIB.BASEBOARD_FAB2(SCH_1):PAGE192_I10@DEV_DISCRETE.CAP_A(CHIPS)':
 'B': CDS_PINID='B';
NODE_NAME     C3P51 2
 '@BASEBOARD_FAB2_LIB.BASEBOARD_FAB2(SCH_1):PAGE192_I11@DEV_DISCRETE.CAP_A(CHIPS)':
 'B': CDS_PINID='B';
NODE_NAME     C3P47 2
 '@BASEBOARD_FAB2_LIB.BASEBOARD_FAB2(SCH_1):PAGE192_I12@DEV_DISCRETE.CAP_A(CHIPS)':
 'B': CDS_PINID='B';
NODE_NAME     U8D7 B2
 '@BASEBOARD_FAB2_LIB.BASEBOARD_FAB2(SCH_1):PAGE192_I14@MSTR_MEMORY.LCMXO2_A(CHIPS)':
 'GND'<0>: CDS_PINID='GND(0)';
NODE_NAME     U8D7 B15
 '@BASEBOARD_FAB2_LIB.BASEBOARD_FAB2(SCH_1):PAGE192_I14@MSTR_MEMORY.LCMXO2_A(CHIPS)':
 'GND'<1>: CDS_PINID='GND(1)';
NODE_NAME     U8D7 C3
 '@BASEBOARD_FAB2_LIB.BASEBOARD_FAB2(SCH_1):PAGE192_I14@MSTR_MEMORY.LCMXO2_A(CHIPS)':
 'GND'<2>: CDS_PINID='GND(2)';
NODE_NAME     U8D7 C14
 '@BASEBOARD_FAB2_LIB.BASEBOARD_FAB2(SCH_1):PAGE192_I14@MSTR_MEMORY.LCMXO2_A(CHIPS)':
 'GND'<3>: CDS_PINID='GND(3)';
NODE_NAME     U8D7 D4
 '@BASEBOARD_FAB2_LIB.BASEBOARD_FAB2(SCH_1):PAGE192_I14@MSTR_MEMORY.LCMXO2_A(CHIPS)':
 'GND'<4>: CDS_PINID='GND(4)';
NODE_NAME     U8D7 D13
 '@BASEBOARD_FAB2_LIB.BASEBOARD_FAB2(SCH_1):PAGE192_I14@MSTR_MEMORY.LCMXO2_A(CHIPS)':
 'GND'<5>: CDS_PINID='GND(5)';
NODE_NAME     U8D7 E5
 '@BASEBOARD_FAB2_LIB.BASEBOARD_FAB2(SCH_1):PAGE192_I14@MSTR_MEMORY.LCMXO2_A(CHIPS)':
 'GND'<6>: CDS_PINID='GND(6)';
NODE_NAME     U8D7 E12
 '@BASEBOARD_FAB2_LIB.BASEBOARD_FAB2(SCH_1):PAGE192_I14@MSTR_MEMORY.LCMXO2_A(CHIPS)':
 'GND'<7>: CDS_PINID='GND(7)';
NODE_NAME     U8D7 F6
 '@BASEBOARD_FAB2_LIB.BASEBOARD_FAB2(SCH_1):PAGE192_I14@MSTR_MEMORY.LCMXO2_A(CHIPS)':
 'GND'<8>: CDS_PINID='GND(8)';
NODE_NAME     U8D7 F11
 '@BASEBOARD_FAB2_LIB.BASEBOARD_FAB2(SCH_1):PAGE192_I14@MSTR_MEMORY.LCMXO2_A(CHIPS)':
 'GND'<9>: CDS_PINID='GND(9)';
NODE_NAME     U8D7 H8
 '@BASEBOARD_FAB2_LIB.BASEBOARD_FAB2(SCH_1):PAGE192_I14@MSTR_MEMORY.LCMXO2_A(CHIPS)':
 'GND'<10>: CDS_PINID='GND(10)';
NODE_NAME     U8D7 H9
 '@BASEBOARD_FAB2_LIB.BASEBOARD_FAB2(SCH_1):PAGE192_I14@MSTR_MEMORY.LCMXO2_A(CHIPS)':
 'GND'<11>: CDS_PINID='GND(11)';
NODE_NAME     U8D7 J8
 '@BASEBOARD_FAB2_LIB.BASEBOARD_FAB2(SCH_1):PAGE192_I14@MSTR_MEMORY.LCMXO2_A(CHIPS)':
 'GND'<12>: CDS_PINID='GND(12)';
NODE_NAME     U8D7 J9
 '@BASEBOARD_FAB2_LIB.BASEBOARD_FAB2(SCH_1):PAGE192_I14@MSTR_MEMORY.LCMXO2_A(CHIPS)':
 'GND'<13>: CDS_PINID='GND(13)';
NODE_NAME     U8D7 L6
 '@BASEBOARD_FAB2_LIB.BASEBOARD_FAB2(SCH_1):PAGE192_I14@MSTR_MEMORY.LCMXO2_A(CHIPS)':
 'GND'<14>: CDS_PINID='GND(14)';
NODE_NAME     U8D7 L11
 '@BASEBOARD_FAB2_LIB.BASEBOARD_FAB2(SCH_1):PAGE192_I14@MSTR_MEMORY.LCMXO2_A(CHIPS)':
 'GND'<15>: CDS_PINID='GND(15)';
NODE_NAME     U8D7 M5
 '@BASEBOARD_FAB2_LIB.BASEBOARD_FAB2(SCH_1):PAGE192_I14@MSTR_MEMORY.LCMXO2_A(CHIPS)':
 'GND'<16>: CDS_PINID='GND(16)';
NODE_NAME     U8D7 M12
 '@BASEBOARD_FAB2_LIB.BASEBOARD_FAB2(SCH_1):PAGE192_I14@MSTR_MEMORY.LCMXO2_A(CHIPS)':
 'GND'<17>: CDS_PINID='GND(17)';
NODE_NAME     U8D7 N4
 '@BASEBOARD_FAB2_LIB.BASEBOARD_FAB2(SCH_1):PAGE192_I14@MSTR_MEMORY.LCMXO2_A(CHIPS)':
 'GND'<18>: CDS_PINID='GND(18)';
NODE_NAME     U8D7 N13
 '@BASEBOARD_FAB2_LIB.BASEBOARD_FAB2(SCH_1):PAGE192_I14@MSTR_MEMORY.LCMXO2_A(CHIPS)':
 'GND'<19>: CDS_PINID='GND(19)';
NODE_NAME     U8D7 P3
 '@BASEBOARD_FAB2_LIB.BASEBOARD_FAB2(SCH_1):PAGE192_I14@MSTR_MEMORY.LCMXO2_A(CHIPS)':
 'GND'<20>: CDS_PINID='GND(20)';
NODE_NAME     U8D7 P14
 '@BASEBOARD_FAB2_LIB.BASEBOARD_FAB2(SCH_1):PAGE192_I14@MSTR_MEMORY.LCMXO2_A(CHIPS)':
 'GND'<21>: CDS_PINID='GND(21)';
NODE_NAME     U8D7 R2
 '@BASEBOARD_FAB2_LIB.BASEBOARD_FAB2(SCH_1):PAGE192_I14@MSTR_MEMORY.LCMXO2_A(CHIPS)':
 'GND'<22>: CDS_PINID='GND(22)';
NODE_NAME     U8D7 R15
 '@BASEBOARD_FAB2_LIB.BASEBOARD_FAB2(SCH_1):PAGE192_I14@MSTR_MEMORY.LCMXO2_A(CHIPS)':
 'GND'<23>: CDS_PINID='GND(23)';
NODE_NAME     C2R5 2
 '@BASEBOARD_FAB2_LIB.BASEBOARD_FAB2(SCH_1):PAGE192_I15@DEV_DISCRETE.CAP_A(CHIPS)':
 'B': CDS_PINID='B';
NODE_NAME     C2P4 2
 '@BASEBOARD_FAB2_LIB.BASEBOARD_FAB2(SCH_1):PAGE192_I16@DEV_DISCRETE.CAP_A(CHIPS)':
 'B': CDS_PINID='B';
NODE_NAME     C3P52 2
 '@BASEBOARD_FAB2_LIB.BASEBOARD_FAB2(SCH_1):PAGE192_I17@DEV_DISCRETE.CAP_A(CHIPS)':
 'B': CDS_PINID='B';
NODE_NAME     C2P6 2
 '@BASEBOARD_FAB2_LIB.BASEBOARD_FAB2(SCH_1):PAGE192_I18@DEV_DISCRETE.CAP_A(CHIPS)':
 'B': CDS_PINID='B';
NODE_NAME     C2R3 2
 '@BASEBOARD_FAB2_LIB.BASEBOARD_FAB2(SCH_1):PAGE192_I19@DEV_DISCRETE.CAP_A(CHIPS)':
 'B': CDS_PINID='B';
NODE_NAME     C2P7 2
 '@BASEBOARD_FAB2_LIB.BASEBOARD_FAB2(SCH_1):PAGE192_I20@DEV_DISCRETE.CAP_A(CHIPS)':
 'B': CDS_PINID='B';
NODE_NAME     C2R4 2
 '@BASEBOARD_FAB2_LIB.BASEBOARD_FAB2(SCH_1):PAGE192_I21@DEV_DISCRETE.CAP_A(CHIPS)':
 'B': CDS_PINID='B';
NODE_NAME     C2P3 2
 '@BASEBOARD_FAB2_LIB.BASEBOARD_FAB2(SCH_1):PAGE192_I22@DEV_DISCRETE.CAP_A(CHIPS)':
 'B': CDS_PINID='B';
NODE_NAME     C3P44 2
 '@BASEBOARD_FAB2_LIB.BASEBOARD_FAB2(SCH_1):PAGE192_I23@DEV_DISCRETE.CAP_A(CHIPS)':
 'B': CDS_PINID='B';
NODE_NAME     C3P48 2
 '@BASEBOARD_FAB2_LIB.BASEBOARD_FAB2(SCH_1):PAGE192_I25@DEV_DISCRETE.CAP_A(CHIPS)':
 'B': CDS_PINID='B';
NODE_NAME     C2R2 2
 '@BASEBOARD_FAB2_LIB.BASEBOARD_FAB2(SCH_1):PAGE192_I28@DEV_DISCRETE.CAP_A(CHIPS)':
 'B': CDS_PINID='B';
NODE_NAME     R7E20 2
 '@BASEBOARD_FAB2_LIB.BASEBOARD_FAB2(SCH_1):PAGE192_I59@MSTR_DISCRETE.RES(CHIPS)':
 'B': CDS_PINID='B';
NODE_NAME     C4C1 2
 '@BASEBOARD_FAB2_LIB.BASEBOARD_FAB2(SCH_1):PAGE193_I29@MSTR_DISCRETE.CAPP(CHIPS)':
 'B': CDS_PINID='B';
NODE_NAME     C3C2 2
 '@BASEBOARD_FAB2_LIB.BASEBOARD_FAB2(SCH_1):PAGE193_I31@DEV_DISCRETE.CAP_A(CHIPS)':
 'B': CDS_PINID='B';
NODE_NAME     C3C1 2
 '@BASEBOARD_FAB2_LIB.BASEBOARD_FAB2(SCH_1):PAGE193_I38@DEV_DISCRETE.CAP_A(CHIPS)':
 'B': CDS_PINID='B';
NODE_NAME     J4E1 A19
 '@BASEBOARD_FAB2_LIB.BASEBOARD_FAB2(SCH_1):PAGE193_I45@MSTR_SCONN.SCONN120_H61426002(CHIPS)':
 'IOA19': CDS_PINID='IOA19';
NODE_NAME     J4E1 A20
 '@BASEBOARD_FAB2_LIB.BASEBOARD_FAB2(SCH_1):PAGE193_I45@MSTR_SCONN.SCONN120_H61426002(CHIPS)':
 'IOA20': CDS_PINID='IOA20';
NODE_NAME     J4E1 B19
 '@BASEBOARD_FAB2_LIB.BASEBOARD_FAB2(SCH_1):PAGE193_I45@MSTR_SCONN.SCONN120_H61426002(CHIPS)':
 'IOB19': CDS_PINID='IOB19';
NODE_NAME     J4E1 B20
 '@BASEBOARD_FAB2_LIB.BASEBOARD_FAB2(SCH_1):PAGE193_I45@MSTR_SCONN.SCONN120_H61426002(CHIPS)':
 'IOB20': CDS_PINID='IOB20';
NODE_NAME     J4E1 C19
 '@BASEBOARD_FAB2_LIB.BASEBOARD_FAB2(SCH_1):PAGE193_I45@MSTR_SCONN.SCONN120_H61426002(CHIPS)':
 'IOC19': CDS_PINID='IOC19';
NODE_NAME     J4E1 C20
 '@BASEBOARD_FAB2_LIB.BASEBOARD_FAB2(SCH_1):PAGE193_I45@MSTR_SCONN.SCONN120_H61426002(CHIPS)':
 'IOC20': CDS_PINID='IOC20';
NODE_NAME     J4E1 D4
 '@BASEBOARD_FAB2_LIB.BASEBOARD_FAB2(SCH_1):PAGE193_I45@MSTR_SCONN.SCONN120_H61426002(CHIPS)':
 'IOD4': CDS_PINID='IOD4';
NODE_NAME     J4E1 D5
 '@BASEBOARD_FAB2_LIB.BASEBOARD_FAB2(SCH_1):PAGE193_I45@MSTR_SCONN.SCONN120_H61426002(CHIPS)':
 'IOD5': CDS_PINID='IOD5';
NODE_NAME     J4E1 D6
 '@BASEBOARD_FAB2_LIB.BASEBOARD_FAB2(SCH_1):PAGE193_I45@MSTR_SCONN.SCONN120_H61426002(CHIPS)':
 'IOD6': CDS_PINID='IOD6';
NODE_NAME     J4E1 D7
 '@BASEBOARD_FAB2_LIB.BASEBOARD_FAB2(SCH_1):PAGE193_I45@MSTR_SCONN.SCONN120_H61426002(CHIPS)':
 'IOD7': CDS_PINID='IOD7';
NODE_NAME     J4E1 D8
 '@BASEBOARD_FAB2_LIB.BASEBOARD_FAB2(SCH_1):PAGE193_I45@MSTR_SCONN.SCONN120_H61426002(CHIPS)':
 'IOD8': CDS_PINID='IOD8';
NODE_NAME     J4E1 D9
 '@BASEBOARD_FAB2_LIB.BASEBOARD_FAB2(SCH_1):PAGE193_I45@MSTR_SCONN.SCONN120_H61426002(CHIPS)':
 'IOD9': CDS_PINID='IOD9';
NODE_NAME     J4E1 D10
 '@BASEBOARD_FAB2_LIB.BASEBOARD_FAB2(SCH_1):PAGE193_I45@MSTR_SCONN.SCONN120_H61426002(CHIPS)':
 'IOD10': CDS_PINID='IOD10';
NODE_NAME     J4E1 D11
 '@BASEBOARD_FAB2_LIB.BASEBOARD_FAB2(SCH_1):PAGE193_I45@MSTR_SCONN.SCONN120_H61426002(CHIPS)':
 'IOD11': CDS_PINID='IOD11';
NODE_NAME     J4E1 D12
 '@BASEBOARD_FAB2_LIB.BASEBOARD_FAB2(SCH_1):PAGE193_I45@MSTR_SCONN.SCONN120_H61426002(CHIPS)':
 'IOD12': CDS_PINID='IOD12';
NODE_NAME     J4E1 D13
 '@BASEBOARD_FAB2_LIB.BASEBOARD_FAB2(SCH_1):PAGE193_I45@MSTR_SCONN.SCONN120_H61426002(CHIPS)':
 'IOD13': CDS_PINID='IOD13';
NODE_NAME     J4E1 D14
 '@BASEBOARD_FAB2_LIB.BASEBOARD_FAB2(SCH_1):PAGE193_I45@MSTR_SCONN.SCONN120_H61426002(CHIPS)':
 'IOD14': CDS_PINID='IOD14';
NODE_NAME     J4E1 D15
 '@BASEBOARD_FAB2_LIB.BASEBOARD_FAB2(SCH_1):PAGE193_I45@MSTR_SCONN.SCONN120_H61426002(CHIPS)':
 'IOD15': CDS_PINID='IOD15';
NODE_NAME     J4E1 D16
 '@BASEBOARD_FAB2_LIB.BASEBOARD_FAB2(SCH_1):PAGE193_I45@MSTR_SCONN.SCONN120_H61426002(CHIPS)':
 'IOD16': CDS_PINID='IOD16';
NODE_NAME     J4E1 D17
 '@BASEBOARD_FAB2_LIB.BASEBOARD_FAB2(SCH_1):PAGE193_I45@MSTR_SCONN.SCONN120_H61426002(CHIPS)':
 'IOD17': CDS_PINID='IOD17';
NODE_NAME     J4E1 D18
 '@BASEBOARD_FAB2_LIB.BASEBOARD_FAB2(SCH_1):PAGE193_I45@MSTR_SCONN.SCONN120_H61426002(CHIPS)':
 'IOD18': CDS_PINID='IOD18';
NODE_NAME     J4E1 D19
 '@BASEBOARD_FAB2_LIB.BASEBOARD_FAB2(SCH_1):PAGE193_I45@MSTR_SCONN.SCONN120_H61426002(CHIPS)':
 'IOD19': CDS_PINID='IOD19';
NODE_NAME     J4E1 D20
 '@BASEBOARD_FAB2_LIB.BASEBOARD_FAB2(SCH_1):PAGE193_I45@MSTR_SCONN.SCONN120_H61426002(CHIPS)':
 'IOD20': CDS_PINID='IOD20';
NODE_NAME     J4E1 E4
 '@BASEBOARD_FAB2_LIB.BASEBOARD_FAB2(SCH_1):PAGE193_I45@MSTR_SCONN.SCONN120_H61426002(CHIPS)':
 'IOE4': CDS_PINID='IOE4';
NODE_NAME     J4E1 E6
 '@BASEBOARD_FAB2_LIB.BASEBOARD_FAB2(SCH_1):PAGE193_I45@MSTR_SCONN.SCONN120_H61426002(CHIPS)':
 'IOE6': CDS_PINID='IOE6';
NODE_NAME     J4E1 E7
 '@BASEBOARD_FAB2_LIB.BASEBOARD_FAB2(SCH_1):PAGE193_I45@MSTR_SCONN.SCONN120_H61426002(CHIPS)':
 'IOE7': CDS_PINID='IOE7';
NODE_NAME     J4E1 E8
 '@BASEBOARD_FAB2_LIB.BASEBOARD_FAB2(SCH_1):PAGE193_I45@MSTR_SCONN.SCONN120_H61426002(CHIPS)':
 'IOE8': CDS_PINID='IOE8';
NODE_NAME     J4E1 E9
 '@BASEBOARD_FAB2_LIB.BASEBOARD_FAB2(SCH_1):PAGE193_I45@MSTR_SCONN.SCONN120_H61426002(CHIPS)':
 'IOE9': CDS_PINID='IOE9';
NODE_NAME     J4E1 E10
 '@BASEBOARD_FAB2_LIB.BASEBOARD_FAB2(SCH_1):PAGE193_I45@MSTR_SCONN.SCONN120_H61426002(CHIPS)':
 'IOE10': CDS_PINID='IOE10';
NODE_NAME     J4E1 E11
 '@BASEBOARD_FAB2_LIB.BASEBOARD_FAB2(SCH_1):PAGE193_I45@MSTR_SCONN.SCONN120_H61426002(CHIPS)':
 'IOE11': CDS_PINID='IOE11';
NODE_NAME     J4E1 E12
 '@BASEBOARD_FAB2_LIB.BASEBOARD_FAB2(SCH_1):PAGE193_I45@MSTR_SCONN.SCONN120_H61426002(CHIPS)':
 'IOE12': CDS_PINID='IOE12';
NODE_NAME     J4E1 E13
 '@BASEBOARD_FAB2_LIB.BASEBOARD_FAB2(SCH_1):PAGE193_I45@MSTR_SCONN.SCONN120_H61426002(CHIPS)':
 'IOE13': CDS_PINID='IOE13';
NODE_NAME     J4E1 E14
 '@BASEBOARD_FAB2_LIB.BASEBOARD_FAB2(SCH_1):PAGE193_I45@MSTR_SCONN.SCONN120_H61426002(CHIPS)':
 'IOE14': CDS_PINID='IOE14';
NODE_NAME     J4E1 E15
 '@BASEBOARD_FAB2_LIB.BASEBOARD_FAB2(SCH_1):PAGE193_I45@MSTR_SCONN.SCONN120_H61426002(CHIPS)':
 'IOE15': CDS_PINID='IOE15';
NODE_NAME     J4E1 E16
 '@BASEBOARD_FAB2_LIB.BASEBOARD_FAB2(SCH_1):PAGE193_I45@MSTR_SCONN.SCONN120_H61426002(CHIPS)':
 'IOE16': CDS_PINID='IOE16';
NODE_NAME     J4E1 E17
 '@BASEBOARD_FAB2_LIB.BASEBOARD_FAB2(SCH_1):PAGE193_I45@MSTR_SCONN.SCONN120_H61426002(CHIPS)':
 'IOE17': CDS_PINID='IOE17';
NODE_NAME     J4E1 E18
 '@BASEBOARD_FAB2_LIB.BASEBOARD_FAB2(SCH_1):PAGE193_I45@MSTR_SCONN.SCONN120_H61426002(CHIPS)':
 'IOE18': CDS_PINID='IOE18';
NODE_NAME     J4E1 E19
 '@BASEBOARD_FAB2_LIB.BASEBOARD_FAB2(SCH_1):PAGE193_I45@MSTR_SCONN.SCONN120_H61426002(CHIPS)':
 'IOE19': CDS_PINID='IOE19';
NODE_NAME     J4E1 E20
 '@BASEBOARD_FAB2_LIB.BASEBOARD_FAB2(SCH_1):PAGE193_I45@MSTR_SCONN.SCONN120_H61426002(CHIPS)':
 'IOE20': CDS_PINID='IOE20';
NODE_NAME     J4E1 F4
 '@BASEBOARD_FAB2_LIB.BASEBOARD_FAB2(SCH_1):PAGE193_I45@MSTR_SCONN.SCONN120_H61426002(CHIPS)':
 'IOF4': CDS_PINID='IOF4';
NODE_NAME     J4E1 F6
 '@BASEBOARD_FAB2_LIB.BASEBOARD_FAB2(SCH_1):PAGE193_I45@MSTR_SCONN.SCONN120_H61426002(CHIPS)':
 'IOF6': CDS_PINID='IOF6';
NODE_NAME     J4E1 F7
 '@BASEBOARD_FAB2_LIB.BASEBOARD_FAB2(SCH_1):PAGE193_I45@MSTR_SCONN.SCONN120_H61426002(CHIPS)':
 'IOF7': CDS_PINID='IOF7';
NODE_NAME     J4E1 F8
 '@BASEBOARD_FAB2_LIB.BASEBOARD_FAB2(SCH_1):PAGE193_I45@MSTR_SCONN.SCONN120_H61426002(CHIPS)':
 'IOF8': CDS_PINID='IOF8';
NODE_NAME     J4E1 F9
 '@BASEBOARD_FAB2_LIB.BASEBOARD_FAB2(SCH_1):PAGE193_I45@MSTR_SCONN.SCONN120_H61426002(CHIPS)':
 'IOF9': CDS_PINID='IOF9';
NODE_NAME     J4E1 F10
 '@BASEBOARD_FAB2_LIB.BASEBOARD_FAB2(SCH_1):PAGE193_I45@MSTR_SCONN.SCONN120_H61426002(CHIPS)':
 'IOF10': CDS_PINID='IOF10';
NODE_NAME     J4E1 F11
 '@BASEBOARD_FAB2_LIB.BASEBOARD_FAB2(SCH_1):PAGE193_I45@MSTR_SCONN.SCONN120_H61426002(CHIPS)':
 'IOF11': CDS_PINID='IOF11';
NODE_NAME     J4E1 F12
 '@BASEBOARD_FAB2_LIB.BASEBOARD_FAB2(SCH_1):PAGE193_I45@MSTR_SCONN.SCONN120_H61426002(CHIPS)':
 'IOF12': CDS_PINID='IOF12';
NODE_NAME     J4E1 F13
 '@BASEBOARD_FAB2_LIB.BASEBOARD_FAB2(SCH_1):PAGE193_I45@MSTR_SCONN.SCONN120_H61426002(CHIPS)':
 'IOF13': CDS_PINID='IOF13';
NODE_NAME     J4E1 F14
 '@BASEBOARD_FAB2_LIB.BASEBOARD_FAB2(SCH_1):PAGE193_I45@MSTR_SCONN.SCONN120_H61426002(CHIPS)':
 'IOF14': CDS_PINID='IOF14';
NODE_NAME     J4E1 F15
 '@BASEBOARD_FAB2_LIB.BASEBOARD_FAB2(SCH_1):PAGE193_I45@MSTR_SCONN.SCONN120_H61426002(CHIPS)':
 'IOF15': CDS_PINID='IOF15';
NODE_NAME     J4E1 F16
 '@BASEBOARD_FAB2_LIB.BASEBOARD_FAB2(SCH_1):PAGE193_I45@MSTR_SCONN.SCONN120_H61426002(CHIPS)':
 'IOF16': CDS_PINID='IOF16';
NODE_NAME     J4E1 F17
 '@BASEBOARD_FAB2_LIB.BASEBOARD_FAB2(SCH_1):PAGE193_I45@MSTR_SCONN.SCONN120_H61426002(CHIPS)':
 'IOF17': CDS_PINID='IOF17';
NODE_NAME     J4E1 F18
 '@BASEBOARD_FAB2_LIB.BASEBOARD_FAB2(SCH_1):PAGE193_I45@MSTR_SCONN.SCONN120_H61426002(CHIPS)':
 'IOF18': CDS_PINID='IOF18';
NODE_NAME     J4E1 F19
 '@BASEBOARD_FAB2_LIB.BASEBOARD_FAB2(SCH_1):PAGE193_I45@MSTR_SCONN.SCONN120_H61426002(CHIPS)':
 'IOF19': CDS_PINID='IOF19';
NODE_NAME     J4E1 F20
 '@BASEBOARD_FAB2_LIB.BASEBOARD_FAB2(SCH_1):PAGE193_I45@MSTR_SCONN.SCONN120_H61426002(CHIPS)':
 'IOF20': CDS_PINID='IOF20';
NODE_NAME     J4B2 A9
 '@BASEBOARD_FAB2_LIB.BASEBOARD_FAB2(SCH_1):PAGE193_I46@MSTR_SCONN.SCONN120_H61426002(CHIPS)':
 'IOA9': CDS_PINID='IOA9';
NODE_NAME     J4B2 A10
 '@BASEBOARD_FAB2_LIB.BASEBOARD_FAB2(SCH_1):PAGE193_I46@MSTR_SCONN.SCONN120_H61426002(CHIPS)':
 'IOA10': CDS_PINID='IOA10';
NODE_NAME     J4B2 A12
 '@BASEBOARD_FAB2_LIB.BASEBOARD_FAB2(SCH_1):PAGE193_I46@MSTR_SCONN.SCONN120_H61426002(CHIPS)':
 'IOA12': CDS_PINID='IOA12';
NODE_NAME     J4B2 A14
 '@BASEBOARD_FAB2_LIB.BASEBOARD_FAB2(SCH_1):PAGE193_I46@MSTR_SCONN.SCONN120_H61426002(CHIPS)':
 'IOA14': CDS_PINID='IOA14';
NODE_NAME     J4B2 A17
 '@BASEBOARD_FAB2_LIB.BASEBOARD_FAB2(SCH_1):PAGE193_I46@MSTR_SCONN.SCONN120_H61426002(CHIPS)':
 'IOA17': CDS_PINID='IOA17';
NODE_NAME     J4B2 B9
 '@BASEBOARD_FAB2_LIB.BASEBOARD_FAB2(SCH_1):PAGE193_I46@MSTR_SCONN.SCONN120_H61426002(CHIPS)':
 'IOB9': CDS_PINID='IOB9';
NODE_NAME     J4B2 B10
 '@BASEBOARD_FAB2_LIB.BASEBOARD_FAB2(SCH_1):PAGE193_I46@MSTR_SCONN.SCONN120_H61426002(CHIPS)':
 'IOB10': CDS_PINID='IOB10';
NODE_NAME     J4B2 B12
 '@BASEBOARD_FAB2_LIB.BASEBOARD_FAB2(SCH_1):PAGE193_I46@MSTR_SCONN.SCONN120_H61426002(CHIPS)':
 'IOB12': CDS_PINID='IOB12';
NODE_NAME     J4B2 B14
 '@BASEBOARD_FAB2_LIB.BASEBOARD_FAB2(SCH_1):PAGE193_I46@MSTR_SCONN.SCONN120_H61426002(CHIPS)':
 'IOB14': CDS_PINID='IOB14';
NODE_NAME     J4B2 B17
 '@BASEBOARD_FAB2_LIB.BASEBOARD_FAB2(SCH_1):PAGE193_I46@MSTR_SCONN.SCONN120_H61426002(CHIPS)':
 'IOB17': CDS_PINID='IOB17';
NODE_NAME     J4B2 C1
 '@BASEBOARD_FAB2_LIB.BASEBOARD_FAB2(SCH_1):PAGE193_I46@MSTR_SCONN.SCONN120_H61426002(CHIPS)':
 'IOC1': CDS_PINID='IOC1';
NODE_NAME     J4B2 C2
 '@BASEBOARD_FAB2_LIB.BASEBOARD_FAB2(SCH_1):PAGE193_I46@MSTR_SCONN.SCONN120_H61426002(CHIPS)':
 'IOC2': CDS_PINID='IOC2';
NODE_NAME     J4B2 C3
 '@BASEBOARD_FAB2_LIB.BASEBOARD_FAB2(SCH_1):PAGE193_I46@MSTR_SCONN.SCONN120_H61426002(CHIPS)':
 'IOC3': CDS_PINID='IOC3';
NODE_NAME     J4B2 C4
 '@BASEBOARD_FAB2_LIB.BASEBOARD_FAB2(SCH_1):PAGE193_I46@MSTR_SCONN.SCONN120_H61426002(CHIPS)':
 'IOC4': CDS_PINID='IOC4';
NODE_NAME     J4B2 C5
 '@BASEBOARD_FAB2_LIB.BASEBOARD_FAB2(SCH_1):PAGE193_I46@MSTR_SCONN.SCONN120_H61426002(CHIPS)':
 'IOC5': CDS_PINID='IOC5';
NODE_NAME     J4B2 C6
 '@BASEBOARD_FAB2_LIB.BASEBOARD_FAB2(SCH_1):PAGE193_I46@MSTR_SCONN.SCONN120_H61426002(CHIPS)':
 'IOC6': CDS_PINID='IOC6';
NODE_NAME     J4B2 C7
 '@BASEBOARD_FAB2_LIB.BASEBOARD_FAB2(SCH_1):PAGE193_I46@MSTR_SCONN.SCONN120_H61426002(CHIPS)':
 'IOC7': CDS_PINID='IOC7';
NODE_NAME     J4B2 C8
 '@BASEBOARD_FAB2_LIB.BASEBOARD_FAB2(SCH_1):PAGE193_I46@MSTR_SCONN.SCONN120_H61426002(CHIPS)':
 'IOC8': CDS_PINID='IOC8';
NODE_NAME     J4B2 C9
 '@BASEBOARD_FAB2_LIB.BASEBOARD_FAB2(SCH_1):PAGE193_I46@MSTR_SCONN.SCONN120_H61426002(CHIPS)':
 'IOC9': CDS_PINID='IOC9';
NODE_NAME     J4B2 C10
 '@BASEBOARD_FAB2_LIB.BASEBOARD_FAB2(SCH_1):PAGE193_I46@MSTR_SCONN.SCONN120_H61426002(CHIPS)':
 'IOC10': CDS_PINID='IOC10';
NODE_NAME     J4B2 C12
 '@BASEBOARD_FAB2_LIB.BASEBOARD_FAB2(SCH_1):PAGE193_I46@MSTR_SCONN.SCONN120_H61426002(CHIPS)':
 'IOC12': CDS_PINID='IOC12';
NODE_NAME     J4B2 C14
 '@BASEBOARD_FAB2_LIB.BASEBOARD_FAB2(SCH_1):PAGE193_I46@MSTR_SCONN.SCONN120_H61426002(CHIPS)':
 'IOC14': CDS_PINID='IOC14';
NODE_NAME     J4B2 C15
 '@BASEBOARD_FAB2_LIB.BASEBOARD_FAB2(SCH_1):PAGE193_I46@MSTR_SCONN.SCONN120_H61426002(CHIPS)':
 'IOC15': CDS_PINID='IOC15';
NODE_NAME     J4B2 C16
 '@BASEBOARD_FAB2_LIB.BASEBOARD_FAB2(SCH_1):PAGE193_I46@MSTR_SCONN.SCONN120_H61426002(CHIPS)':
 'IOC16': CDS_PINID='IOC16';
NODE_NAME     J4B2 D2
 '@BASEBOARD_FAB2_LIB.BASEBOARD_FAB2(SCH_1):PAGE193_I46@MSTR_SCONN.SCONN120_H61426002(CHIPS)':
 'IOD2': CDS_PINID='IOD2';
NODE_NAME     J4B2 D3
 '@BASEBOARD_FAB2_LIB.BASEBOARD_FAB2(SCH_1):PAGE193_I46@MSTR_SCONN.SCONN120_H61426002(CHIPS)':
 'IOD3': CDS_PINID='IOD3';
NODE_NAME     J4B2 D4
 '@BASEBOARD_FAB2_LIB.BASEBOARD_FAB2(SCH_1):PAGE193_I46@MSTR_SCONN.SCONN120_H61426002(CHIPS)':
 'IOD4': CDS_PINID='IOD4';
NODE_NAME     J4B2 D5
 '@BASEBOARD_FAB2_LIB.BASEBOARD_FAB2(SCH_1):PAGE193_I46@MSTR_SCONN.SCONN120_H61426002(CHIPS)':
 'IOD5': CDS_PINID='IOD5';
NODE_NAME     J4B2 D6
 '@BASEBOARD_FAB2_LIB.BASEBOARD_FAB2(SCH_1):PAGE193_I46@MSTR_SCONN.SCONN120_H61426002(CHIPS)':
 'IOD6': CDS_PINID='IOD6';
NODE_NAME     J4B2 D7
 '@BASEBOARD_FAB2_LIB.BASEBOARD_FAB2(SCH_1):PAGE193_I46@MSTR_SCONN.SCONN120_H61426002(CHIPS)':
 'IOD7': CDS_PINID='IOD7';
NODE_NAME     J4B2 D8
 '@BASEBOARD_FAB2_LIB.BASEBOARD_FAB2(SCH_1):PAGE193_I46@MSTR_SCONN.SCONN120_H61426002(CHIPS)':
 'IOD8': CDS_PINID='IOD8';
NODE_NAME     J4B2 D9
 '@BASEBOARD_FAB2_LIB.BASEBOARD_FAB2(SCH_1):PAGE193_I46@MSTR_SCONN.SCONN120_H61426002(CHIPS)':
 'IOD9': CDS_PINID='IOD9';
NODE_NAME     J4B2 D10
 '@BASEBOARD_FAB2_LIB.BASEBOARD_FAB2(SCH_1):PAGE193_I46@MSTR_SCONN.SCONN120_H61426002(CHIPS)':
 'IOD10': CDS_PINID='IOD10';
NODE_NAME     J4B2 D11
 '@BASEBOARD_FAB2_LIB.BASEBOARD_FAB2(SCH_1):PAGE193_I46@MSTR_SCONN.SCONN120_H61426002(CHIPS)':
 'IOD11': CDS_PINID='IOD11';
NODE_NAME     J4B2 D12
 '@BASEBOARD_FAB2_LIB.BASEBOARD_FAB2(SCH_1):PAGE193_I46@MSTR_SCONN.SCONN120_H61426002(CHIPS)':
 'IOD12': CDS_PINID='IOD12';
NODE_NAME     J4B2 D13
 '@BASEBOARD_FAB2_LIB.BASEBOARD_FAB2(SCH_1):PAGE193_I46@MSTR_SCONN.SCONN120_H61426002(CHIPS)':
 'IOD13': CDS_PINID='IOD13';
NODE_NAME     J4B2 D14
 '@BASEBOARD_FAB2_LIB.BASEBOARD_FAB2(SCH_1):PAGE193_I46@MSTR_SCONN.SCONN120_H61426002(CHIPS)':
 'IOD14': CDS_PINID='IOD14';
NODE_NAME     J4B2 D15
 '@BASEBOARD_FAB2_LIB.BASEBOARD_FAB2(SCH_1):PAGE193_I46@MSTR_SCONN.SCONN120_H61426002(CHIPS)':
 'IOD15': CDS_PINID='IOD15';
NODE_NAME     J4B2 D16
 '@BASEBOARD_FAB2_LIB.BASEBOARD_FAB2(SCH_1):PAGE193_I46@MSTR_SCONN.SCONN120_H61426002(CHIPS)':
 'IOD16': CDS_PINID='IOD16';
NODE_NAME     J4B2 E2
 '@BASEBOARD_FAB2_LIB.BASEBOARD_FAB2(SCH_1):PAGE193_I46@MSTR_SCONN.SCONN120_H61426002(CHIPS)':
 'IOE2': CDS_PINID='IOE2';
NODE_NAME     J4B2 E3
 '@BASEBOARD_FAB2_LIB.BASEBOARD_FAB2(SCH_1):PAGE193_I46@MSTR_SCONN.SCONN120_H61426002(CHIPS)':
 'IOE3': CDS_PINID='IOE3';
NODE_NAME     J4B2 E4
 '@BASEBOARD_FAB2_LIB.BASEBOARD_FAB2(SCH_1):PAGE193_I46@MSTR_SCONN.SCONN120_H61426002(CHIPS)':
 'IOE4': CDS_PINID='IOE4';
NODE_NAME     J4B2 E5
 '@BASEBOARD_FAB2_LIB.BASEBOARD_FAB2(SCH_1):PAGE193_I46@MSTR_SCONN.SCONN120_H61426002(CHIPS)':
 'IOE5': CDS_PINID='IOE5';
NODE_NAME     J4B2 E6
 '@BASEBOARD_FAB2_LIB.BASEBOARD_FAB2(SCH_1):PAGE193_I46@MSTR_SCONN.SCONN120_H61426002(CHIPS)':
 'IOE6': CDS_PINID='IOE6';
NODE_NAME     J4B2 E7
 '@BASEBOARD_FAB2_LIB.BASEBOARD_FAB2(SCH_1):PAGE193_I46@MSTR_SCONN.SCONN120_H61426002(CHIPS)':
 'IOE7': CDS_PINID='IOE7';
NODE_NAME     J4B2 E9
 '@BASEBOARD_FAB2_LIB.BASEBOARD_FAB2(SCH_1):PAGE193_I46@MSTR_SCONN.SCONN120_H61426002(CHIPS)':
 'IOE9': CDS_PINID='IOE9';
NODE_NAME     J4B2 E11
 '@BASEBOARD_FAB2_LIB.BASEBOARD_FAB2(SCH_1):PAGE193_I46@MSTR_SCONN.SCONN120_H61426002(CHIPS)':
 'IOE11': CDS_PINID='IOE11';
NODE_NAME     J4B2 E12
 '@BASEBOARD_FAB2_LIB.BASEBOARD_FAB2(SCH_1):PAGE193_I46@MSTR_SCONN.SCONN120_H61426002(CHIPS)':
 'IOE12': CDS_PINID='IOE12';
NODE_NAME     J4B2 E13
 '@BASEBOARD_FAB2_LIB.BASEBOARD_FAB2(SCH_1):PAGE193_I46@MSTR_SCONN.SCONN120_H61426002(CHIPS)':
 'IOE13': CDS_PINID='IOE13';
NODE_NAME     J4B2 E14
 '@BASEBOARD_FAB2_LIB.BASEBOARD_FAB2(SCH_1):PAGE193_I46@MSTR_SCONN.SCONN120_H61426002(CHIPS)':
 'IOE14': CDS_PINID='IOE14';
NODE_NAME     J4B2 F2
 '@BASEBOARD_FAB2_LIB.BASEBOARD_FAB2(SCH_1):PAGE193_I46@MSTR_SCONN.SCONN120_H61426002(CHIPS)':
 'IOF2': CDS_PINID='IOF2';
NODE_NAME     J4B2 F3
 '@BASEBOARD_FAB2_LIB.BASEBOARD_FAB2(SCH_1):PAGE193_I46@MSTR_SCONN.SCONN120_H61426002(CHIPS)':
 'IOF3': CDS_PINID='IOF3';
NODE_NAME     J4B2 F4
 '@BASEBOARD_FAB2_LIB.BASEBOARD_FAB2(SCH_1):PAGE193_I46@MSTR_SCONN.SCONN120_H61426002(CHIPS)':
 'IOF4': CDS_PINID='IOF4';
NODE_NAME     J4B2 F5
 '@BASEBOARD_FAB2_LIB.BASEBOARD_FAB2(SCH_1):PAGE193_I46@MSTR_SCONN.SCONN120_H61426002(CHIPS)':
 'IOF5': CDS_PINID='IOF5';
NODE_NAME     J4B2 F6
 '@BASEBOARD_FAB2_LIB.BASEBOARD_FAB2(SCH_1):PAGE193_I46@MSTR_SCONN.SCONN120_H61426002(CHIPS)':
 'IOF6': CDS_PINID='IOF6';
NODE_NAME     J4B2 F7
 '@BASEBOARD_FAB2_LIB.BASEBOARD_FAB2(SCH_1):PAGE193_I46@MSTR_SCONN.SCONN120_H61426002(CHIPS)':
 'IOF7': CDS_PINID='IOF7';
NODE_NAME     J4B2 F9
 '@BASEBOARD_FAB2_LIB.BASEBOARD_FAB2(SCH_1):PAGE193_I46@MSTR_SCONN.SCONN120_H61426002(CHIPS)':
 'IOF9': CDS_PINID='IOF9';
NODE_NAME     J4B2 F11
 '@BASEBOARD_FAB2_LIB.BASEBOARD_FAB2(SCH_1):PAGE193_I46@MSTR_SCONN.SCONN120_H61426002(CHIPS)':
 'IOF11': CDS_PINID='IOF11';
NODE_NAME     J4B2 F12
 '@BASEBOARD_FAB2_LIB.BASEBOARD_FAB2(SCH_1):PAGE193_I46@MSTR_SCONN.SCONN120_H61426002(CHIPS)':
 'IOF12': CDS_PINID='IOF12';
NODE_NAME     J4B2 F13
 '@BASEBOARD_FAB2_LIB.BASEBOARD_FAB2(SCH_1):PAGE193_I46@MSTR_SCONN.SCONN120_H61426002(CHIPS)':
 'IOF13': CDS_PINID='IOF13';
NODE_NAME     J4B2 F14
 '@BASEBOARD_FAB2_LIB.BASEBOARD_FAB2(SCH_1):PAGE193_I46@MSTR_SCONN.SCONN120_H61426002(CHIPS)':
 'IOF14': CDS_PINID='IOF14';
NODE_NAME     C4E24 2
 '@BASEBOARD_FAB2_LIB.BASEBOARD_FAB2(SCH_1):PAGE193_I61@MSTR_DISCRETE.CAPP(CHIPS)':
 'B': CDS_PINID='B';
NODE_NAME     C6R16 2
 '@BASEBOARD_FAB2_LIB.BASEBOARD_FAB2(SCH_1):PAGE193_I62@MSTR_DISCRETE.CAPP(CHIPS)':
 'B': CDS_PINID='B';
NODE_NAME     C4F1 2
 '@BASEBOARD_FAB2_LIB.BASEBOARD_FAB2(SCH_1):PAGE193_I68@DEV_DISCRETE.CAP_A(CHIPS)':
 'B': CDS_PINID='B';
NODE_NAME     C4F3 2
 '@BASEBOARD_FAB2_LIB.BASEBOARD_FAB2(SCH_1):PAGE193_I70@DEV_DISCRETE.CAP_A(CHIPS)':
 'B': CDS_PINID='B';
NODE_NAME     C3F1 2
 '@BASEBOARD_FAB2_LIB.BASEBOARD_FAB2(SCH_1):PAGE193_I140@DEV_DISCRETE.CAP_A(CHIPS)':
 'B': CDS_PINID='B';
NODE_NAME     C4F2 2
 '@BASEBOARD_FAB2_LIB.BASEBOARD_FAB2(SCH_1):PAGE193_I141@DEV_DISCRETE.CAP_A(CHIPS)':
 'B': CDS_PINID='B';
NODE_NAME     R4C12 2
 '@BASEBOARD_FAB2_LIB.BASEBOARD_FAB2(SCH_1):PAGE193_I169@MSTR_DISCRETE.RES(CHIPS)':
 'B': CDS_PINID='B';
NODE_NAME     R4C11 2
 '@BASEBOARD_FAB2_LIB.BASEBOARD_FAB2(SCH_1):PAGE193_I170@MSTR_DISCRETE.RES(CHIPS)':
 'B': CDS_PINID='B';
NODE_NAME     C4T2 2
 '@BASEBOARD_FAB2_LIB.BASEBOARD_FAB2(SCH_1):PAGE194_I9@DEV_DISCRETE.CAP_A(CHIPS)':
 'B': CDS_PINID='B';
NODE_NAME     C4T1 2
 '@BASEBOARD_FAB2_LIB.BASEBOARD_FAB2(SCH_1):PAGE194_I16@DEV_DISCRETE.CAP_A(CHIPS)':
 'B': CDS_PINID='B';
NODE_NAME     C4R1 2
 '@BASEBOARD_FAB2_LIB.BASEBOARD_FAB2(SCH_1):PAGE194_I29@MSTR_DISCRETE.CAPP(CHIPS)':
 'B': CDS_PINID='B';
NODE_NAME     C3R4 2
 '@BASEBOARD_FAB2_LIB.BASEBOARD_FAB2(SCH_1):PAGE194_I31@MSTR_DISCRETE.CAPP(CHIPS)':
 'B': CDS_PINID='B';
NODE_NAME     J6E1 A19
 '@BASEBOARD_FAB2_LIB.BASEBOARD_FAB2(SCH_1):PAGE194_I55@MSTR_SCONN.SCONN120_H61426002(CHIPS)':
 'IOA19': CDS_PINID='IOA19';
NODE_NAME     J6E1 A20
 '@BASEBOARD_FAB2_LIB.BASEBOARD_FAB2(SCH_1):PAGE194_I55@MSTR_SCONN.SCONN120_H61426002(CHIPS)':
 'IOA20': CDS_PINID='IOA20';
NODE_NAME     J6E1 B19
 '@BASEBOARD_FAB2_LIB.BASEBOARD_FAB2(SCH_1):PAGE194_I55@MSTR_SCONN.SCONN120_H61426002(CHIPS)':
 'IOB19': CDS_PINID='IOB19';
NODE_NAME     J6E1 B20
 '@BASEBOARD_FAB2_LIB.BASEBOARD_FAB2(SCH_1):PAGE194_I55@MSTR_SCONN.SCONN120_H61426002(CHIPS)':
 'IOB20': CDS_PINID='IOB20';
NODE_NAME     J6E1 C19
 '@BASEBOARD_FAB2_LIB.BASEBOARD_FAB2(SCH_1):PAGE194_I55@MSTR_SCONN.SCONN120_H61426002(CHIPS)':
 'IOC19': CDS_PINID='IOC19';
NODE_NAME     J6E1 C20
 '@BASEBOARD_FAB2_LIB.BASEBOARD_FAB2(SCH_1):PAGE194_I55@MSTR_SCONN.SCONN120_H61426002(CHIPS)':
 'IOC20': CDS_PINID='IOC20';
NODE_NAME     J6E1 D4
 '@BASEBOARD_FAB2_LIB.BASEBOARD_FAB2(SCH_1):PAGE194_I55@MSTR_SCONN.SCONN120_H61426002(CHIPS)':
 'IOD4': CDS_PINID='IOD4';
NODE_NAME     J6E1 D5
 '@BASEBOARD_FAB2_LIB.BASEBOARD_FAB2(SCH_1):PAGE194_I55@MSTR_SCONN.SCONN120_H61426002(CHIPS)':
 'IOD5': CDS_PINID='IOD5';
NODE_NAME     J6E1 D6
 '@BASEBOARD_FAB2_LIB.BASEBOARD_FAB2(SCH_1):PAGE194_I55@MSTR_SCONN.SCONN120_H61426002(CHIPS)':
 'IOD6': CDS_PINID='IOD6';
NODE_NAME     J6E1 D7
 '@BASEBOARD_FAB2_LIB.BASEBOARD_FAB2(SCH_1):PAGE194_I55@MSTR_SCONN.SCONN120_H61426002(CHIPS)':
 'IOD7': CDS_PINID='IOD7';
NODE_NAME     J6E1 D8
 '@BASEBOARD_FAB2_LIB.BASEBOARD_FAB2(SCH_1):PAGE194_I55@MSTR_SCONN.SCONN120_H61426002(CHIPS)':
 'IOD8': CDS_PINID='IOD8';
NODE_NAME     J6E1 D9
 '@BASEBOARD_FAB2_LIB.BASEBOARD_FAB2(SCH_1):PAGE194_I55@MSTR_SCONN.SCONN120_H61426002(CHIPS)':
 'IOD9': CDS_PINID='IOD9';
NODE_NAME     J6E1 D10
 '@BASEBOARD_FAB2_LIB.BASEBOARD_FAB2(SCH_1):PAGE194_I55@MSTR_SCONN.SCONN120_H61426002(CHIPS)':
 'IOD10': CDS_PINID='IOD10';
NODE_NAME     J6E1 D11
 '@BASEBOARD_FAB2_LIB.BASEBOARD_FAB2(SCH_1):PAGE194_I55@MSTR_SCONN.SCONN120_H61426002(CHIPS)':
 'IOD11': CDS_PINID='IOD11';
NODE_NAME     J6E1 D12
 '@BASEBOARD_FAB2_LIB.BASEBOARD_FAB2(SCH_1):PAGE194_I55@MSTR_SCONN.SCONN120_H61426002(CHIPS)':
 'IOD12': CDS_PINID='IOD12';
NODE_NAME     J6E1 D13
 '@BASEBOARD_FAB2_LIB.BASEBOARD_FAB2(SCH_1):PAGE194_I55@MSTR_SCONN.SCONN120_H61426002(CHIPS)':
 'IOD13': CDS_PINID='IOD13';
NODE_NAME     J6E1 D14
 '@BASEBOARD_FAB2_LIB.BASEBOARD_FAB2(SCH_1):PAGE194_I55@MSTR_SCONN.SCONN120_H61426002(CHIPS)':
 'IOD14': CDS_PINID='IOD14';
NODE_NAME     J6E1 D15
 '@BASEBOARD_FAB2_LIB.BASEBOARD_FAB2(SCH_1):PAGE194_I55@MSTR_SCONN.SCONN120_H61426002(CHIPS)':
 'IOD15': CDS_PINID='IOD15';
NODE_NAME     J6E1 D16
 '@BASEBOARD_FAB2_LIB.BASEBOARD_FAB2(SCH_1):PAGE194_I55@MSTR_SCONN.SCONN120_H61426002(CHIPS)':
 'IOD16': CDS_PINID='IOD16';
NODE_NAME     J6E1 D17
 '@BASEBOARD_FAB2_LIB.BASEBOARD_FAB2(SCH_1):PAGE194_I55@MSTR_SCONN.SCONN120_H61426002(CHIPS)':
 'IOD17': CDS_PINID='IOD17';
NODE_NAME     J6E1 D18
 '@BASEBOARD_FAB2_LIB.BASEBOARD_FAB2(SCH_1):PAGE194_I55@MSTR_SCONN.SCONN120_H61426002(CHIPS)':
 'IOD18': CDS_PINID='IOD18';
NODE_NAME     J6E1 D19
 '@BASEBOARD_FAB2_LIB.BASEBOARD_FAB2(SCH_1):PAGE194_I55@MSTR_SCONN.SCONN120_H61426002(CHIPS)':
 'IOD19': CDS_PINID='IOD19';
NODE_NAME     J6E1 D20
 '@BASEBOARD_FAB2_LIB.BASEBOARD_FAB2(SCH_1):PAGE194_I55@MSTR_SCONN.SCONN120_H61426002(CHIPS)':
 'IOD20': CDS_PINID='IOD20';
NODE_NAME     J6E1 E4
 '@BASEBOARD_FAB2_LIB.BASEBOARD_FAB2(SCH_1):PAGE194_I55@MSTR_SCONN.SCONN120_H61426002(CHIPS)':
 'IOE4': CDS_PINID='IOE4';
NODE_NAME     J6E1 E6
 '@BASEBOARD_FAB2_LIB.BASEBOARD_FAB2(SCH_1):PAGE194_I55@MSTR_SCONN.SCONN120_H61426002(CHIPS)':
 'IOE6': CDS_PINID='IOE6';
NODE_NAME     J6E1 E7
 '@BASEBOARD_FAB2_LIB.BASEBOARD_FAB2(SCH_1):PAGE194_I55@MSTR_SCONN.SCONN120_H61426002(CHIPS)':
 'IOE7': CDS_PINID='IOE7';
NODE_NAME     J6E1 E8
 '@BASEBOARD_FAB2_LIB.BASEBOARD_FAB2(SCH_1):PAGE194_I55@MSTR_SCONN.SCONN120_H61426002(CHIPS)':
 'IOE8': CDS_PINID='IOE8';
NODE_NAME     J6E1 E9
 '@BASEBOARD_FAB2_LIB.BASEBOARD_FAB2(SCH_1):PAGE194_I55@MSTR_SCONN.SCONN120_H61426002(CHIPS)':
 'IOE9': CDS_PINID='IOE9';
NODE_NAME     J6E1 E10
 '@BASEBOARD_FAB2_LIB.BASEBOARD_FAB2(SCH_1):PAGE194_I55@MSTR_SCONN.SCONN120_H61426002(CHIPS)':
 'IOE10': CDS_PINID='IOE10';
NODE_NAME     J6E1 E11
 '@BASEBOARD_FAB2_LIB.BASEBOARD_FAB2(SCH_1):PAGE194_I55@MSTR_SCONN.SCONN120_H61426002(CHIPS)':
 'IOE11': CDS_PINID='IOE11';
NODE_NAME     J6E1 E12
 '@BASEBOARD_FAB2_LIB.BASEBOARD_FAB2(SCH_1):PAGE194_I55@MSTR_SCONN.SCONN120_H61426002(CHIPS)':
 'IOE12': CDS_PINID='IOE12';
NODE_NAME     J6E1 E13
 '@BASEBOARD_FAB2_LIB.BASEBOARD_FAB2(SCH_1):PAGE194_I55@MSTR_SCONN.SCONN120_H61426002(CHIPS)':
 'IOE13': CDS_PINID='IOE13';
NODE_NAME     J6E1 E14
 '@BASEBOARD_FAB2_LIB.BASEBOARD_FAB2(SCH_1):PAGE194_I55@MSTR_SCONN.SCONN120_H61426002(CHIPS)':
 'IOE14': CDS_PINID='IOE14';
NODE_NAME     J6E1 E15
 '@BASEBOARD_FAB2_LIB.BASEBOARD_FAB2(SCH_1):PAGE194_I55@MSTR_SCONN.SCONN120_H61426002(CHIPS)':
 'IOE15': CDS_PINID='IOE15';
NODE_NAME     J6E1 E16
 '@BASEBOARD_FAB2_LIB.BASEBOARD_FAB2(SCH_1):PAGE194_I55@MSTR_SCONN.SCONN120_H61426002(CHIPS)':
 'IOE16': CDS_PINID='IOE16';
NODE_NAME     J6E1 E17
 '@BASEBOARD_FAB2_LIB.BASEBOARD_FAB2(SCH_1):PAGE194_I55@MSTR_SCONN.SCONN120_H61426002(CHIPS)':
 'IOE17': CDS_PINID='IOE17';
NODE_NAME     J6E1 E18
 '@BASEBOARD_FAB2_LIB.BASEBOARD_FAB2(SCH_1):PAGE194_I55@MSTR_SCONN.SCONN120_H61426002(CHIPS)':
 'IOE18': CDS_PINID='IOE18';
NODE_NAME     J6E1 E19
 '@BASEBOARD_FAB2_LIB.BASEBOARD_FAB2(SCH_1):PAGE194_I55@MSTR_SCONN.SCONN120_H61426002(CHIPS)':
 'IOE19': CDS_PINID='IOE19';
NODE_NAME     J6E1 E20
 '@BASEBOARD_FAB2_LIB.BASEBOARD_FAB2(SCH_1):PAGE194_I55@MSTR_SCONN.SCONN120_H61426002(CHIPS)':
 'IOE20': CDS_PINID='IOE20';
NODE_NAME     J6E1 F4
 '@BASEBOARD_FAB2_LIB.BASEBOARD_FAB2(SCH_1):PAGE194_I55@MSTR_SCONN.SCONN120_H61426002(CHIPS)':
 'IOF4': CDS_PINID='IOF4';
NODE_NAME     J6E1 F6
 '@BASEBOARD_FAB2_LIB.BASEBOARD_FAB2(SCH_1):PAGE194_I55@MSTR_SCONN.SCONN120_H61426002(CHIPS)':
 'IOF6': CDS_PINID='IOF6';
NODE_NAME     J6E1 F7
 '@BASEBOARD_FAB2_LIB.BASEBOARD_FAB2(SCH_1):PAGE194_I55@MSTR_SCONN.SCONN120_H61426002(CHIPS)':
 'IOF7': CDS_PINID='IOF7';
NODE_NAME     J6E1 F8
 '@BASEBOARD_FAB2_LIB.BASEBOARD_FAB2(SCH_1):PAGE194_I55@MSTR_SCONN.SCONN120_H61426002(CHIPS)':
 'IOF8': CDS_PINID='IOF8';
NODE_NAME     J6E1 F9
 '@BASEBOARD_FAB2_LIB.BASEBOARD_FAB2(SCH_1):PAGE194_I55@MSTR_SCONN.SCONN120_H61426002(CHIPS)':
 'IOF9': CDS_PINID='IOF9';
NODE_NAME     J6E1 F10
 '@BASEBOARD_FAB2_LIB.BASEBOARD_FAB2(SCH_1):PAGE194_I55@MSTR_SCONN.SCONN120_H61426002(CHIPS)':
 'IOF10': CDS_PINID='IOF10';
NODE_NAME     J6E1 F11
 '@BASEBOARD_FAB2_LIB.BASEBOARD_FAB2(SCH_1):PAGE194_I55@MSTR_SCONN.SCONN120_H61426002(CHIPS)':
 'IOF11': CDS_PINID='IOF11';
NODE_NAME     J6E1 F12
 '@BASEBOARD_FAB2_LIB.BASEBOARD_FAB2(SCH_1):PAGE194_I55@MSTR_SCONN.SCONN120_H61426002(CHIPS)':
 'IOF12': CDS_PINID='IOF12';
NODE_NAME     J6E1 F13
 '@BASEBOARD_FAB2_LIB.BASEBOARD_FAB2(SCH_1):PAGE194_I55@MSTR_SCONN.SCONN120_H61426002(CHIPS)':
 'IOF13': CDS_PINID='IOF13';
NODE_NAME     J6E1 F14
 '@BASEBOARD_FAB2_LIB.BASEBOARD_FAB2(SCH_1):PAGE194_I55@MSTR_SCONN.SCONN120_H61426002(CHIPS)':
 'IOF14': CDS_PINID='IOF14';
NODE_NAME     J6E1 F15
 '@BASEBOARD_FAB2_LIB.BASEBOARD_FAB2(SCH_1):PAGE194_I55@MSTR_SCONN.SCONN120_H61426002(CHIPS)':
 'IOF15': CDS_PINID='IOF15';
NODE_NAME     J6E1 F16
 '@BASEBOARD_FAB2_LIB.BASEBOARD_FAB2(SCH_1):PAGE194_I55@MSTR_SCONN.SCONN120_H61426002(CHIPS)':
 'IOF16': CDS_PINID='IOF16';
NODE_NAME     J6E1 F17
 '@BASEBOARD_FAB2_LIB.BASEBOARD_FAB2(SCH_1):PAGE194_I55@MSTR_SCONN.SCONN120_H61426002(CHIPS)':
 'IOF17': CDS_PINID='IOF17';
NODE_NAME     J6E1 F18
 '@BASEBOARD_FAB2_LIB.BASEBOARD_FAB2(SCH_1):PAGE194_I55@MSTR_SCONN.SCONN120_H61426002(CHIPS)':
 'IOF18': CDS_PINID='IOF18';
NODE_NAME     J6E1 F19
 '@BASEBOARD_FAB2_LIB.BASEBOARD_FAB2(SCH_1):PAGE194_I55@MSTR_SCONN.SCONN120_H61426002(CHIPS)':
 'IOF19': CDS_PINID='IOF19';
NODE_NAME     J6E1 F20
 '@BASEBOARD_FAB2_LIB.BASEBOARD_FAB2(SCH_1):PAGE194_I55@MSTR_SCONN.SCONN120_H61426002(CHIPS)':
 'IOF20': CDS_PINID='IOF20';
NODE_NAME     J6B1 A9
 '@BASEBOARD_FAB2_LIB.BASEBOARD_FAB2(SCH_1):PAGE194_I56@MSTR_SCONN.SCONN120_H61426002(CHIPS)':
 'IOA9': CDS_PINID='IOA9';
NODE_NAME     J6B1 A10
 '@BASEBOARD_FAB2_LIB.BASEBOARD_FAB2(SCH_1):PAGE194_I56@MSTR_SCONN.SCONN120_H61426002(CHIPS)':
 'IOA10': CDS_PINID='IOA10';
NODE_NAME     J6B1 A12
 '@BASEBOARD_FAB2_LIB.BASEBOARD_FAB2(SCH_1):PAGE194_I56@MSTR_SCONN.SCONN120_H61426002(CHIPS)':
 'IOA12': CDS_PINID='IOA12';
NODE_NAME     J6B1 A14
 '@BASEBOARD_FAB2_LIB.BASEBOARD_FAB2(SCH_1):PAGE194_I56@MSTR_SCONN.SCONN120_H61426002(CHIPS)':
 'IOA14': CDS_PINID='IOA14';
NODE_NAME     J6B1 A17
 '@BASEBOARD_FAB2_LIB.BASEBOARD_FAB2(SCH_1):PAGE194_I56@MSTR_SCONN.SCONN120_H61426002(CHIPS)':
 'IOA17': CDS_PINID='IOA17';
NODE_NAME     J6B1 B9
 '@BASEBOARD_FAB2_LIB.BASEBOARD_FAB2(SCH_1):PAGE194_I56@MSTR_SCONN.SCONN120_H61426002(CHIPS)':
 'IOB9': CDS_PINID='IOB9';
NODE_NAME     J6B1 B10
 '@BASEBOARD_FAB2_LIB.BASEBOARD_FAB2(SCH_1):PAGE194_I56@MSTR_SCONN.SCONN120_H61426002(CHIPS)':
 'IOB10': CDS_PINID='IOB10';
NODE_NAME     J6B1 B12
 '@BASEBOARD_FAB2_LIB.BASEBOARD_FAB2(SCH_1):PAGE194_I56@MSTR_SCONN.SCONN120_H61426002(CHIPS)':
 'IOB12': CDS_PINID='IOB12';
NODE_NAME     J6B1 B14
 '@BASEBOARD_FAB2_LIB.BASEBOARD_FAB2(SCH_1):PAGE194_I56@MSTR_SCONN.SCONN120_H61426002(CHIPS)':
 'IOB14': CDS_PINID='IOB14';
NODE_NAME     J6B1 B17
 '@BASEBOARD_FAB2_LIB.BASEBOARD_FAB2(SCH_1):PAGE194_I56@MSTR_SCONN.SCONN120_H61426002(CHIPS)':
 'IOB17': CDS_PINID='IOB17';
NODE_NAME     J6B1 C1
 '@BASEBOARD_FAB2_LIB.BASEBOARD_FAB2(SCH_1):PAGE194_I56@MSTR_SCONN.SCONN120_H61426002(CHIPS)':
 'IOC1': CDS_PINID='IOC1';
NODE_NAME     J6B1 C2
 '@BASEBOARD_FAB2_LIB.BASEBOARD_FAB2(SCH_1):PAGE194_I56@MSTR_SCONN.SCONN120_H61426002(CHIPS)':
 'IOC2': CDS_PINID='IOC2';
NODE_NAME     J6B1 C3
 '@BASEBOARD_FAB2_LIB.BASEBOARD_FAB2(SCH_1):PAGE194_I56@MSTR_SCONN.SCONN120_H61426002(CHIPS)':
 'IOC3': CDS_PINID='IOC3';
NODE_NAME     J6B1 C4
 '@BASEBOARD_FAB2_LIB.BASEBOARD_FAB2(SCH_1):PAGE194_I56@MSTR_SCONN.SCONN120_H61426002(CHIPS)':
 'IOC4': CDS_PINID='IOC4';
NODE_NAME     J6B1 C5
 '@BASEBOARD_FAB2_LIB.BASEBOARD_FAB2(SCH_1):PAGE194_I56@MSTR_SCONN.SCONN120_H61426002(CHIPS)':
 'IOC5': CDS_PINID='IOC5';
NODE_NAME     J6B1 C6
 '@BASEBOARD_FAB2_LIB.BASEBOARD_FAB2(SCH_1):PAGE194_I56@MSTR_SCONN.SCONN120_H61426002(CHIPS)':
 'IOC6': CDS_PINID='IOC6';
NODE_NAME     J6B1 C7
 '@BASEBOARD_FAB2_LIB.BASEBOARD_FAB2(SCH_1):PAGE194_I56@MSTR_SCONN.SCONN120_H61426002(CHIPS)':
 'IOC7': CDS_PINID='IOC7';
NODE_NAME     J6B1 C8
 '@BASEBOARD_FAB2_LIB.BASEBOARD_FAB2(SCH_1):PAGE194_I56@MSTR_SCONN.SCONN120_H61426002(CHIPS)':
 'IOC8': CDS_PINID='IOC8';
NODE_NAME     J6B1 C9
 '@BASEBOARD_FAB2_LIB.BASEBOARD_FAB2(SCH_1):PAGE194_I56@MSTR_SCONN.SCONN120_H61426002(CHIPS)':
 'IOC9': CDS_PINID='IOC9';
NODE_NAME     J6B1 C10
 '@BASEBOARD_FAB2_LIB.BASEBOARD_FAB2(SCH_1):PAGE194_I56@MSTR_SCONN.SCONN120_H61426002(CHIPS)':
 'IOC10': CDS_PINID='IOC10';
NODE_NAME     J6B1 C12
 '@BASEBOARD_FAB2_LIB.BASEBOARD_FAB2(SCH_1):PAGE194_I56@MSTR_SCONN.SCONN120_H61426002(CHIPS)':
 'IOC12': CDS_PINID='IOC12';
NODE_NAME     J6B1 C14
 '@BASEBOARD_FAB2_LIB.BASEBOARD_FAB2(SCH_1):PAGE194_I56@MSTR_SCONN.SCONN120_H61426002(CHIPS)':
 'IOC14': CDS_PINID='IOC14';
NODE_NAME     J6B1 C15
 '@BASEBOARD_FAB2_LIB.BASEBOARD_FAB2(SCH_1):PAGE194_I56@MSTR_SCONN.SCONN120_H61426002(CHIPS)':
 'IOC15': CDS_PINID='IOC15';
NODE_NAME     J6B1 C16
 '@BASEBOARD_FAB2_LIB.BASEBOARD_FAB2(SCH_1):PAGE194_I56@MSTR_SCONN.SCONN120_H61426002(CHIPS)':
 'IOC16': CDS_PINID='IOC16';
NODE_NAME     J6B1 D2
 '@BASEBOARD_FAB2_LIB.BASEBOARD_FAB2(SCH_1):PAGE194_I56@MSTR_SCONN.SCONN120_H61426002(CHIPS)':
 'IOD2': CDS_PINID='IOD2';
NODE_NAME     J6B1 D3
 '@BASEBOARD_FAB2_LIB.BASEBOARD_FAB2(SCH_1):PAGE194_I56@MSTR_SCONN.SCONN120_H61426002(CHIPS)':
 'IOD3': CDS_PINID='IOD3';
NODE_NAME     J6B1 D4
 '@BASEBOARD_FAB2_LIB.BASEBOARD_FAB2(SCH_1):PAGE194_I56@MSTR_SCONN.SCONN120_H61426002(CHIPS)':
 'IOD4': CDS_PINID='IOD4';
NODE_NAME     J6B1 D5
 '@BASEBOARD_FAB2_LIB.BASEBOARD_FAB2(SCH_1):PAGE194_I56@MSTR_SCONN.SCONN120_H61426002(CHIPS)':
 'IOD5': CDS_PINID='IOD5';
NODE_NAME     J6B1 D6
 '@BASEBOARD_FAB2_LIB.BASEBOARD_FAB2(SCH_1):PAGE194_I56@MSTR_SCONN.SCONN120_H61426002(CHIPS)':
 'IOD6': CDS_PINID='IOD6';
NODE_NAME     J6B1 D7
 '@BASEBOARD_FAB2_LIB.BASEBOARD_FAB2(SCH_1):PAGE194_I56@MSTR_SCONN.SCONN120_H61426002(CHIPS)':
 'IOD7': CDS_PINID='IOD7';
NODE_NAME     J6B1 D8
 '@BASEBOARD_FAB2_LIB.BASEBOARD_FAB2(SCH_1):PAGE194_I56@MSTR_SCONN.SCONN120_H61426002(CHIPS)':
 'IOD8': CDS_PINID='IOD8';
NODE_NAME     J6B1 D9
 '@BASEBOARD_FAB2_LIB.BASEBOARD_FAB2(SCH_1):PAGE194_I56@MSTR_SCONN.SCONN120_H61426002(CHIPS)':
 'IOD9': CDS_PINID='IOD9';
NODE_NAME     J6B1 D10
 '@BASEBOARD_FAB2_LIB.BASEBOARD_FAB2(SCH_1):PAGE194_I56@MSTR_SCONN.SCONN120_H61426002(CHIPS)':
 'IOD10': CDS_PINID='IOD10';
NODE_NAME     J6B1 D11
 '@BASEBOARD_FAB2_LIB.BASEBOARD_FAB2(SCH_1):PAGE194_I56@MSTR_SCONN.SCONN120_H61426002(CHIPS)':
 'IOD11': CDS_PINID='IOD11';
NODE_NAME     J6B1 D12
 '@BASEBOARD_FAB2_LIB.BASEBOARD_FAB2(SCH_1):PAGE194_I56@MSTR_SCONN.SCONN120_H61426002(CHIPS)':
 'IOD12': CDS_PINID='IOD12';
NODE_NAME     J6B1 D13
 '@BASEBOARD_FAB2_LIB.BASEBOARD_FAB2(SCH_1):PAGE194_I56@MSTR_SCONN.SCONN120_H61426002(CHIPS)':
 'IOD13': CDS_PINID='IOD13';
NODE_NAME     J6B1 D14
 '@BASEBOARD_FAB2_LIB.BASEBOARD_FAB2(SCH_1):PAGE194_I56@MSTR_SCONN.SCONN120_H61426002(CHIPS)':
 'IOD14': CDS_PINID='IOD14';
NODE_NAME     J6B1 D15
 '@BASEBOARD_FAB2_LIB.BASEBOARD_FAB2(SCH_1):PAGE194_I56@MSTR_SCONN.SCONN120_H61426002(CHIPS)':
 'IOD15': CDS_PINID='IOD15';
NODE_NAME     J6B1 D16
 '@BASEBOARD_FAB2_LIB.BASEBOARD_FAB2(SCH_1):PAGE194_I56@MSTR_SCONN.SCONN120_H61426002(CHIPS)':
 'IOD16': CDS_PINID='IOD16';
NODE_NAME     J6B1 E2
 '@BASEBOARD_FAB2_LIB.BASEBOARD_FAB2(SCH_1):PAGE194_I56@MSTR_SCONN.SCONN120_H61426002(CHIPS)':
 'IOE2': CDS_PINID='IOE2';
NODE_NAME     J6B1 E3
 '@BASEBOARD_FAB2_LIB.BASEBOARD_FAB2(SCH_1):PAGE194_I56@MSTR_SCONN.SCONN120_H61426002(CHIPS)':
 'IOE3': CDS_PINID='IOE3';
NODE_NAME     J6B1 E4
 '@BASEBOARD_FAB2_LIB.BASEBOARD_FAB2(SCH_1):PAGE194_I56@MSTR_SCONN.SCONN120_H61426002(CHIPS)':
 'IOE4': CDS_PINID='IOE4';
NODE_NAME     J6B1 E5
 '@BASEBOARD_FAB2_LIB.BASEBOARD_FAB2(SCH_1):PAGE194_I56@MSTR_SCONN.SCONN120_H61426002(CHIPS)':
 'IOE5': CDS_PINID='IOE5';
NODE_NAME     J6B1 E6
 '@BASEBOARD_FAB2_LIB.BASEBOARD_FAB2(SCH_1):PAGE194_I56@MSTR_SCONN.SCONN120_H61426002(CHIPS)':
 'IOE6': CDS_PINID='IOE6';
NODE_NAME     J6B1 E7
 '@BASEBOARD_FAB2_LIB.BASEBOARD_FAB2(SCH_1):PAGE194_I56@MSTR_SCONN.SCONN120_H61426002(CHIPS)':
 'IOE7': CDS_PINID='IOE7';
NODE_NAME     J6B1 E9
 '@BASEBOARD_FAB2_LIB.BASEBOARD_FAB2(SCH_1):PAGE194_I56@MSTR_SCONN.SCONN120_H61426002(CHIPS)':
 'IOE9': CDS_PINID='IOE9';
NODE_NAME     J6B1 E11
 '@BASEBOARD_FAB2_LIB.BASEBOARD_FAB2(SCH_1):PAGE194_I56@MSTR_SCONN.SCONN120_H61426002(CHIPS)':
 'IOE11': CDS_PINID='IOE11';
NODE_NAME     J6B1 E12
 '@BASEBOARD_FAB2_LIB.BASEBOARD_FAB2(SCH_1):PAGE194_I56@MSTR_SCONN.SCONN120_H61426002(CHIPS)':
 'IOE12': CDS_PINID='IOE12';
NODE_NAME     J6B1 E13
 '@BASEBOARD_FAB2_LIB.BASEBOARD_FAB2(SCH_1):PAGE194_I56@MSTR_SCONN.SCONN120_H61426002(CHIPS)':
 'IOE13': CDS_PINID='IOE13';
NODE_NAME     J6B1 E14
 '@BASEBOARD_FAB2_LIB.BASEBOARD_FAB2(SCH_1):PAGE194_I56@MSTR_SCONN.SCONN120_H61426002(CHIPS)':
 'IOE14': CDS_PINID='IOE14';
NODE_NAME     J6B1 F2
 '@BASEBOARD_FAB2_LIB.BASEBOARD_FAB2(SCH_1):PAGE194_I56@MSTR_SCONN.SCONN120_H61426002(CHIPS)':
 'IOF2': CDS_PINID='IOF2';
NODE_NAME     J6B1 F3
 '@BASEBOARD_FAB2_LIB.BASEBOARD_FAB2(SCH_1):PAGE194_I56@MSTR_SCONN.SCONN120_H61426002(CHIPS)':
 'IOF3': CDS_PINID='IOF3';
NODE_NAME     J6B1 F4
 '@BASEBOARD_FAB2_LIB.BASEBOARD_FAB2(SCH_1):PAGE194_I56@MSTR_SCONN.SCONN120_H61426002(CHIPS)':
 'IOF4': CDS_PINID='IOF4';
NODE_NAME     J6B1 F5
 '@BASEBOARD_FAB2_LIB.BASEBOARD_FAB2(SCH_1):PAGE194_I56@MSTR_SCONN.SCONN120_H61426002(CHIPS)':
 'IOF5': CDS_PINID='IOF5';
NODE_NAME     J6B1 F6
 '@BASEBOARD_FAB2_LIB.BASEBOARD_FAB2(SCH_1):PAGE194_I56@MSTR_SCONN.SCONN120_H61426002(CHIPS)':
 'IOF6': CDS_PINID='IOF6';
NODE_NAME     J6B1 F7
 '@BASEBOARD_FAB2_LIB.BASEBOARD_FAB2(SCH_1):PAGE194_I56@MSTR_SCONN.SCONN120_H61426002(CHIPS)':
 'IOF7': CDS_PINID='IOF7';
NODE_NAME     J6B1 F9
 '@BASEBOARD_FAB2_LIB.BASEBOARD_FAB2(SCH_1):PAGE194_I56@MSTR_SCONN.SCONN120_H61426002(CHIPS)':
 'IOF9': CDS_PINID='IOF9';
NODE_NAME     J6B1 F11
 '@BASEBOARD_FAB2_LIB.BASEBOARD_FAB2(SCH_1):PAGE194_I56@MSTR_SCONN.SCONN120_H61426002(CHIPS)':
 'IOF11': CDS_PINID='IOF11';
NODE_NAME     J6B1 F12
 '@BASEBOARD_FAB2_LIB.BASEBOARD_FAB2(SCH_1):PAGE194_I56@MSTR_SCONN.SCONN120_H61426002(CHIPS)':
 'IOF12': CDS_PINID='IOF12';
NODE_NAME     J6B1 F13
 '@BASEBOARD_FAB2_LIB.BASEBOARD_FAB2(SCH_1):PAGE194_I56@MSTR_SCONN.SCONN120_H61426002(CHIPS)':
 'IOF13': CDS_PINID='IOF13';
NODE_NAME     J6B1 F14
 '@BASEBOARD_FAB2_LIB.BASEBOARD_FAB2(SCH_1):PAGE194_I56@MSTR_SCONN.SCONN120_H61426002(CHIPS)':
 'IOF14': CDS_PINID='IOF14';
NODE_NAME     C3N40 2
 '@BASEBOARD_FAB2_LIB.BASEBOARD_FAB2(SCH_1):PAGE194_I86@DEV_DISCRETE.CAP_A(CHIPS)':
 'B': CDS_PINID='B';
NODE_NAME     C3M46 2
 '@BASEBOARD_FAB2_LIB.BASEBOARD_FAB2(SCH_1):PAGE194_I99@DEV_DISCRETE.CAP_A(CHIPS)':
 'B': CDS_PINID='B';
NODE_NAME     C3N14 2
 '@BASEBOARD_FAB2_LIB.BASEBOARD_FAB2(SCH_1):PAGE194_I101@MSTR_DISCRETE.CAPP(CHIPS)':
 'B': CDS_PINID='B';
NODE_NAME     C3T1 2
 '@BASEBOARD_FAB2_LIB.BASEBOARD_FAB2(SCH_1):PAGE194_I149@DEV_DISCRETE.CAP_A(CHIPS)':
 'B': CDS_PINID='B';
NODE_NAME     C3T2 2
 '@BASEBOARD_FAB2_LIB.BASEBOARD_FAB2(SCH_1):PAGE194_I150@DEV_DISCRETE.CAP_A(CHIPS)':
 'B': CDS_PINID='B';
NODE_NAME     R7C24 2
 '@BASEBOARD_FAB2_LIB.BASEBOARD_FAB2(SCH_1):PAGE194_I155@MSTR_DISCRETE.RES(CHIPS)':
 'B': CDS_PINID='B';
NODE_NAME     R3N29 2
 '@BASEBOARD_FAB2_LIB.BASEBOARD_FAB2(SCH_1):PAGE194_I156@MSTR_DISCRETE.RES(CHIPS)':
 'B': CDS_PINID='B';
NODE_NAME     RM1E1 1
 '@BASEBOARD_FAB2_LIB.BASEBOARD_FAB2(SCH_1):PAGE195_I26@MSTR_CONN.CONN3_G98259001(CHIPS)':
 'IO1': CDS_PINID='IO1';
NODE_NAME     RM1E1 2
 '@BASEBOARD_FAB2_LIB.BASEBOARD_FAB2(SCH_1):PAGE195_I26@MSTR_CONN.CONN3_G98259001(CHIPS)':
 'IO2': CDS_PINID='IO2';
NODE_NAME     RM1E1 3
 '@BASEBOARD_FAB2_LIB.BASEBOARD_FAB2(SCH_1):PAGE195_I26@MSTR_CONN.CONN3_G98259001(CHIPS)':
 'IO3': CDS_PINID='IO3';
NODE_NAME     C9R5 2
 '@BASEBOARD_FAB2_LIB.BASEBOARD_FAB2(SCH_1):PAGE195_I31@MSTR_DISCRETE.CAP(CHIPS)':
 'B': CDS_PINID='B';
NODE_NAME     C1E12 2
 '@BASEBOARD_FAB2_LIB.BASEBOARD_FAB2(SCH_1):PAGE195_I32@MSTR_DISCRETE.CAP(CHIPS)':
 'B': CDS_PINID='B';
NODE_NAME     C1E15 2
 '@BASEBOARD_FAB2_LIB.BASEBOARD_FAB2(SCH_1):PAGE195_I35@MSTR_DISCRETE.CAP(CHIPS)':
 'B': CDS_PINID='B';
NODE_NAME     C9R12 2
 '@BASEBOARD_FAB2_LIB.BASEBOARD_FAB2(SCH_1):PAGE195_I36@DEV_DISCRETE.CAP_A(CHIPS)':
 'B': CDS_PINID='B';
NODE_NAME     C9R6 2
 '@BASEBOARD_FAB2_LIB.BASEBOARD_FAB2(SCH_1):PAGE195_I37@DEV_DISCRETE.CAP_A(CHIPS)':
 'B': CDS_PINID='B';
NODE_NAME     C1E17 2
 '@BASEBOARD_FAB2_LIB.BASEBOARD_FAB2(SCH_1):PAGE195_I38@DEV_DISCRETE.CAP_A(CHIPS)':
 'B': CDS_PINID='B';
NODE_NAME     C1E16 2
 '@BASEBOARD_FAB2_LIB.BASEBOARD_FAB2(SCH_1):PAGE195_I39@DEV_DISCRETE.CAP_A(CHIPS)':
 'B': CDS_PINID='B';
NODE_NAME     TH4G1 1
 '@BASEBOARD_FAB2_LIB.BASEBOARD_FAB2(SCH_1):PAGE195_I49@MSTR_MISC.MTG_KEYHOLE(CHIPS)':
 '1': CDS_PINID='\1\';
NODE_NAME     TH9G1 1
 '@BASEBOARD_FAB2_LIB.BASEBOARD_FAB2(SCH_1):PAGE195_I52@MSTR_MISC.MTG_KEYHOLE(CHIPS)':
 '1': CDS_PINID='\1\';
NODE_NAME     TH9A1 1
 '@BASEBOARD_FAB2_LIB.BASEBOARD_FAB2(SCH_1):PAGE195_I54@MSTR_MISC.MTG_KEYHOLE(CHIPS)':
 '1': CDS_PINID='\1\';
NODE_NAME     TH1A1 1
 '@BASEBOARD_FAB2_LIB.BASEBOARD_FAB2(SCH_1):PAGE195_I56@MSTR_MISC.MTG_KEYHOLE(CHIPS)':
 '1': CDS_PINID='\1\';
NODE_NAME     TH4A1 1
 '@BASEBOARD_FAB2_LIB.BASEBOARD_FAB2(SCH_1):PAGE195_I62@MSTR_MISC.MTG_KEYHOLE(CHIPS)':
 '1': CDS_PINID='\1\';
NODE_NAME     TH7A1 1
 '@BASEBOARD_FAB2_LIB.BASEBOARD_FAB2(SCH_1):PAGE195_I65@MSTR_MISC.MTG_KEYHOLE(CHIPS)':
 '1': CDS_PINID='\1\';
NODE_NAME     TH7G1 1
 '@BASEBOARD_FAB2_LIB.BASEBOARD_FAB2(SCH_1):PAGE195_I67@MSTR_MISC.MTG_KEYHOLE(CHIPS)':
 '1': CDS_PINID='\1\';
NODE_NAME     C4F6 2
 '@BASEBOARD_FAB2_LIB.BASEBOARD_FAB2(SCH_1):PAGE195_I82@MSTR_DISCRETE.CAPP(CHIPS)':
 'B': CDS_PINID='B';
NODE_NAME     C4B13 2
 '@BASEBOARD_FAB2_LIB.BASEBOARD_FAB2(SCH_1):PAGE195_I83@MSTR_DISCRETE.CAPP(CHIPS)':
 'B': CDS_PINID='B';
NODE_NAME     C1B14 2
 '@BASEBOARD_FAB2_LIB.BASEBOARD_FAB2(SCH_1):PAGE195_I84@MSTR_DISCRETE.CAPP(CHIPS)':
 'B': CDS_PINID='B';
NODE_NAME     C1F7 2
 '@BASEBOARD_FAB2_LIB.BASEBOARD_FAB2(SCH_1):PAGE195_I85@MSTR_DISCRETE.CAPP(CHIPS)':
 'B': CDS_PINID='B';
NODE_NAME     C4F5 2
 '@BASEBOARD_FAB2_LIB.BASEBOARD_FAB2(SCH_1):PAGE195_I96@MSTR_DISCRETE.CAPP(CHIPS)':
 'B': CDS_PINID='B';
NODE_NAME     C4B14 2
 '@BASEBOARD_FAB2_LIB.BASEBOARD_FAB2(SCH_1):PAGE195_I97@MSTR_DISCRETE.CAPP(CHIPS)':
 'B': CDS_PINID='B';
NODE_NAME     C3T6 2
 '@BASEBOARD_FAB2_LIB.BASEBOARD_FAB2(SCH_1):PAGE195_I98@MSTR_DISCRETE.CAPP(CHIPS)':
 'B': CDS_PINID='B';
NODE_NAME     C9M3 2
 '@BASEBOARD_FAB2_LIB.BASEBOARD_FAB2(SCH_1):PAGE195_I99@MSTR_DISCRETE.CAPP(CHIPS)':
 'B': CDS_PINID='B';
NODE_NAME     C3B6 2
 '@BASEBOARD_FAB2_LIB.BASEBOARD_FAB2(SCH_1):PAGE195_I100@MSTR_DISCRETE.CAPP(CHIPS)':
 'B': CDS_PINID='B';
NODE_NAME     C1R23 2
 '@BASEBOARD_FAB2_LIB.BASEBOARD_FAB2(SCH_1):PAGE195_I101@MSTR_DISCRETE.CAPP(CHIPS)':
 'B': CDS_PINID='B';
NODE_NAME     C4M6 2
 '@BASEBOARD_FAB2_LIB.BASEBOARD_FAB2(SCH_1):PAGE195_I102@MSTR_DISCRETE.CAPP(CHIPS)':
 'B': CDS_PINID='B';
NODE_NAME     C1M5 2
 '@BASEBOARD_FAB2_LIB.BASEBOARD_FAB2(SCH_1):PAGE195_I103@MSTR_DISCRETE.CAPP(CHIPS)':
 'B': CDS_PINID='B';
NODE_NAME     C3T13 2
 '@BASEBOARD_FAB2_LIB.BASEBOARD_FAB2(SCH_1):PAGE195_I104@MSTR_DISCRETE.CAPP(CHIPS)':
 'B': CDS_PINID='B';
NODE_NAME     C4M7 2
 '@BASEBOARD_FAB2_LIB.BASEBOARD_FAB2(SCH_1):PAGE195_I105@MSTR_DISCRETE.CAPP(CHIPS)':
 'B': CDS_PINID='B';
NODE_NAME     C3T15 2
 '@BASEBOARD_FAB2_LIB.BASEBOARD_FAB2(SCH_1):PAGE195_I106@MSTR_DISCRETE.CAPP(CHIPS)':
 'B': CDS_PINID='B';
NODE_NAME     C7M6 2
 '@BASEBOARD_FAB2_LIB.BASEBOARD_FAB2(SCH_1):PAGE195_I108@MSTR_DISCRETE.CAPP(CHIPS)':
 'B': CDS_PINID='B';
NODE_NAME     C6N5 2
 '@BASEBOARD_FAB2_LIB.BASEBOARD_FAB2(SCH_1):PAGE195_I109@MSTR_DISCRETE.CAPP(CHIPS)':
 'B': CDS_PINID='B';
NODE_NAME     C9T3 2
 '@BASEBOARD_FAB2_LIB.BASEBOARD_FAB2(SCH_1):PAGE195_I111@MSTR_DISCRETE.CAPP(CHIPS)':
 'B': CDS_PINID='B';
NODE_NAME     C4F4 2
 '@BASEBOARD_FAB2_LIB.BASEBOARD_FAB2(SCH_1):PAGE195_I112@MSTR_DISCRETE.CAPP(CHIPS)':
 'B': CDS_PINID='B';
NODE_NAME     C3T3 2
 '@BASEBOARD_FAB2_LIB.BASEBOARD_FAB2(SCH_1):PAGE195_I113@MSTR_DISCRETE.CAPP(CHIPS)':
 'B': CDS_PINID='B';
NODE_NAME     XBT8G1 3
 '@BASEBOARD_FAB2_LIB.BASEBOARD_FAB2(SCH_1):PAGE196_I51@MSTR_DISCRETE.VERT_BATT_3PIN(CHIPS)':
 'N': CDS_PINID='N';
NODE_NAME     C3P45 2
 '@BASEBOARD_FAB2_LIB.BASEBOARD_FAB2(SCH_1):PAGE196_I60@MSTR_DISCRETE.CAP(CHIPS)':
 'B': CDS_PINID='B';
NODE_NAME     U7D3 2
 '@BASEBOARD_FAB2_LIB.BASEBOARD_FAB2(SCH_1):PAGE196_I70@MSTR_ANALOG.ADM1085(CHIPS)':
 'GND': CDS_PINID='GND';
NODE_NAME     C3P46 2
 '@BASEBOARD_FAB2_LIB.BASEBOARD_FAB2(SCH_1):PAGE196_I72@DEV_DISCRETE.CAP_A(CHIPS)':
 'B': CDS_PINID='B';
NODE_NAME     R3P51 2
 '@BASEBOARD_FAB2_LIB.BASEBOARD_FAB2(SCH_1):PAGE196_I75@MSTR_DISCRETE.RES(CHIPS)':
 'B': CDS_PINID='B';
NODE_NAME     C1L16 2
 '@BASEBOARD_FAB2_LIB.BASEBOARD_FAB2(SCH_1):PAGE196_I81@DEV_DISCRETE.CAP_A(CHIPS)':
 'B': CDS_PINID='B';
NODE_NAME     C8E3 2
 '@BASEBOARD_FAB2_LIB.BASEBOARD_FAB2(SCH_1):PAGE196_I94@DEV_DISCRETE.CAP_A(CHIPS)':
 'B': CDS_PINID='B';
NODE_NAME     C2U26 2
 '@BASEBOARD_FAB2_LIB.BASEBOARD_FAB2(SCH_1):PAGE196_I102@DEV_DISCRETE.CAP_A(CHIPS)':
 'B': CDS_PINID='B';
NODE_NAME     U8D8 5
 '@BASEBOARD_FAB2_LIB.BASEBOARD_FAB2(SCH_1):PAGE196_I104@MSTR_VREG.TPS3700(CHIPS)':
 'GND': CDS_PINID='GND';
NODE_NAME     C8D4 2
 '@BASEBOARD_FAB2_LIB.BASEBOARD_FAB2(SCH_1):PAGE196_I105@DEV_DISCRETE.CAP_A(CHIPS)':
 'B': CDS_PINID='B';
NODE_NAME     R8D37 2
 '@BASEBOARD_FAB2_LIB.BASEBOARD_FAB2(SCH_1):PAGE196_I115@MSTR_DISCRETE.RES(CHIPS)':
 'B': CDS_PINID='B';
NODE_NAME     EU2T1 4
 '@BASEBOARD_FAB2_LIB.BASEBOARD_FAB2(SCH_1):PAGE198_I1@MSTR_VREG.SLG55021(CHIPS)':
 'GND': CDS_PINID='GND';
NODE_NAME     EU2T1 9
 '@BASEBOARD_FAB2_LIB.BASEBOARD_FAB2(SCH_1):PAGE198_I1@MSTR_VREG.SLG55021(CHIPS)':
 'THPAD': CDS_PINID='THPAD';
NODE_NAME     EU8B1 4
 '@BASEBOARD_FAB2_LIB.BASEBOARD_FAB2(SCH_1):PAGE198_I13@MSTR_VREG.SLG55021(CHIPS)':
 'GND': CDS_PINID='GND';
NODE_NAME     EU8B1 9
 '@BASEBOARD_FAB2_LIB.BASEBOARD_FAB2(SCH_1):PAGE198_I13@MSTR_VREG.SLG55021(CHIPS)':
 'THPAD': CDS_PINID='THPAD';
NODE_NAME     EU7E1 4
 '@BASEBOARD_FAB2_LIB.BASEBOARD_FAB2(SCH_1):PAGE198_I19@MSTR_VREG.SLG55021(CHIPS)':
 'GND': CDS_PINID='GND';
NODE_NAME     EU7E1 9
 '@BASEBOARD_FAB2_LIB.BASEBOARD_FAB2(SCH_1):PAGE198_I19@MSTR_VREG.SLG55021(CHIPS)':
 'THPAD': CDS_PINID='THPAD';
NODE_NAME     C8F17 2
 '@BASEBOARD_FAB2_LIB.BASEBOARD_FAB2(SCH_1):PAGE198_I24@DEV_DISCRETE.CAP_A(CHIPS)':
 'B': CDS_PINID='B';
NODE_NAME     C8B8 2
 '@BASEBOARD_FAB2_LIB.BASEBOARD_FAB2(SCH_1):PAGE198_I26@DEV_DISCRETE.CAP_A(CHIPS)':
 'B': CDS_PINID='B';
NODE_NAME     C8E19 2
 '@BASEBOARD_FAB2_LIB.BASEBOARD_FAB2(SCH_1):PAGE198_I28@DEV_DISCRETE.CAP_A(CHIPS)':
 'B': CDS_PINID='B';
NODE_NAME     C8B5 2
 '@BASEBOARD_FAB2_LIB.BASEBOARD_FAB2(SCH_1):PAGE198_I37@DEV_DISCRETE.CAP_A(CHIPS)':
 'B': CDS_PINID='B';
NODE_NAME     C8B12 2
 '@BASEBOARD_FAB2_LIB.BASEBOARD_FAB2(SCH_1):PAGE198_I38@MSTR_DISCRETE.CAP(CHIPS)':
 'B': CDS_PINID='B';
NODE_NAME     C8B6 2
 '@BASEBOARD_FAB2_LIB.BASEBOARD_FAB2(SCH_1):PAGE198_I40@MSTR_DISCRETE.CAP(CHIPS)':
 'B': CDS_PINID='B';
NODE_NAME     C8B7 2
 '@BASEBOARD_FAB2_LIB.BASEBOARD_FAB2(SCH_1):PAGE198_I41@DEV_DISCRETE.CAP_A(CHIPS)':
 'B': CDS_PINID='B';
NODE_NAME     C2T36 2
 '@BASEBOARD_FAB2_LIB.BASEBOARD_FAB2(SCH_1):PAGE198_I43@DEV_DISCRETE.CAP_A(CHIPS)':
 'B': CDS_PINID='B';
NODE_NAME     C2U1 2
 '@BASEBOARD_FAB2_LIB.BASEBOARD_FAB2(SCH_1):PAGE198_I44@MSTR_DISCRETE.CAP(CHIPS)':
 'B': CDS_PINID='B';
NODE_NAME     C2U19 2
 '@BASEBOARD_FAB2_LIB.BASEBOARD_FAB2(SCH_1):PAGE198_I46@DEV_DISCRETE.CAP_A(CHIPS)':
 'B': CDS_PINID='B';
NODE_NAME     C2U2 2
 '@BASEBOARD_FAB2_LIB.BASEBOARD_FAB2(SCH_1):PAGE198_I47@MSTR_DISCRETE.CAP(CHIPS)':
 'B': CDS_PINID='B';
NODE_NAME     C7E9 2
 '@BASEBOARD_FAB2_LIB.BASEBOARD_FAB2(SCH_1):PAGE198_I49@DEV_DISCRETE.CAP_A(CHIPS)':
 'B': CDS_PINID='B';
NODE_NAME     C7E8 2
 '@BASEBOARD_FAB2_LIB.BASEBOARD_FAB2(SCH_1):PAGE198_I50@MSTR_DISCRETE.CAP(CHIPS)':
 'B': CDS_PINID='B';
NODE_NAME     C7E5 2
 '@BASEBOARD_FAB2_LIB.BASEBOARD_FAB2(SCH_1):PAGE198_I52@DEV_DISCRETE.CAP_A(CHIPS)':
 'B': CDS_PINID='B';
NODE_NAME     C7E6 2
 '@BASEBOARD_FAB2_LIB.BASEBOARD_FAB2(SCH_1):PAGE198_I53@MSTR_DISCRETE.CAP(CHIPS)':
 'B': CDS_PINID='B';
NODE_NAME     C1B18 2
 '@BASEBOARD_FAB2_LIB.BASEBOARD_FAB2(SCH_1):PAGE198_I61@MSTR_DISCRETE.CAP(CHIPS)':
 'B': CDS_PINID='B';
NODE_NAME     C1B19 2
 '@BASEBOARD_FAB2_LIB.BASEBOARD_FAB2(SCH_1):PAGE198_I64@DEV_DISCRETE.CAP_A(CHIPS)':
 'B': CDS_PINID='B';
NODE_NAME     C9M6 2
 '@BASEBOARD_FAB2_LIB.BASEBOARD_FAB2(SCH_1):PAGE198_I67@DEV_DISCRETE.CAP_A(CHIPS)':
 'B': CDS_PINID='B';
NODE_NAME     EU9M1 4
 '@BASEBOARD_FAB2_LIB.BASEBOARD_FAB2(SCH_1):PAGE198_I69@MSTR_VREG.SLG55021(CHIPS)':
 'GND': CDS_PINID='GND';
NODE_NAME     EU9M1 9
 '@BASEBOARD_FAB2_LIB.BASEBOARD_FAB2(SCH_1):PAGE198_I69@MSTR_VREG.SLG55021(CHIPS)':
 'THPAD': CDS_PINID='THPAD';
NODE_NAME     C9M10 2
 '@BASEBOARD_FAB2_LIB.BASEBOARD_FAB2(SCH_1):PAGE198_I74@MSTR_DISCRETE.CAP(CHIPS)':
 'B': CDS_PINID='B';
NODE_NAME     C9M9 2
 '@BASEBOARD_FAB2_LIB.BASEBOARD_FAB2(SCH_1):PAGE198_I76@DEV_DISCRETE.CAP_A(CHIPS)':
 'B': CDS_PINID='B';
NODE_NAME     R8B4 2
 '@BASEBOARD_FAB2_LIB.BASEBOARD_FAB2(SCH_1):PAGE198_I83@MSTR_DISCRETE.RES(CHIPS)':
 'B': CDS_PINID='B';
NODE_NAME     EU1D2 23
 '@BASEBOARD_FAB2_LIB.BASEBOARD_FAB2(SCH_1):PAGE199_I10@MSTR_CONTROLLER.ADM1278(CHIPS)':
 'PGND': CDS_PINID='PGND';
NODE_NAME     R1D41 1
 '@BASEBOARD_FAB2_LIB.BASEBOARD_FAB2(SCH_1):PAGE199_I19@MSTR_DISCRETE.RES(CHIPS)':
 'A': CDS_PINID='A';
NODE_NAME     R1D31 2
 '@BASEBOARD_FAB2_LIB.BASEBOARD_FAB2(SCH_1):PAGE199_I43@MSTR_DISCRETE.RES(CHIPS)':
 'B': CDS_PINID='B';
NODE_NAME     VR1D1 2
 '@BASEBOARD_FAB2_LIB.BASEBOARD_FAB2(SCH_1):PAGE199_I99@MSTR_DISCRETE.ZENER(CHIPS)':
 'A': CDS_PINID='A';
NODE_NAME     C1E2 2
 '@BASEBOARD_FAB2_LIB.BASEBOARD_FAB2(SCH_1):PAGE200_I155@MSTR_DISCRETE.CAP(CHIPS)':
 'B': CDS_PINID='B';
NODE_NAME     U9P1 5
 '@BASEBOARD_FAB2_LIB.BASEBOARD_FAB2(SCH_1):PAGE200_I163@MSTR_VREG.TPS3700(CHIPS)':
 'GND': CDS_PINID='GND';
NODE_NAME     U1D2 5
 '@BASEBOARD_FAB2_LIB.BASEBOARD_FAB2(SCH_1):PAGE200_I170@MSTR_VREG.TPS3700(CHIPS)':
 'GND': CDS_PINID='GND';
NODE_NAME     Q9P1 1
 '@BASEBOARD_FAB2_LIB.BASEBOARD_FAB2(SCH_1):PAGE200_I196@MSTR_DISCRETE.FET_N_DUAL(CHIPS)':
 'SOURCE'<0>: CDS_PINID='SOURCE(0)';
NODE_NAME     Q9P1 4
 '@BASEBOARD_FAB2_LIB.BASEBOARD_FAB2(SCH_1):PAGE200_I199@MSTR_DISCRETE.FET_N_DUAL(CHIPS)':
 'SOURCE'<0>: CDS_PINID='SOURCE(0)';
NODE_NAME     U9P2 5
 '@BASEBOARD_FAB2_LIB.BASEBOARD_FAB2(SCH_1):PAGE200_I200@MSTR_VREG.TPS3700(CHIPS)':
 'GND': CDS_PINID='GND';
NODE_NAME     C9P11 2
 '@BASEBOARD_FAB2_LIB.BASEBOARD_FAB2(SCH_1):PAGE200_I201@DEV_DISCRETE.CAP_A(CHIPS)':
 'B': CDS_PINID='B';
NODE_NAME     Q1D2 2
 '@BASEBOARD_FAB2_LIB.BASEBOARD_FAB2(SCH_1):PAGE200_I203@MSTR_DISCRETE.FET_N(CHIPS)':
 'SRC': CDS_PINID='SRC';
NODE_NAME     CR1F5 2
 '@BASEBOARD_FAB2_LIB.BASEBOARD_FAB2(SCH_1):PAGE200_I220@MSTR_DISCRETE.DIODE(CHIPS)':
 'A': CDS_PINID='A';
NODE_NAME     C4D25 2
 '@BASEBOARD_FAB2_LIB.BASEBOARD_FAB2(SCH_1):PAGE201_I30@DEV_DISCRETE.CAP_A(CHIPS)':
 'B': CDS_PINID='B';
NODE_NAME     C4D26 2
 '@BASEBOARD_FAB2_LIB.BASEBOARD_FAB2(SCH_1):PAGE201_I32@DEV_DISCRETE.CAP_A(CHIPS)':
 'B': CDS_PINID='B';
NODE_NAME     C4D15 2
 '@BASEBOARD_FAB2_LIB.BASEBOARD_FAB2(SCH_1):PAGE201_I37@DEV_DISCRETE.CAP_A(CHIPS)':
 'B': CDS_PINID='B';
NODE_NAME     C4D19 2
 '@BASEBOARD_FAB2_LIB.BASEBOARD_FAB2(SCH_1):PAGE201_I39@DEV_DISCRETE.CAP_A(CHIPS)':
 'B': CDS_PINID='B';
NODE_NAME     R4D32 2
 '@BASEBOARD_FAB2_LIB.BASEBOARD_FAB2(SCH_1):PAGE201_I55@MSTR_DISCRETE.RES(CHIPS)':
 'B': CDS_PINID='B';
NODE_NAME     C4D17 2
 '@BASEBOARD_FAB2_LIB.BASEBOARD_FAB2(SCH_1):PAGE201_I66@MSTR_DISCRETE.CAP(CHIPS)':
 'B': CDS_PINID='B';
NODE_NAME     C4D18 2
 '@BASEBOARD_FAB2_LIB.BASEBOARD_FAB2(SCH_1):PAGE201_I68@MSTR_DISCRETE.CAP(CHIPS)':
 'B': CDS_PINID='B';
NODE_NAME     R6P27 2
 '@BASEBOARD_FAB2_LIB.BASEBOARD_FAB2(SCH_1):PAGE201_I120@MSTR_DISCRETE.RES(CHIPS)':
 'B': CDS_PINID='B';
NODE_NAME     R6P28 2
 '@BASEBOARD_FAB2_LIB.BASEBOARD_FAB2(SCH_1):PAGE201_I121@MSTR_DISCRETE.RES(CHIPS)':
 'B': CDS_PINID='B';
NODE_NAME     C4D42 2
 '@BASEBOARD_FAB2_LIB.BASEBOARD_FAB2(SCH_1):PAGE201_I125@MSTR_DISCRETE.CAP(CHIPS)':
 'B': CDS_PINID='B';
NODE_NAME     EU4D4 49
 '@BASEBOARD_FAB2_LIB.BASEBOARD_FAB2(SCH_1):PAGE201_I155@MSTR_CONTROLLER.PXE1610B(CHIPS)':
 'THPAD': CDS_PINID='THPAD';
NODE_NAME     C6R7 2
 '@BASEBOARD_FAB2_LIB.BASEBOARD_FAB2(SCH_1):PAGE202_I9@DEV_DISCRETE.CAP_A(CHIPS)':
 'B': CDS_PINID='B';
NODE_NAME     C4E5 2
 '@BASEBOARD_FAB2_LIB.BASEBOARD_FAB2(SCH_1):PAGE202_I18@MSTR_DISCRETE.CAP(CHIPS)':
 'B': CDS_PINID='B';
NODE_NAME     C4E27 2
 '@BASEBOARD_FAB2_LIB.BASEBOARD_FAB2(SCH_1):PAGE202_I24@MSTR_DISCRETE.CAP(CHIPS)':
 'B': CDS_PINID='B';
NODE_NAME     C4E11 2
 '@BASEBOARD_FAB2_LIB.BASEBOARD_FAB2(SCH_1):PAGE202_I27@DEV_DISCRETE.CAP_A(CHIPS)':
 'B': CDS_PINID='B';
NODE_NAME     C4E10 2
 '@BASEBOARD_FAB2_LIB.BASEBOARD_FAB2(SCH_1):PAGE202_I34@MSTR_DISCRETE.CAP(CHIPS)':
 'B': CDS_PINID='B';
NODE_NAME     C4E20 2
 '@BASEBOARD_FAB2_LIB.BASEBOARD_FAB2(SCH_1):PAGE202_I35@DEV_DISCRETE.CAP_A(CHIPS)':
 'B': CDS_PINID='B';
NODE_NAME     C4E19 2
 '@BASEBOARD_FAB2_LIB.BASEBOARD_FAB2(SCH_1):PAGE202_I36@MSTR_DISCRETE.CAP(CHIPS)':
 'B': CDS_PINID='B';
NODE_NAME     C6R11 2
 '@BASEBOARD_FAB2_LIB.BASEBOARD_FAB2(SCH_1):PAGE202_I37@MSTR_DISCRETE.CAP(CHIPS)':
 'B': CDS_PINID='B';
NODE_NAME     C6P13 2
 '@BASEBOARD_FAB2_LIB.BASEBOARD_FAB2(SCH_1):PAGE202_I38@MSTR_DISCRETE.CAP(CHIPS)':
 'B': CDS_PINID='B';
NODE_NAME     C6R13 2
 '@BASEBOARD_FAB2_LIB.BASEBOARD_FAB2(SCH_1):PAGE202_I42@MSTR_DISCRETE.CAP(CHIPS)':
 'B': CDS_PINID='B';
NODE_NAME     C4E26 2
 '@BASEBOARD_FAB2_LIB.BASEBOARD_FAB2(SCH_1):PAGE202_I45@MSTR_DISCRETE.CAP(CHIPS)':
 'B': CDS_PINID='B';
NODE_NAME     C4D49 2
 '@BASEBOARD_FAB2_LIB.BASEBOARD_FAB2(SCH_1):PAGE202_I46@DEV_DISCRETE.CAP_A(CHIPS)':
 'B': CDS_PINID='B';
NODE_NAME     C4D48 2
 '@BASEBOARD_FAB2_LIB.BASEBOARD_FAB2(SCH_1):PAGE202_I47@MSTR_DISCRETE.CAP(CHIPS)':
 'B': CDS_PINID='B';
NODE_NAME     C6R4 2
 '@BASEBOARD_FAB2_LIB.BASEBOARD_FAB2(SCH_1):PAGE202_I48@MSTR_DISCRETE.CAP(CHIPS)':
 'B': CDS_PINID='B';
NODE_NAME     C6P22 2
 '@BASEBOARD_FAB2_LIB.BASEBOARD_FAB2(SCH_1):PAGE202_I49@MSTR_DISCRETE.CAP(CHIPS)':
 'B': CDS_PINID='B';
NODE_NAME     C6N8 2
 '@BASEBOARD_FAB2_LIB.BASEBOARD_FAB2(SCH_1):PAGE202_I51@MSTR_DISCRETE.CAP(CHIPS)':
 'B': CDS_PINID='B';
NODE_NAME     C4E3 2
 '@BASEBOARD_FAB2_LIB.BASEBOARD_FAB2(SCH_1):PAGE202_I61@DEV_DISCRETE.CAP_A(CHIPS)':
 'B': CDS_PINID='B';
NODE_NAME     C6P16 2
 '@BASEBOARD_FAB2_LIB.BASEBOARD_FAB2(SCH_1):PAGE202_I62@DEV_DISCRETE.CAP_A(CHIPS)':
 'B': CDS_PINID='B';
NODE_NAME     EU4E1 2
 '@BASEBOARD_FAB2_LIB.BASEBOARD_FAB2(SCH_1):PAGE202_I63@MSTR_DISCRETE.IR354XX(CHIPS)':
 'LGND': CDS_PINID='LGND';
NODE_NAME     EU4E1 5
 '@BASEBOARD_FAB2_LIB.BASEBOARD_FAB2(SCH_1):PAGE202_I63@MSTR_DISCRETE.IR354XX(CHIPS)':
 'PGND'<0>: CDS_PINID='PGND(0)';
NODE_NAME     EU4E1 7
 '@BASEBOARD_FAB2_LIB.BASEBOARD_FAB2(SCH_1):PAGE202_I63@MSTR_DISCRETE.IR354XX(CHIPS)':
 'PGND'<1>: CDS_PINID='PGND(1)';
NODE_NAME     EU4E1 40
 '@BASEBOARD_FAB2_LIB.BASEBOARD_FAB2(SCH_1):PAGE202_I63@MSTR_DISCRETE.IR354XX(CHIPS)':
 'PGND'<2>: CDS_PINID='PGND(2)';
NODE_NAME     EU4D6 2
 '@BASEBOARD_FAB2_LIB.BASEBOARD_FAB2(SCH_1):PAGE202_I64@MSTR_DISCRETE.IR354XX(CHIPS)':
 'LGND': CDS_PINID='LGND';
NODE_NAME     EU4D6 5
 '@BASEBOARD_FAB2_LIB.BASEBOARD_FAB2(SCH_1):PAGE202_I64@MSTR_DISCRETE.IR354XX(CHIPS)':
 'PGND'<0>: CDS_PINID='PGND(0)';
NODE_NAME     EU4D6 7
 '@BASEBOARD_FAB2_LIB.BASEBOARD_FAB2(SCH_1):PAGE202_I64@MSTR_DISCRETE.IR354XX(CHIPS)':
 'PGND'<1>: CDS_PINID='PGND(1)';
NODE_NAME     EU4D6 40
 '@BASEBOARD_FAB2_LIB.BASEBOARD_FAB2(SCH_1):PAGE202_I64@MSTR_DISCRETE.IR354XX(CHIPS)':
 'PGND'<2>: CDS_PINID='PGND(2)';
NODE_NAME     R4E22 2
 '@BASEBOARD_FAB2_LIB.BASEBOARD_FAB2(SCH_1):PAGE202_I65@MSTR_DISCRETE.RES(CHIPS)':
 'B': CDS_PINID='B';
NODE_NAME     R4E19 2
 '@BASEBOARD_FAB2_LIB.BASEBOARD_FAB2(SCH_1):PAGE202_I67@MSTR_DISCRETE.RES(CHIPS)':
 'B': CDS_PINID='B';
NODE_NAME     C6P24 2
 '@BASEBOARD_FAB2_LIB.BASEBOARD_FAB2(SCH_1):PAGE203_I1@MSTR_DISCRETE.CAP(CHIPS)':
 'B': CDS_PINID='B';
NODE_NAME     C6R6 2
 '@BASEBOARD_FAB2_LIB.BASEBOARD_FAB2(SCH_1):PAGE203_I2@MSTR_DISCRETE.CAP(CHIPS)':
 'B': CDS_PINID='B';
NODE_NAME     C6R3 2
 '@BASEBOARD_FAB2_LIB.BASEBOARD_FAB2(SCH_1):PAGE203_I16@MSTR_DISCRETE.CAPP(CHIPS)':
 'B': CDS_PINID='B';
NODE_NAME     C6R9 2
 '@BASEBOARD_FAB2_LIB.BASEBOARD_FAB2(SCH_1):PAGE203_I18@MSTR_DISCRETE.CAPP(CHIPS)':
 'B': CDS_PINID='B';
NODE_NAME     C6P3 2
 '@BASEBOARD_FAB2_LIB.BASEBOARD_FAB2(SCH_1):PAGE203_I25@DEV_DISCRETE.CAP_A(CHIPS)':
 'B': CDS_PINID='B';
NODE_NAME     C6P23 2
 '@BASEBOARD_FAB2_LIB.BASEBOARD_FAB2(SCH_1):PAGE203_I28@MSTR_DISCRETE.CAPP(CHIPS)':
 'B': CDS_PINID='B';
NODE_NAME     C6P14 2
 '@BASEBOARD_FAB2_LIB.BASEBOARD_FAB2(SCH_1):PAGE203_I29@MSTR_DISCRETE.CAPP(CHIPS)':
 'B': CDS_PINID='B';
NODE_NAME     C6P18 2
 '@BASEBOARD_FAB2_LIB.BASEBOARD_FAB2(SCH_1):PAGE203_I30@MSTR_DISCRETE.CAPP(CHIPS)':
 'B': CDS_PINID='B';
NODE_NAME     C6P8 2
 '@BASEBOARD_FAB2_LIB.BASEBOARD_FAB2(SCH_1):PAGE203_I32@MSTR_DISCRETE.CAPP(CHIPS)':
 'B': CDS_PINID='B';
NODE_NAME     C6N9 2
 '@BASEBOARD_FAB2_LIB.BASEBOARD_FAB2(SCH_1):PAGE203_I34@MSTR_DISCRETE.CAPP(CHIPS)':
 'B': CDS_PINID='B';
NODE_NAME     C4D13 2
 '@BASEBOARD_FAB2_LIB.BASEBOARD_FAB2(SCH_1):PAGE203_I40@MSTR_DISCRETE.CAP(CHIPS)':
 'B': CDS_PINID='B';
NODE_NAME     C4D16 2
 '@BASEBOARD_FAB2_LIB.BASEBOARD_FAB2(SCH_1):PAGE203_I45@MSTR_DISCRETE.CAP(CHIPS)':
 'B': CDS_PINID='B';
NODE_NAME     C4D35 2
 '@BASEBOARD_FAB2_LIB.BASEBOARD_FAB2(SCH_1):PAGE203_I46@DEV_DISCRETE.CAP_A(CHIPS)':
 'B': CDS_PINID='B';
NODE_NAME     C4D30 2
 '@BASEBOARD_FAB2_LIB.BASEBOARD_FAB2(SCH_1):PAGE203_I47@MSTR_DISCRETE.CAP(CHIPS)':
 'B': CDS_PINID='B';
NODE_NAME     C4D5 2
 '@BASEBOARD_FAB2_LIB.BASEBOARD_FAB2(SCH_1):PAGE203_I48@MSTR_DISCRETE.CAP(CHIPS)':
 'B': CDS_PINID='B';
NODE_NAME     C4D7 2
 '@BASEBOARD_FAB2_LIB.BASEBOARD_FAB2(SCH_1):PAGE203_I51@MSTR_DISCRETE.CAP(CHIPS)':
 'B': CDS_PINID='B';
NODE_NAME     C4D11 2
 '@BASEBOARD_FAB2_LIB.BASEBOARD_FAB2(SCH_1):PAGE203_I52@DEV_DISCRETE.CAP_A(CHIPS)':
 'B': CDS_PINID='B';
NODE_NAME     C4D10 2
 '@BASEBOARD_FAB2_LIB.BASEBOARD_FAB2(SCH_1):PAGE203_I53@MSTR_DISCRETE.CAP(CHIPS)':
 'B': CDS_PINID='B';
NODE_NAME     C6P19 2
 '@BASEBOARD_FAB2_LIB.BASEBOARD_FAB2(SCH_1):PAGE203_I54@MSTR_DISCRETE.CAP(CHIPS)':
 'B': CDS_PINID='B';
NODE_NAME     C6P20 2
 '@BASEBOARD_FAB2_LIB.BASEBOARD_FAB2(SCH_1):PAGE203_I57@MSTR_DISCRETE.CAP(CHIPS)':
 'B': CDS_PINID='B';
NODE_NAME     C6P15 2
 '@BASEBOARD_FAB2_LIB.BASEBOARD_FAB2(SCH_1):PAGE203_I58@MSTR_DISCRETE.CAP(CHIPS)':
 'B': CDS_PINID='B';
NODE_NAME     C6P7 2
 '@BASEBOARD_FAB2_LIB.BASEBOARD_FAB2(SCH_1):PAGE203_I59@MSTR_DISCRETE.CAP(CHIPS)':
 'B': CDS_PINID='B';
NODE_NAME     C6P21 2
 '@BASEBOARD_FAB2_LIB.BASEBOARD_FAB2(SCH_1):PAGE203_I66@DEV_DISCRETE.CAP_A(CHIPS)':
 'B': CDS_PINID='B';
NODE_NAME     R4E13 2
 '@BASEBOARD_FAB2_LIB.BASEBOARD_FAB2(SCH_1):PAGE203_I67@MSTR_DISCRETE.RES(CHIPS)':
 'B': CDS_PINID='B';
NODE_NAME     C4D34 2
 '@BASEBOARD_FAB2_LIB.BASEBOARD_FAB2(SCH_1):PAGE203_I68@DEV_DISCRETE.CAP_A(CHIPS)':
 'B': CDS_PINID='B';
NODE_NAME     C4D4 2
 '@BASEBOARD_FAB2_LIB.BASEBOARD_FAB2(SCH_1):PAGE203_I69@DEV_DISCRETE.CAP_A(CHIPS)':
 'B': CDS_PINID='B';
NODE_NAME     EU4D3 2
 '@BASEBOARD_FAB2_LIB.BASEBOARD_FAB2(SCH_1):PAGE203_I70@MSTR_DISCRETE.IR354XX(CHIPS)':
 'LGND': CDS_PINID='LGND';
NODE_NAME     EU4D3 5
 '@BASEBOARD_FAB2_LIB.BASEBOARD_FAB2(SCH_1):PAGE203_I70@MSTR_DISCRETE.IR354XX(CHIPS)':
 'PGND'<0>: CDS_PINID='PGND(0)';
NODE_NAME     EU4D3 7
 '@BASEBOARD_FAB2_LIB.BASEBOARD_FAB2(SCH_1):PAGE203_I70@MSTR_DISCRETE.IR354XX(CHIPS)':
 'PGND'<1>: CDS_PINID='PGND(1)';
NODE_NAME     EU4D3 40
 '@BASEBOARD_FAB2_LIB.BASEBOARD_FAB2(SCH_1):PAGE203_I70@MSTR_DISCRETE.IR354XX(CHIPS)':
 'PGND'<2>: CDS_PINID='PGND(2)';
NODE_NAME     EU4D1 2
 '@BASEBOARD_FAB2_LIB.BASEBOARD_FAB2(SCH_1):PAGE203_I71@MSTR_DISCRETE.IR354XX(CHIPS)':
 'LGND': CDS_PINID='LGND';
NODE_NAME     EU4D1 5
 '@BASEBOARD_FAB2_LIB.BASEBOARD_FAB2(SCH_1):PAGE203_I71@MSTR_DISCRETE.IR354XX(CHIPS)':
 'PGND'<0>: CDS_PINID='PGND(0)';
NODE_NAME     EU4D1 7
 '@BASEBOARD_FAB2_LIB.BASEBOARD_FAB2(SCH_1):PAGE203_I71@MSTR_DISCRETE.IR354XX(CHIPS)':
 'PGND'<1>: CDS_PINID='PGND(1)';
NODE_NAME     EU4D1 40
 '@BASEBOARD_FAB2_LIB.BASEBOARD_FAB2(SCH_1):PAGE203_I71@MSTR_DISCRETE.IR354XX(CHIPS)':
 'PGND'<2>: CDS_PINID='PGND(2)';
NODE_NAME     R4D72 2
 '@BASEBOARD_FAB2_LIB.BASEBOARD_FAB2(SCH_1):PAGE203_I89@MSTR_DISCRETE.RES(CHIPS)':
 'B': CDS_PINID='B';
NODE_NAME     R4D71 2
 '@BASEBOARD_FAB2_LIB.BASEBOARD_FAB2(SCH_1):PAGE203_I91@MSTR_DISCRETE.RES(CHIPS)':
 'B': CDS_PINID='B';
NODE_NAME     C4D12 2
 '@BASEBOARD_FAB2_LIB.BASEBOARD_FAB2(SCH_1):PAGE204_I9@DEV_DISCRETE.CAP_A(CHIPS)':
 'B': CDS_PINID='B';
NODE_NAME     C4D47 2
 '@BASEBOARD_FAB2_LIB.BASEBOARD_FAB2(SCH_1):PAGE204_I18@MSTR_DISCRETE.CAP(CHIPS)':
 'B': CDS_PINID='B';
NODE_NAME     C4D46 2
 '@BASEBOARD_FAB2_LIB.BASEBOARD_FAB2(SCH_1):PAGE204_I34@MSTR_DISCRETE.CAP(CHIPS)':
 'B': CDS_PINID='B';
NODE_NAME     C4C19 2
 '@BASEBOARD_FAB2_LIB.BASEBOARD_FAB2(SCH_1):PAGE204_I35@DEV_DISCRETE.CAP_A(CHIPS)':
 'B': CDS_PINID='B';
NODE_NAME     C4C18 2
 '@BASEBOARD_FAB2_LIB.BASEBOARD_FAB2(SCH_1):PAGE204_I36@MSTR_DISCRETE.CAP(CHIPS)':
 'B': CDS_PINID='B';
NODE_NAME     C6N10 2
 '@BASEBOARD_FAB2_LIB.BASEBOARD_FAB2(SCH_1):PAGE204_I37@MSTR_DISCRETE.CAP(CHIPS)':
 'B': CDS_PINID='B';
NODE_NAME     C6P17 2
 '@BASEBOARD_FAB2_LIB.BASEBOARD_FAB2(SCH_1):PAGE204_I38@MSTR_DISCRETE.CAP(CHIPS)':
 'B': CDS_PINID='B';
NODE_NAME     C6N11 2
 '@BASEBOARD_FAB2_LIB.BASEBOARD_FAB2(SCH_1):PAGE204_I42@MSTR_DISCRETE.CAP(CHIPS)':
 'B': CDS_PINID='B';
NODE_NAME     C4D2 2
 '@BASEBOARD_FAB2_LIB.BASEBOARD_FAB2(SCH_1):PAGE204_I48@MSTR_DISCRETE.CAPP(CHIPS)':
 'B': CDS_PINID='B';
NODE_NAME     C4E16 2
 '@BASEBOARD_FAB2_LIB.BASEBOARD_FAB2(SCH_1):PAGE204_I50@MSTR_DISCRETE.CAPP(CHIPS)':
 'B': CDS_PINID='B';
NODE_NAME     R4E18 2
 '@BASEBOARD_FAB2_LIB.BASEBOARD_FAB2(SCH_1):PAGE204_I64@MSTR_DISCRETE.RES(CHIPS)':
 'B': CDS_PINID='B';
NODE_NAME     C4C12 2
 '@BASEBOARD_FAB2_LIB.BASEBOARD_FAB2(SCH_1):PAGE204_I67@MSTR_DISCRETE.CAPP(CHIPS)':
 'B': CDS_PINID='B';
NODE_NAME     C6R2 2
 '@BASEBOARD_FAB2_LIB.BASEBOARD_FAB2(SCH_1):PAGE204_I70@DEV_DISCRETE.CAP_A(CHIPS)':
 'B': CDS_PINID='B';
NODE_NAME     EU4C2 2
 '@BASEBOARD_FAB2_LIB.BASEBOARD_FAB2(SCH_1):PAGE204_I71@MSTR_DISCRETE.IR354XX(CHIPS)':
 'LGND': CDS_PINID='LGND';
NODE_NAME     EU4C2 5
 '@BASEBOARD_FAB2_LIB.BASEBOARD_FAB2(SCH_1):PAGE204_I71@MSTR_DISCRETE.IR354XX(CHIPS)':
 'PGND'<0>: CDS_PINID='PGND(0)';
NODE_NAME     EU4C2 7
 '@BASEBOARD_FAB2_LIB.BASEBOARD_FAB2(SCH_1):PAGE204_I71@MSTR_DISCRETE.IR354XX(CHIPS)':
 'PGND'<1>: CDS_PINID='PGND(1)';
NODE_NAME     EU4C2 40
 '@BASEBOARD_FAB2_LIB.BASEBOARD_FAB2(SCH_1):PAGE204_I71@MSTR_DISCRETE.IR354XX(CHIPS)':
 'PGND'<2>: CDS_PINID='PGND(2)';
NODE_NAME     R4D68 2
 '@BASEBOARD_FAB2_LIB.BASEBOARD_FAB2(SCH_1):PAGE204_I83@MSTR_DISCRETE.RES(CHIPS)':
 'B': CDS_PINID='B';
NODE_NAME     C6N7 2
 '@BASEBOARD_FAB2_LIB.BASEBOARD_FAB2(SCH_1):PAGE205_I5@DEV_DISCRETE.CAP_A(CHIPS)':
 'B': CDS_PINID='B';
NODE_NAME     C6N1 2
 '@BASEBOARD_FAB2_LIB.BASEBOARD_FAB2(SCH_1):PAGE205_I12@MSTR_DISCRETE.CAPP(CHIPS)':
 'B': CDS_PINID='B';
NODE_NAME     C6N4 2
 '@BASEBOARD_FAB2_LIB.BASEBOARD_FAB2(SCH_1):PAGE205_I14@MSTR_DISCRETE.CAPP(CHIPS)':
 'B': CDS_PINID='B';
NODE_NAME     C4C5 2
 '@BASEBOARD_FAB2_LIB.BASEBOARD_FAB2(SCH_1):PAGE205_I16@MSTR_DISCRETE.CAP(CHIPS)':
 'B': CDS_PINID='B';
NODE_NAME     C4C6 2
 '@BASEBOARD_FAB2_LIB.BASEBOARD_FAB2(SCH_1):PAGE205_I20@MSTR_DISCRETE.CAP(CHIPS)':
 'B': CDS_PINID='B';
NODE_NAME     R4C1 2
 '@BASEBOARD_FAB2_LIB.BASEBOARD_FAB2(SCH_1):PAGE205_I29@MSTR_DISCRETE.RES(CHIPS)':
 'B': CDS_PINID='B';
NODE_NAME     C4C10 2
 '@BASEBOARD_FAB2_LIB.BASEBOARD_FAB2(SCH_1):PAGE205_I31@DEV_DISCRETE.CAP_A(CHIPS)':
 'B': CDS_PINID='B';
NODE_NAME     C4C9 2
 '@BASEBOARD_FAB2_LIB.BASEBOARD_FAB2(SCH_1):PAGE205_I32@MSTR_DISCRETE.CAP(CHIPS)':
 'B': CDS_PINID='B';
NODE_NAME     C6N2 2
 '@BASEBOARD_FAB2_LIB.BASEBOARD_FAB2(SCH_1):PAGE205_I33@MSTR_DISCRETE.CAP(CHIPS)':
 'B': CDS_PINID='B';
NODE_NAME     C6N3 2
 '@BASEBOARD_FAB2_LIB.BASEBOARD_FAB2(SCH_1):PAGE205_I34@MSTR_DISCRETE.CAP(CHIPS)':
 'B': CDS_PINID='B';
NODE_NAME     C6N6 2
 '@BASEBOARD_FAB2_LIB.BASEBOARD_FAB2(SCH_1):PAGE205_I35@MSTR_DISCRETE.CAP(CHIPS)':
 'B': CDS_PINID='B';
NODE_NAME     C4C11 2
 '@BASEBOARD_FAB2_LIB.BASEBOARD_FAB2(SCH_1):PAGE205_I43@DEV_DISCRETE.CAP_A(CHIPS)':
 'B': CDS_PINID='B';
NODE_NAME     R6N4 2
 '@BASEBOARD_FAB2_LIB.BASEBOARD_FAB2(SCH_1):PAGE205_I45@MSTR_DISCRETE.RES(CHIPS)':
 'B': CDS_PINID='B';
NODE_NAME     EU4C1 2
 '@BASEBOARD_FAB2_LIB.BASEBOARD_FAB2(SCH_1):PAGE205_I46@MSTR_DISCRETE.IR354XX(CHIPS)':
 'LGND': CDS_PINID='LGND';
NODE_NAME     EU4C1 5
 '@BASEBOARD_FAB2_LIB.BASEBOARD_FAB2(SCH_1):PAGE205_I46@MSTR_DISCRETE.IR354XX(CHIPS)':
 'PGND'<0>: CDS_PINID='PGND(0)';
NODE_NAME     EU4C1 7
 '@BASEBOARD_FAB2_LIB.BASEBOARD_FAB2(SCH_1):PAGE205_I46@MSTR_DISCRETE.IR354XX(CHIPS)':
 'PGND'<1>: CDS_PINID='PGND(1)';
NODE_NAME     EU4C1 40
 '@BASEBOARD_FAB2_LIB.BASEBOARD_FAB2(SCH_1):PAGE205_I46@MSTR_DISCRETE.IR354XX(CHIPS)':
 'PGND'<2>: CDS_PINID='PGND(2)';
NODE_NAME     R4C13 2
 '@BASEBOARD_FAB2_LIB.BASEBOARD_FAB2(SCH_1):PAGE205_I62@MSTR_DISCRETE.RES(CHIPS)':
 'B': CDS_PINID='B';
NODE_NAME     C1C13 2
 '@BASEBOARD_FAB2_LIB.BASEBOARD_FAB2(SCH_1):PAGE206_I29@DEV_DISCRETE.CAP_A(CHIPS)':
 'B': CDS_PINID='B';
NODE_NAME     C1C14 2
 '@BASEBOARD_FAB2_LIB.BASEBOARD_FAB2(SCH_1):PAGE206_I31@DEV_DISCRETE.CAP_A(CHIPS)':
 'B': CDS_PINID='B';
NODE_NAME     C1C7 2
 '@BASEBOARD_FAB2_LIB.BASEBOARD_FAB2(SCH_1):PAGE206_I41@DEV_DISCRETE.CAP_A(CHIPS)':
 'B': CDS_PINID='B';
NODE_NAME     C1C9 2
 '@BASEBOARD_FAB2_LIB.BASEBOARD_FAB2(SCH_1):PAGE206_I42@DEV_DISCRETE.CAP_A(CHIPS)':
 'B': CDS_PINID='B';
NODE_NAME     R1C16 2
 '@BASEBOARD_FAB2_LIB.BASEBOARD_FAB2(SCH_1):PAGE206_I56@MSTR_DISCRETE.RES(CHIPS)':
 'B': CDS_PINID='B';
NODE_NAME     C1C10 2
 '@BASEBOARD_FAB2_LIB.BASEBOARD_FAB2(SCH_1):PAGE206_I69@MSTR_DISCRETE.CAP(CHIPS)':
 'B': CDS_PINID='B';
NODE_NAME     C1C11 2
 '@BASEBOARD_FAB2_LIB.BASEBOARD_FAB2(SCH_1):PAGE206_I71@MSTR_DISCRETE.CAP(CHIPS)':
 'B': CDS_PINID='B';
NODE_NAME     R9N7 2
 '@BASEBOARD_FAB2_LIB.BASEBOARD_FAB2(SCH_1):PAGE206_I111@MSTR_DISCRETE.RES(CHIPS)':
 'B': CDS_PINID='B';
NODE_NAME     R9N8 2
 '@BASEBOARD_FAB2_LIB.BASEBOARD_FAB2(SCH_1):PAGE206_I112@MSTR_DISCRETE.RES(CHIPS)':
 'B': CDS_PINID='B';
NODE_NAME     C1C23 2
 '@BASEBOARD_FAB2_LIB.BASEBOARD_FAB2(SCH_1):PAGE206_I114@MSTR_DISCRETE.CAP(CHIPS)':
 'B': CDS_PINID='B';
NODE_NAME     EU1C2 49
 '@BASEBOARD_FAB2_LIB.BASEBOARD_FAB2(SCH_1):PAGE206_I130@MSTR_CONTROLLER.PXE1610B(CHIPS)':
 'THPAD': CDS_PINID='THPAD';
NODE_NAME     C9R8 2
 '@BASEBOARD_FAB2_LIB.BASEBOARD_FAB2(SCH_1):PAGE207_I8@DEV_DISCRETE.CAP_A(CHIPS)':
 'B': CDS_PINID='B';
NODE_NAME     C1E3 2
 '@BASEBOARD_FAB2_LIB.BASEBOARD_FAB2(SCH_1):PAGE207_I18@DEV_DISCRETE.CAP_A(CHIPS)':
 'B': CDS_PINID='B';
NODE_NAME     EU1E2 2
 '@BASEBOARD_FAB2_LIB.BASEBOARD_FAB2(SCH_1):PAGE207_I20@MSTR_DISCRETE.IR354XX(CHIPS)':
 'LGND': CDS_PINID='LGND';
NODE_NAME     EU1E2 5
 '@BASEBOARD_FAB2_LIB.BASEBOARD_FAB2(SCH_1):PAGE207_I20@MSTR_DISCRETE.IR354XX(CHIPS)':
 'PGND'<0>: CDS_PINID='PGND(0)';
NODE_NAME     EU1E2 7
 '@BASEBOARD_FAB2_LIB.BASEBOARD_FAB2(SCH_1):PAGE207_I20@MSTR_DISCRETE.IR354XX(CHIPS)':
 'PGND'<1>: CDS_PINID='PGND(1)';
NODE_NAME     EU1E2 40
 '@BASEBOARD_FAB2_LIB.BASEBOARD_FAB2(SCH_1):PAGE207_I20@MSTR_DISCRETE.IR354XX(CHIPS)':
 'PGND'<2>: CDS_PINID='PGND(2)';
NODE_NAME     C1E7 2
 '@BASEBOARD_FAB2_LIB.BASEBOARD_FAB2(SCH_1):PAGE207_I28@MSTR_DISCRETE.CAP(CHIPS)':
 'B': CDS_PINID='B';
NODE_NAME     C1E8 2
 '@BASEBOARD_FAB2_LIB.BASEBOARD_FAB2(SCH_1):PAGE207_I32@MSTR_DISCRETE.CAP(CHIPS)':
 'B': CDS_PINID='B';
NODE_NAME     C1E14 2
 '@BASEBOARD_FAB2_LIB.BASEBOARD_FAB2(SCH_1):PAGE207_I33@DEV_DISCRETE.CAP_A(CHIPS)':
 'B': CDS_PINID='B';
NODE_NAME     C1E13 2
 '@BASEBOARD_FAB2_LIB.BASEBOARD_FAB2(SCH_1):PAGE207_I34@MSTR_DISCRETE.CAP(CHIPS)':
 'B': CDS_PINID='B';
NODE_NAME     C1E25 2
 '@BASEBOARD_FAB2_LIB.BASEBOARD_FAB2(SCH_1):PAGE207_I36@MSTR_DISCRETE.CAP(CHIPS)':
 'B': CDS_PINID='B';
NODE_NAME     C1E24 2
 '@BASEBOARD_FAB2_LIB.BASEBOARD_FAB2(SCH_1):PAGE207_I40@MSTR_DISCRETE.CAP(CHIPS)':
 'B': CDS_PINID='B';
NODE_NAME     C1D34 2
 '@BASEBOARD_FAB2_LIB.BASEBOARD_FAB2(SCH_1):PAGE207_I41@DEV_DISCRETE.CAP_A(CHIPS)':
 'B': CDS_PINID='B';
NODE_NAME     C1D35 2
 '@BASEBOARD_FAB2_LIB.BASEBOARD_FAB2(SCH_1):PAGE207_I42@MSTR_DISCRETE.CAP(CHIPS)':
 'B': CDS_PINID='B';
NODE_NAME     C9R7 2
 '@BASEBOARD_FAB2_LIB.BASEBOARD_FAB2(SCH_1):PAGE207_I43@MSTR_DISCRETE.CAP(CHIPS)':
 'B': CDS_PINID='B';
NODE_NAME     C9R10 2
 '@BASEBOARD_FAB2_LIB.BASEBOARD_FAB2(SCH_1):PAGE207_I44@MSTR_DISCRETE.CAP(CHIPS)':
 'B': CDS_PINID='B';
NODE_NAME     C9R11 2
 '@BASEBOARD_FAB2_LIB.BASEBOARD_FAB2(SCH_1):PAGE207_I48@MSTR_DISCRETE.CAP(CHIPS)':
 'B': CDS_PINID='B';
NODE_NAME     C9P22 2
 '@BASEBOARD_FAB2_LIB.BASEBOARD_FAB2(SCH_1):PAGE207_I50@MSTR_DISCRETE.CAP(CHIPS)':
 'B': CDS_PINID='B';
NODE_NAME     C9P25 2
 '@BASEBOARD_FAB2_LIB.BASEBOARD_FAB2(SCH_1):PAGE207_I51@MSTR_DISCRETE.CAP(CHIPS)':
 'B': CDS_PINID='B';
NODE_NAME     C9P26 2
 '@BASEBOARD_FAB2_LIB.BASEBOARD_FAB2(SCH_1):PAGE207_I54@MSTR_DISCRETE.CAP(CHIPS)':
 'B': CDS_PINID='B';
NODE_NAME     C1E9 2
 '@BASEBOARD_FAB2_LIB.BASEBOARD_FAB2(SCH_1):PAGE207_I58@DEV_DISCRETE.CAP_A(CHIPS)':
 'B': CDS_PINID='B';
NODE_NAME     C9P3 2
 '@BASEBOARD_FAB2_LIB.BASEBOARD_FAB2(SCH_1):PAGE207_I59@DEV_DISCRETE.CAP_A(CHIPS)':
 'B': CDS_PINID='B';
NODE_NAME     R1E13 2
 '@BASEBOARD_FAB2_LIB.BASEBOARD_FAB2(SCH_1):PAGE207_I67@MSTR_DISCRETE.RES(CHIPS)':
 'B': CDS_PINID='B';
NODE_NAME     R1E14 2
 '@BASEBOARD_FAB2_LIB.BASEBOARD_FAB2(SCH_1):PAGE207_I68@MSTR_DISCRETE.RES(CHIPS)':
 'B': CDS_PINID='B';
NODE_NAME     R1E3 2
 '@BASEBOARD_FAB2_LIB.BASEBOARD_FAB2(SCH_1):PAGE208_I7@MSTR_DISCRETE.RES(CHIPS)':
 'B': CDS_PINID='B';
NODE_NAME     C1D14 2
 '@BASEBOARD_FAB2_LIB.BASEBOARD_FAB2(SCH_1):PAGE208_I9@DEV_DISCRETE.CAP_A(CHIPS)':
 'B': CDS_PINID='B';
NODE_NAME     C9P8 2
 '@BASEBOARD_FAB2_LIB.BASEBOARD_FAB2(SCH_1):PAGE208_I12@MSTR_DISCRETE.CAPP(CHIPS)':
 'B': CDS_PINID='B';
NODE_NAME     C9P5 2
 '@BASEBOARD_FAB2_LIB.BASEBOARD_FAB2(SCH_1):PAGE208_I14@MSTR_DISCRETE.CAPP(CHIPS)':
 'B': CDS_PINID='B';
NODE_NAME     C1D3 2
 '@BASEBOARD_FAB2_LIB.BASEBOARD_FAB2(SCH_1):PAGE208_I22@DEV_DISCRETE.CAP_A(CHIPS)':
 'B': CDS_PINID='B';
NODE_NAME     C9N24 2
 '@BASEBOARD_FAB2_LIB.BASEBOARD_FAB2(SCH_1):PAGE208_I24@MSTR_DISCRETE.CAPP(CHIPS)':
 'B': CDS_PINID='B';
NODE_NAME     C9R9 2
 '@BASEBOARD_FAB2_LIB.BASEBOARD_FAB2(SCH_1):PAGE208_I25@MSTR_DISCRETE.CAPP(CHIPS)':
 'B': CDS_PINID='B';
NODE_NAME     C9R3 2
 '@BASEBOARD_FAB2_LIB.BASEBOARD_FAB2(SCH_1):PAGE208_I26@MSTR_DISCRETE.CAPP(CHIPS)':
 'B': CDS_PINID='B';
NODE_NAME     EU1D3 2
 '@BASEBOARD_FAB2_LIB.BASEBOARD_FAB2(SCH_1):PAGE208_I27@MSTR_DISCRETE.IR354XX(CHIPS)':
 'LGND': CDS_PINID='LGND';
NODE_NAME     EU1D3 5
 '@BASEBOARD_FAB2_LIB.BASEBOARD_FAB2(SCH_1):PAGE208_I27@MSTR_DISCRETE.IR354XX(CHIPS)':
 'PGND'<0>: CDS_PINID='PGND(0)';
NODE_NAME     EU1D3 7
 '@BASEBOARD_FAB2_LIB.BASEBOARD_FAB2(SCH_1):PAGE208_I27@MSTR_DISCRETE.IR354XX(CHIPS)':
 'PGND'<1>: CDS_PINID='PGND(1)';
NODE_NAME     EU1D3 40
 '@BASEBOARD_FAB2_LIB.BASEBOARD_FAB2(SCH_1):PAGE208_I27@MSTR_DISCRETE.IR354XX(CHIPS)':
 'PGND'<2>: CDS_PINID='PGND(2)';
NODE_NAME     C9P23 2
 '@BASEBOARD_FAB2_LIB.BASEBOARD_FAB2(SCH_1):PAGE208_I28@MSTR_DISCRETE.CAPP(CHIPS)':
 'B': CDS_PINID='B';
NODE_NAME     C9P18 2
 '@BASEBOARD_FAB2_LIB.BASEBOARD_FAB2(SCH_1):PAGE208_I30@MSTR_DISCRETE.CAPP(CHIPS)':
 'B': CDS_PINID='B';
NODE_NAME     C1D16 2
 '@BASEBOARD_FAB2_LIB.BASEBOARD_FAB2(SCH_1):PAGE208_I38@MSTR_DISCRETE.CAP(CHIPS)':
 'B': CDS_PINID='B';
NODE_NAME     C1D17 2
 '@BASEBOARD_FAB2_LIB.BASEBOARD_FAB2(SCH_1):PAGE208_I43@MSTR_DISCRETE.CAP(CHIPS)':
 'B': CDS_PINID='B';
NODE_NAME     C1D28 2
 '@BASEBOARD_FAB2_LIB.BASEBOARD_FAB2(SCH_1):PAGE208_I44@DEV_DISCRETE.CAP_A(CHIPS)':
 'B': CDS_PINID='B';
NODE_NAME     C1D23 2
 '@BASEBOARD_FAB2_LIB.BASEBOARD_FAB2(SCH_1):PAGE208_I45@MSTR_DISCRETE.CAP(CHIPS)':
 'B': CDS_PINID='B';
NODE_NAME     C1D6 2
 '@BASEBOARD_FAB2_LIB.BASEBOARD_FAB2(SCH_1):PAGE208_I46@MSTR_DISCRETE.CAP(CHIPS)':
 'B': CDS_PINID='B';
NODE_NAME     C1D7 2
 '@BASEBOARD_FAB2_LIB.BASEBOARD_FAB2(SCH_1):PAGE208_I50@MSTR_DISCRETE.CAP(CHIPS)':
 'B': CDS_PINID='B';
NODE_NAME     C1D13 2
 '@BASEBOARD_FAB2_LIB.BASEBOARD_FAB2(SCH_1):PAGE208_I51@DEV_DISCRETE.CAP_A(CHIPS)':
 'B': CDS_PINID='B';
NODE_NAME     C1D12 2
 '@BASEBOARD_FAB2_LIB.BASEBOARD_FAB2(SCH_1):PAGE208_I52@MSTR_DISCRETE.CAP(CHIPS)':
 'B': CDS_PINID='B';
NODE_NAME     C9P4 2
 '@BASEBOARD_FAB2_LIB.BASEBOARD_FAB2(SCH_1):PAGE208_I53@MSTR_DISCRETE.CAP(CHIPS)':
 'B': CDS_PINID='B';
NODE_NAME     C9P7 2
 '@BASEBOARD_FAB2_LIB.BASEBOARD_FAB2(SCH_1):PAGE208_I54@MSTR_DISCRETE.CAP(CHIPS)':
 'B': CDS_PINID='B';
NODE_NAME     C9P9 2
 '@BASEBOARD_FAB2_LIB.BASEBOARD_FAB2(SCH_1):PAGE208_I55@MSTR_DISCRETE.CAP(CHIPS)':
 'B': CDS_PINID='B';
NODE_NAME     C9P24 2
 '@BASEBOARD_FAB2_LIB.BASEBOARD_FAB2(SCH_1):PAGE208_I58@MSTR_DISCRETE.CAP(CHIPS)':
 'B': CDS_PINID='B';
NODE_NAME     C9P1 2
 '@BASEBOARD_FAB2_LIB.BASEBOARD_FAB2(SCH_1):PAGE208_I59@MSTR_DISCRETE.CAP(CHIPS)':
 'B': CDS_PINID='B';
NODE_NAME     C9P2 2
 '@BASEBOARD_FAB2_LIB.BASEBOARD_FAB2(SCH_1):PAGE208_I60@MSTR_DISCRETE.CAP(CHIPS)':
 'B': CDS_PINID='B';
NODE_NAME     C9P10 2
 '@BASEBOARD_FAB2_LIB.BASEBOARD_FAB2(SCH_1):PAGE208_I66@DEV_DISCRETE.CAP_A(CHIPS)':
 'B': CDS_PINID='B';
NODE_NAME     C9R2 2
 '@BASEBOARD_FAB2_LIB.BASEBOARD_FAB2(SCH_1):PAGE208_I67@DEV_DISCRETE.CAP_A(CHIPS)':
 'B': CDS_PINID='B';
NODE_NAME     EU1D1 2
 '@BASEBOARD_FAB2_LIB.BASEBOARD_FAB2(SCH_1):PAGE208_I71@MSTR_DISCRETE.IR354XX(CHIPS)':
 'LGND': CDS_PINID='LGND';
NODE_NAME     EU1D1 5
 '@BASEBOARD_FAB2_LIB.BASEBOARD_FAB2(SCH_1):PAGE208_I71@MSTR_DISCRETE.IR354XX(CHIPS)':
 'PGND'<0>: CDS_PINID='PGND(0)';
NODE_NAME     EU1D1 7
 '@BASEBOARD_FAB2_LIB.BASEBOARD_FAB2(SCH_1):PAGE208_I71@MSTR_DISCRETE.IR354XX(CHIPS)':
 'PGND'<1>: CDS_PINID='PGND(1)';
NODE_NAME     EU1D1 40
 '@BASEBOARD_FAB2_LIB.BASEBOARD_FAB2(SCH_1):PAGE208_I71@MSTR_DISCRETE.IR354XX(CHIPS)':
 'PGND'<2>: CDS_PINID='PGND(2)';
NODE_NAME     R1D54 2
 '@BASEBOARD_FAB2_LIB.BASEBOARD_FAB2(SCH_1):PAGE208_I75@MSTR_DISCRETE.RES(CHIPS)':
 'B': CDS_PINID='B';
NODE_NAME     R1D55 2
 '@BASEBOARD_FAB2_LIB.BASEBOARD_FAB2(SCH_1):PAGE208_I76@MSTR_DISCRETE.RES(CHIPS)':
 'B': CDS_PINID='B';
NODE_NAME     C9N27 2
 '@BASEBOARD_FAB2_LIB.BASEBOARD_FAB2(SCH_1):PAGE209_I5@MSTR_DISCRETE.CAP(CHIPS)':
 'B': CDS_PINID='B';
NODE_NAME     C9N26 2
 '@BASEBOARD_FAB2_LIB.BASEBOARD_FAB2(SCH_1):PAGE209_I7@MSTR_DISCRETE.CAP(CHIPS)':
 'B': CDS_PINID='B';
NODE_NAME     C9N25 2
 '@BASEBOARD_FAB2_LIB.BASEBOARD_FAB2(SCH_1):PAGE209_I8@MSTR_DISCRETE.CAP(CHIPS)':
 'B': CDS_PINID='B';
NODE_NAME     R1E8 2
 '@BASEBOARD_FAB2_LIB.BASEBOARD_FAB2(SCH_1):PAGE209_I9@MSTR_DISCRETE.RES(CHIPS)':
 'B': CDS_PINID='B';
NODE_NAME     C1C26 2
 '@BASEBOARD_FAB2_LIB.BASEBOARD_FAB2(SCH_1):PAGE209_I16@MSTR_DISCRETE.CAP(CHIPS)':
 'B': CDS_PINID='B';
NODE_NAME     C1C25 2
 '@BASEBOARD_FAB2_LIB.BASEBOARD_FAB2(SCH_1):PAGE209_I17@DEV_DISCRETE.CAP_A(CHIPS)':
 'B': CDS_PINID='B';
NODE_NAME     C1D32 2
 '@BASEBOARD_FAB2_LIB.BASEBOARD_FAB2(SCH_1):PAGE209_I18@MSTR_DISCRETE.CAP(CHIPS)':
 'B': CDS_PINID='B';
NODE_NAME     C1D33 2
 '@BASEBOARD_FAB2_LIB.BASEBOARD_FAB2(SCH_1):PAGE209_I22@MSTR_DISCRETE.CAP(CHIPS)':
 'B': CDS_PINID='B';
NODE_NAME     C1C1 2
 '@BASEBOARD_FAB2_LIB.BASEBOARD_FAB2(SCH_1):PAGE209_I35@MSTR_DISCRETE.CAPP(CHIPS)':
 'B': CDS_PINID='B';
NODE_NAME     C1E18 2
 '@BASEBOARD_FAB2_LIB.BASEBOARD_FAB2(SCH_1):PAGE209_I37@MSTR_DISCRETE.CAPP(CHIPS)':
 'B': CDS_PINID='B';
NODE_NAME     C1C2 2
 '@BASEBOARD_FAB2_LIB.BASEBOARD_FAB2(SCH_1):PAGE209_I38@MSTR_DISCRETE.CAPP(CHIPS)':
 'B': CDS_PINID='B';
NODE_NAME     C1D24 2
 '@BASEBOARD_FAB2_LIB.BASEBOARD_FAB2(SCH_1):PAGE209_I42@DEV_DISCRETE.CAP_A(CHIPS)':
 'B': CDS_PINID='B';
NODE_NAME     C9P20 2
 '@BASEBOARD_FAB2_LIB.BASEBOARD_FAB2(SCH_1):PAGE209_I55@DEV_DISCRETE.CAP_A(CHIPS)':
 'B': CDS_PINID='B';
NODE_NAME     EU1C3 2
 '@BASEBOARD_FAB2_LIB.BASEBOARD_FAB2(SCH_1):PAGE209_I56@MSTR_DISCRETE.IR354XX(CHIPS)':
 'LGND': CDS_PINID='LGND';
NODE_NAME     EU1C3 5
 '@BASEBOARD_FAB2_LIB.BASEBOARD_FAB2(SCH_1):PAGE209_I56@MSTR_DISCRETE.IR354XX(CHIPS)':
 'PGND'<0>: CDS_PINID='PGND(0)';
NODE_NAME     EU1C3 7
 '@BASEBOARD_FAB2_LIB.BASEBOARD_FAB2(SCH_1):PAGE209_I56@MSTR_DISCRETE.IR354XX(CHIPS)':
 'PGND'<1>: CDS_PINID='PGND(1)';
NODE_NAME     EU1C3 40
 '@BASEBOARD_FAB2_LIB.BASEBOARD_FAB2(SCH_1):PAGE209_I56@MSTR_DISCRETE.IR354XX(CHIPS)':
 'PGND'<2>: CDS_PINID='PGND(2)';
NODE_NAME     R1D52 2
 '@BASEBOARD_FAB2_LIB.BASEBOARD_FAB2(SCH_1):PAGE209_I59@MSTR_DISCRETE.RES(CHIPS)':
 'B': CDS_PINID='B';
NODE_NAME     C1C19 2
 '@BASEBOARD_FAB2_LIB.BASEBOARD_FAB2(SCH_1):PAGE210_I8@DEV_DISCRETE.CAP_A(CHIPS)':
 'B': CDS_PINID='B';
NODE_NAME     C9N11 2
 '@BASEBOARD_FAB2_LIB.BASEBOARD_FAB2(SCH_1):PAGE210_I12@MSTR_DISCRETE.CAPP(CHIPS)':
 'B': CDS_PINID='B';
NODE_NAME     C9N20 2
 '@BASEBOARD_FAB2_LIB.BASEBOARD_FAB2(SCH_1):PAGE210_I14@MSTR_DISCRETE.CAPP(CHIPS)':
 'B': CDS_PINID='B';
NODE_NAME     C1C4 2
 '@BASEBOARD_FAB2_LIB.BASEBOARD_FAB2(SCH_1):PAGE210_I22@MSTR_DISCRETE.CAP(CHIPS)':
 'B': CDS_PINID='B';
NODE_NAME     C1C5 2
 '@BASEBOARD_FAB2_LIB.BASEBOARD_FAB2(SCH_1):PAGE210_I26@MSTR_DISCRETE.CAP(CHIPS)':
 'B': CDS_PINID='B';
NODE_NAME     C1C17 2
 '@BASEBOARD_FAB2_LIB.BASEBOARD_FAB2(SCH_1):PAGE210_I27@DEV_DISCRETE.CAP_A(CHIPS)':
 'B': CDS_PINID='B';
NODE_NAME     C1C15 2
 '@BASEBOARD_FAB2_LIB.BASEBOARD_FAB2(SCH_1):PAGE210_I28@MSTR_DISCRETE.CAP(CHIPS)':
 'B': CDS_PINID='B';
NODE_NAME     R1C4 2
 '@BASEBOARD_FAB2_LIB.BASEBOARD_FAB2(SCH_1):PAGE210_I33@MSTR_DISCRETE.RES(CHIPS)':
 'B': CDS_PINID='B';
NODE_NAME     C9N13 2
 '@BASEBOARD_FAB2_LIB.BASEBOARD_FAB2(SCH_1):PAGE210_I35@MSTR_DISCRETE.CAP(CHIPS)':
 'B': CDS_PINID='B';
NODE_NAME     C9N19 2
 '@BASEBOARD_FAB2_LIB.BASEBOARD_FAB2(SCH_1):PAGE210_I36@MSTR_DISCRETE.CAP(CHIPS)':
 'B': CDS_PINID='B';
NODE_NAME     C9N21 2
 '@BASEBOARD_FAB2_LIB.BASEBOARD_FAB2(SCH_1):PAGE210_I38@MSTR_DISCRETE.CAP(CHIPS)':
 'B': CDS_PINID='B';
NODE_NAME     C9N22 2
 '@BASEBOARD_FAB2_LIB.BASEBOARD_FAB2(SCH_1):PAGE210_I44@DEV_DISCRETE.CAP_A(CHIPS)':
 'B': CDS_PINID='B';
NODE_NAME     R9N4 2
 '@BASEBOARD_FAB2_LIB.BASEBOARD_FAB2(SCH_1):PAGE210_I45@MSTR_DISCRETE.RES(CHIPS)':
 'B': CDS_PINID='B';
NODE_NAME     EU1C1 2
 '@BASEBOARD_FAB2_LIB.BASEBOARD_FAB2(SCH_1):PAGE210_I51@MSTR_DISCRETE.IR354XX(CHIPS)':
 'LGND': CDS_PINID='LGND';
NODE_NAME     EU1C1 5
 '@BASEBOARD_FAB2_LIB.BASEBOARD_FAB2(SCH_1):PAGE210_I51@MSTR_DISCRETE.IR354XX(CHIPS)':
 'PGND'<0>: CDS_PINID='PGND(0)';
NODE_NAME     EU1C1 7
 '@BASEBOARD_FAB2_LIB.BASEBOARD_FAB2(SCH_1):PAGE210_I51@MSTR_DISCRETE.IR354XX(CHIPS)':
 'PGND'<1>: CDS_PINID='PGND(1)';
NODE_NAME     EU1C1 40
 '@BASEBOARD_FAB2_LIB.BASEBOARD_FAB2(SCH_1):PAGE210_I51@MSTR_DISCRETE.IR354XX(CHIPS)':
 'PGND'<2>: CDS_PINID='PGND(2)';
NODE_NAME     R1C37 2
 '@BASEBOARD_FAB2_LIB.BASEBOARD_FAB2(SCH_1):PAGE210_I52@MSTR_DISCRETE.RES(CHIPS)':
 'B': CDS_PINID='B';
NODE_NAME     C3P4 2
 '@BASEBOARD_FAB2_LIB.BASEBOARD_FAB2(SCH_1):PAGE211_I11@DEV_DISCRETE.CAP_A(CHIPS)':
 'B': CDS_PINID='B';
NODE_NAME     C3P5 2
 '@BASEBOARD_FAB2_LIB.BASEBOARD_FAB2(SCH_1):PAGE211_I13@DEV_DISCRETE.CAP_A(CHIPS)':
 'B': CDS_PINID='B';
NODE_NAME     C3P3 2
 '@BASEBOARD_FAB2_LIB.BASEBOARD_FAB2(SCH_1):PAGE211_I20@DEV_DISCRETE.CAP_A(CHIPS)':
 'B': CDS_PINID='B';
NODE_NAME     C3P7 2
 '@BASEBOARD_FAB2_LIB.BASEBOARD_FAB2(SCH_1):PAGE211_I22@DEV_DISCRETE.CAP_A(CHIPS)':
 'B': CDS_PINID='B';
NODE_NAME     R3P16 2
 '@BASEBOARD_FAB2_LIB.BASEBOARD_FAB2(SCH_1):PAGE211_I32@MSTR_DISCRETE.RES(CHIPS)':
 'B': CDS_PINID='B';
NODE_NAME     R3N31 2
 '@BASEBOARD_FAB2_LIB.BASEBOARD_FAB2(SCH_1):PAGE211_I52@MSTR_DISCRETE.RES(CHIPS)':
 'B': CDS_PINID='B';
NODE_NAME     C3P6 2
 '@BASEBOARD_FAB2_LIB.BASEBOARD_FAB2(SCH_1):PAGE211_I71@MSTR_DISCRETE.CAP(CHIPS)':
 'B': CDS_PINID='B';
NODE_NAME     EU3P1 26
 '@BASEBOARD_FAB2_LIB.BASEBOARD_FAB2(SCH_1):PAGE211_I93@MSTR_CONTROLLER.PXE1110B(CHIPS)':
 'BISEN1': CDS_PINID='BISEN1';
NODE_NAME     EU3P1 27
 '@BASEBOARD_FAB2_LIB.BASEBOARD_FAB2(SCH_1):PAGE211_I93@MSTR_CONTROLLER.PXE1110B(CHIPS)':
 'GND'<0>: CDS_PINID='GND(0)';
NODE_NAME     EU3P1 23
 '@BASEBOARD_FAB2_LIB.BASEBOARD_FAB2(SCH_1):PAGE211_I93@MSTR_CONTROLLER.PXE1110B(CHIPS)':
 'GND'<1>: CDS_PINID='GND(1)';
NODE_NAME     EU3P1 41
 '@BASEBOARD_FAB2_LIB.BASEBOARD_FAB2(SCH_1):PAGE211_I93@MSTR_CONTROLLER.PXE1110B(CHIPS)':
 'THPAD': CDS_PINID='THPAD';
NODE_NAME     C3N35 2
 '@BASEBOARD_FAB2_LIB.BASEBOARD_FAB2(SCH_1):PAGE212_I18@MSTR_DISCRETE.CAPP(CHIPS)':
 'B': CDS_PINID='B';
NODE_NAME     C7C6 2
 '@BASEBOARD_FAB2_LIB.BASEBOARD_FAB2(SCH_1):PAGE212_I23@DEV_DISCRETE.CAP_A(CHIPS)':
 'B': CDS_PINID='B';
NODE_NAME     C7C18 2
 '@BASEBOARD_FAB2_LIB.BASEBOARD_FAB2(SCH_1):PAGE212_I33@MSTR_DISCRETE.CAP(CHIPS)':
 'B': CDS_PINID='B';
NODE_NAME     C7C17 2
 '@BASEBOARD_FAB2_LIB.BASEBOARD_FAB2(SCH_1):PAGE212_I36@MSTR_DISCRETE.CAP(CHIPS)':
 'B': CDS_PINID='B';
NODE_NAME     C7C11 2
 '@BASEBOARD_FAB2_LIB.BASEBOARD_FAB2(SCH_1):PAGE212_I38@DEV_DISCRETE.CAP_A(CHIPS)':
 'B': CDS_PINID='B';
NODE_NAME     C7C12 2
 '@BASEBOARD_FAB2_LIB.BASEBOARD_FAB2(SCH_1):PAGE212_I39@MSTR_DISCRETE.CAP(CHIPS)':
 'B': CDS_PINID='B';
NODE_NAME     C3N36 2
 '@BASEBOARD_FAB2_LIB.BASEBOARD_FAB2(SCH_1):PAGE212_I40@MSTR_DISCRETE.CAP(CHIPS)':
 'B': CDS_PINID='B';
NODE_NAME     C3N33 2
 '@BASEBOARD_FAB2_LIB.BASEBOARD_FAB2(SCH_1):PAGE212_I41@MSTR_DISCRETE.CAP(CHIPS)':
 'B': CDS_PINID='B';
NODE_NAME     C3N34 2
 '@BASEBOARD_FAB2_LIB.BASEBOARD_FAB2(SCH_1):PAGE212_I43@MSTR_DISCRETE.CAP(CHIPS)':
 'B': CDS_PINID='B';
NODE_NAME     R3N20 2
 '@BASEBOARD_FAB2_LIB.BASEBOARD_FAB2(SCH_1):PAGE212_I68@MSTR_DISCRETE.RES(CHIPS)':
 'B': CDS_PINID='B';
NODE_NAME     C7C10 2
 '@BASEBOARD_FAB2_LIB.BASEBOARD_FAB2(SCH_1):PAGE212_I77@DEV_DISCRETE.CAP_A(CHIPS)':
 'B': CDS_PINID='B';
NODE_NAME     R7C3 2
 '@BASEBOARD_FAB2_LIB.BASEBOARD_FAB2(SCH_1):PAGE212_I78@MSTR_DISCRETE.RES(CHIPS)':
 'B': CDS_PINID='B';
NODE_NAME     EU7C1 2
 '@BASEBOARD_FAB2_LIB.BASEBOARD_FAB2(SCH_1):PAGE212_I101@MSTR_DISCRETE.IR354XX(CHIPS)':
 'LGND': CDS_PINID='LGND';
NODE_NAME     EU7C1 5
 '@BASEBOARD_FAB2_LIB.BASEBOARD_FAB2(SCH_1):PAGE212_I101@MSTR_DISCRETE.IR354XX(CHIPS)':
 'PGND'<0>: CDS_PINID='PGND(0)';
NODE_NAME     EU7C1 7
 '@BASEBOARD_FAB2_LIB.BASEBOARD_FAB2(SCH_1):PAGE212_I101@MSTR_DISCRETE.IR354XX(CHIPS)':
 'PGND'<1>: CDS_PINID='PGND(1)';
NODE_NAME     EU7C1 40
 '@BASEBOARD_FAB2_LIB.BASEBOARD_FAB2(SCH_1):PAGE212_I101@MSTR_DISCRETE.IR354XX(CHIPS)':
 'PGND'<2>: CDS_PINID='PGND(2)';
NODE_NAME     R7C25 2
 '@BASEBOARD_FAB2_LIB.BASEBOARD_FAB2(SCH_1):PAGE212_I103@MSTR_DISCRETE.RES(CHIPS)':
 'B': CDS_PINID='B';
NODE_NAME     C4D31 2
 '@BASEBOARD_FAB2_LIB.BASEBOARD_FAB2(SCH_1):PAGE213_I9@DEV_DISCRETE.CAP_A(CHIPS)':
 'B': CDS_PINID='B';
NODE_NAME     C4D32 2
 '@BASEBOARD_FAB2_LIB.BASEBOARD_FAB2(SCH_1):PAGE213_I11@DEV_DISCRETE.CAP_A(CHIPS)':
 'B': CDS_PINID='B';
NODE_NAME     C4D36 2
 '@BASEBOARD_FAB2_LIB.BASEBOARD_FAB2(SCH_1):PAGE213_I17@DEV_DISCRETE.CAP_A(CHIPS)':
 'B': CDS_PINID='B';
NODE_NAME     R4D57 2
 '@BASEBOARD_FAB2_LIB.BASEBOARD_FAB2(SCH_1):PAGE213_I32@MSTR_DISCRETE.RES(CHIPS)':
 'B': CDS_PINID='B';
NODE_NAME     C4D38 2
 '@BASEBOARD_FAB2_LIB.BASEBOARD_FAB2(SCH_1):PAGE213_I35@DEV_DISCRETE.CAP_A(CHIPS)':
 'B': CDS_PINID='B';
NODE_NAME     C4D33 2
 '@BASEBOARD_FAB2_LIB.BASEBOARD_FAB2(SCH_1):PAGE213_I73@MSTR_DISCRETE.CAP(CHIPS)':
 'B': CDS_PINID='B';
NODE_NAME     EU4D5 26
 '@BASEBOARD_FAB2_LIB.BASEBOARD_FAB2(SCH_1):PAGE213_I96@MSTR_CONTROLLER.PXE1110B(CHIPS)':
 'BISEN1': CDS_PINID='BISEN1';
NODE_NAME     EU4D5 27
 '@BASEBOARD_FAB2_LIB.BASEBOARD_FAB2(SCH_1):PAGE213_I96@MSTR_CONTROLLER.PXE1110B(CHIPS)':
 'GND'<0>: CDS_PINID='GND(0)';
NODE_NAME     EU4D5 23
 '@BASEBOARD_FAB2_LIB.BASEBOARD_FAB2(SCH_1):PAGE213_I96@MSTR_CONTROLLER.PXE1110B(CHIPS)':
 'GND'<1>: CDS_PINID='GND(1)';
NODE_NAME     EU4D5 41
 '@BASEBOARD_FAB2_LIB.BASEBOARD_FAB2(SCH_1):PAGE213_I96@MSTR_CONTROLLER.PXE1110B(CHIPS)':
 'THPAD': CDS_PINID='THPAD';
NODE_NAME     C6R5 2
 '@BASEBOARD_FAB2_LIB.BASEBOARD_FAB2(SCH_1):PAGE214_I24@MSTR_DISCRETE.CAPP(CHIPS)':
 'B': CDS_PINID='B';
NODE_NAME     C7R1 2
 '@BASEBOARD_FAB2_LIB.BASEBOARD_FAB2(SCH_1):PAGE214_I65@DEV_DISCRETE.CAP_A(CHIPS)':
 'B': CDS_PINID='B';
NODE_NAME     C4E23 2
 '@BASEBOARD_FAB2_LIB.BASEBOARD_FAB2(SCH_1):PAGE214_I73@MSTR_DISCRETE.CAP(CHIPS)':
 'B': CDS_PINID='B';
NODE_NAME     C4E22 2
 '@BASEBOARD_FAB2_LIB.BASEBOARD_FAB2(SCH_1):PAGE214_I76@MSTR_DISCRETE.CAP(CHIPS)':
 'B': CDS_PINID='B';
NODE_NAME     C4E13 2
 '@BASEBOARD_FAB2_LIB.BASEBOARD_FAB2(SCH_1):PAGE214_I77@DEV_DISCRETE.CAP_A(CHIPS)':
 'B': CDS_PINID='B';
NODE_NAME     C4E15 2
 '@BASEBOARD_FAB2_LIB.BASEBOARD_FAB2(SCH_1):PAGE214_I79@MSTR_DISCRETE.CAP(CHIPS)':
 'B': CDS_PINID='B';
NODE_NAME     C6R14 2
 '@BASEBOARD_FAB2_LIB.BASEBOARD_FAB2(SCH_1):PAGE214_I80@MSTR_DISCRETE.CAP(CHIPS)':
 'B': CDS_PINID='B';
NODE_NAME     C6R10 2
 '@BASEBOARD_FAB2_LIB.BASEBOARD_FAB2(SCH_1):PAGE214_I81@MSTR_DISCRETE.CAP(CHIPS)':
 'B': CDS_PINID='B';
NODE_NAME     C6R8 2
 '@BASEBOARD_FAB2_LIB.BASEBOARD_FAB2(SCH_1):PAGE214_I83@MSTR_DISCRETE.CAP(CHIPS)':
 'B': CDS_PINID='B';
NODE_NAME     R3D28 2
 '@BASEBOARD_FAB2_LIB.BASEBOARD_FAB2(SCH_1):PAGE214_I101@MSTR_DISCRETE.RES(CHIPS)':
 'B': CDS_PINID='B';
NODE_NAME     C3E1 2
 '@BASEBOARD_FAB2_LIB.BASEBOARD_FAB2(SCH_1):PAGE214_I108@DEV_DISCRETE.CAP_A(CHIPS)':
 'B': CDS_PINID='B';
NODE_NAME     R7R1 2
 '@BASEBOARD_FAB2_LIB.BASEBOARD_FAB2(SCH_1):PAGE214_I109@MSTR_DISCRETE.RES(CHIPS)':
 'B': CDS_PINID='B';
NODE_NAME     EU4E2 2
 '@BASEBOARD_FAB2_LIB.BASEBOARD_FAB2(SCH_1):PAGE214_I126@MSTR_DISCRETE.IR354XX(CHIPS)':
 'LGND': CDS_PINID='LGND';
NODE_NAME     EU4E2 5
 '@BASEBOARD_FAB2_LIB.BASEBOARD_FAB2(SCH_1):PAGE214_I126@MSTR_DISCRETE.IR354XX(CHIPS)':
 'PGND'<0>: CDS_PINID='PGND(0)';
NODE_NAME     EU4E2 7
 '@BASEBOARD_FAB2_LIB.BASEBOARD_FAB2(SCH_1):PAGE214_I126@MSTR_DISCRETE.IR354XX(CHIPS)':
 'PGND'<1>: CDS_PINID='PGND(1)';
NODE_NAME     EU4E2 40
 '@BASEBOARD_FAB2_LIB.BASEBOARD_FAB2(SCH_1):PAGE214_I126@MSTR_DISCRETE.IR354XX(CHIPS)':
 'PGND'<2>: CDS_PINID='PGND(2)';
NODE_NAME     R4E21 2
 '@BASEBOARD_FAB2_LIB.BASEBOARD_FAB2(SCH_1):PAGE214_I127@MSTR_DISCRETE.RES(CHIPS)':
 'B': CDS_PINID='B';
NODE_NAME     C6G3 2
 '@BASEBOARD_FAB2_LIB.BASEBOARD_FAB2(SCH_1):PAGE216_I6@MSTR_DISCRETE.CAP(CHIPS)':
 'B': CDS_PINID='B';
NODE_NAME     C3U2 2
 '@BASEBOARD_FAB2_LIB.BASEBOARD_FAB2(SCH_1):PAGE216_I45@MSTR_DISCRETE.CAP(CHIPS)':
 'B': CDS_PINID='B';
NODE_NAME     C3U3 2
 '@BASEBOARD_FAB2_LIB.BASEBOARD_FAB2(SCH_1):PAGE216_I46@MSTR_DISCRETE.CAP(CHIPS)':
 'B': CDS_PINID='B';
NODE_NAME     C3U4 2
 '@BASEBOARD_FAB2_LIB.BASEBOARD_FAB2(SCH_1):PAGE216_I47@MSTR_DISCRETE.CAP(CHIPS)':
 'B': CDS_PINID='B';
NODE_NAME     C7G37 2
 '@BASEBOARD_FAB2_LIB.BASEBOARD_FAB2(SCH_1):PAGE216_I48@MSTR_DISCRETE.CAP(CHIPS)':
 'B': CDS_PINID='B';
NODE_NAME     C7G33 2
 '@BASEBOARD_FAB2_LIB.BASEBOARD_FAB2(SCH_1):PAGE216_I50@MSTR_DISCRETE.CAP(CHIPS)':
 'B': CDS_PINID='B';
NODE_NAME     C7G29 2
 '@BASEBOARD_FAB2_LIB.BASEBOARD_FAB2(SCH_1):PAGE216_I51@DEV_DISCRETE.CAP_A(CHIPS)':
 'B': CDS_PINID='B';
NODE_NAME     C7G34 2
 '@BASEBOARD_FAB2_LIB.BASEBOARD_FAB2(SCH_1):PAGE216_I54@MSTR_DISCRETE.CAP(CHIPS)':
 'B': CDS_PINID='B';
NODE_NAME     C7G27 2
 '@BASEBOARD_FAB2_LIB.BASEBOARD_FAB2(SCH_1):PAGE216_I68@MSTR_DISCRETE.CAP(CHIPS)':
 'B': CDS_PINID='B';
NODE_NAME     C7G41 2
 '@BASEBOARD_FAB2_LIB.BASEBOARD_FAB2(SCH_1):PAGE216_I72@MSTR_DISCRETE.CAP(CHIPS)':
 'B': CDS_PINID='B';
NODE_NAME     C7G40 2
 '@BASEBOARD_FAB2_LIB.BASEBOARD_FAB2(SCH_1):PAGE216_I77@MSTR_DISCRETE.CAP(CHIPS)':
 'B': CDS_PINID='B';
NODE_NAME     C7G36 2
 '@BASEBOARD_FAB2_LIB.BASEBOARD_FAB2(SCH_1):PAGE216_I78@DEV_DISCRETE.CAP_A(CHIPS)':
 'B': CDS_PINID='B';
NODE_NAME     C7G30 2
 '@BASEBOARD_FAB2_LIB.BASEBOARD_FAB2(SCH_1):PAGE216_I79@MSTR_DISCRETE.CAP(CHIPS)':
 'B': CDS_PINID='B';
NODE_NAME     C3U9 2
 '@BASEBOARD_FAB2_LIB.BASEBOARD_FAB2(SCH_1):PAGE216_I80@MSTR_DISCRETE.CAP(CHIPS)':
 'B': CDS_PINID='B';
NODE_NAME     C3U7 2
 '@BASEBOARD_FAB2_LIB.BASEBOARD_FAB2(SCH_1):PAGE216_I81@MSTR_DISCRETE.CAP(CHIPS)':
 'B': CDS_PINID='B';
NODE_NAME     C3U6 2
 '@BASEBOARD_FAB2_LIB.BASEBOARD_FAB2(SCH_1):PAGE216_I84@MSTR_DISCRETE.CAP(CHIPS)':
 'B': CDS_PINID='B';
NODE_NAME     EU7G2 2
 '@BASEBOARD_FAB2_LIB.BASEBOARD_FAB2(SCH_1):PAGE216_I102@MSTR_DISCRETE.IR354XX(CHIPS)':
 'LGND': CDS_PINID='LGND';
NODE_NAME     EU7G2 5
 '@BASEBOARD_FAB2_LIB.BASEBOARD_FAB2(SCH_1):PAGE216_I102@MSTR_DISCRETE.IR354XX(CHIPS)':
 'PGND'<0>: CDS_PINID='PGND(0)';
NODE_NAME     EU7G2 7
 '@BASEBOARD_FAB2_LIB.BASEBOARD_FAB2(SCH_1):PAGE216_I102@MSTR_DISCRETE.IR354XX(CHIPS)':
 'PGND'<1>: CDS_PINID='PGND(1)';
NODE_NAME     EU7G2 40
 '@BASEBOARD_FAB2_LIB.BASEBOARD_FAB2(SCH_1):PAGE216_I102@MSTR_DISCRETE.IR354XX(CHIPS)':
 'PGND'<2>: CDS_PINID='PGND(2)';
NODE_NAME     EU7G3 2
 '@BASEBOARD_FAB2_LIB.BASEBOARD_FAB2(SCH_1):PAGE216_I103@MSTR_DISCRETE.IR354XX(CHIPS)':
 'LGND': CDS_PINID='LGND';
NODE_NAME     EU7G3 5
 '@BASEBOARD_FAB2_LIB.BASEBOARD_FAB2(SCH_1):PAGE216_I103@MSTR_DISCRETE.IR354XX(CHIPS)':
 'PGND'<0>: CDS_PINID='PGND(0)';
NODE_NAME     EU7G3 7
 '@BASEBOARD_FAB2_LIB.BASEBOARD_FAB2(SCH_1):PAGE216_I103@MSTR_DISCRETE.IR354XX(CHIPS)':
 'PGND'<1>: CDS_PINID='PGND(1)';
NODE_NAME     EU7G3 40
 '@BASEBOARD_FAB2_LIB.BASEBOARD_FAB2(SCH_1):PAGE216_I103@MSTR_DISCRETE.IR354XX(CHIPS)':
 'PGND'<2>: CDS_PINID='PGND(2)';
NODE_NAME     R7G25 2
 '@BASEBOARD_FAB2_LIB.BASEBOARD_FAB2(SCH_1):PAGE216_I104@MSTR_DISCRETE.RES(CHIPS)':
 'B': CDS_PINID='B';
NODE_NAME     R7G30 2
 '@BASEBOARD_FAB2_LIB.BASEBOARD_FAB2(SCH_1):PAGE216_I106@MSTR_DISCRETE.RES(CHIPS)':
 'B': CDS_PINID='B';
NODE_NAME     R3U4 2
 '@BASEBOARD_FAB2_LIB.BASEBOARD_FAB2(SCH_1):PAGE217_I58@MSTR_DISCRETE.RES(CHIPS)':
 'B': CDS_PINID='B';
NODE_NAME     C7G28 2
 '@BASEBOARD_FAB2_LIB.BASEBOARD_FAB2(SCH_1):PAGE217_I75@MSTR_DISCRETE.CAPP(CHIPS)':
 'B': CDS_PINID='B';
NODE_NAME     C3U1 2
 '@BASEBOARD_FAB2_LIB.BASEBOARD_FAB2(SCH_1):PAGE217_I76@MSTR_DISCRETE.CAPP(CHIPS)':
 'B': CDS_PINID='B';
NODE_NAME     C3U5 2
 '@BASEBOARD_FAB2_LIB.BASEBOARD_FAB2(SCH_1):PAGE217_I77@MSTR_DISCRETE.CAPP(CHIPS)':
 'B': CDS_PINID='B';
NODE_NAME     C3U8 2
 '@BASEBOARD_FAB2_LIB.BASEBOARD_FAB2(SCH_1):PAGE217_I78@MSTR_DISCRETE.CAPP(CHIPS)':
 'B': CDS_PINID='B';
NODE_NAME     C7G2 2
 '@BASEBOARD_FAB2_LIB.BASEBOARD_FAB2(SCH_1):PAGE217_I175@MSTR_DISCRETE.CAPP(CHIPS)':
 'B': CDS_PINID='B';
NODE_NAME     C5F2 2
 '@BASEBOARD_FAB2_LIB.BASEBOARD_FAB2(SCH_1):PAGE217_I205@DEV_DISCRETE.CAP_A(CHIPS)':
 'B': CDS_PINID='B';
NODE_NAME     C5F1 2
 '@BASEBOARD_FAB2_LIB.BASEBOARD_FAB2(SCH_1):PAGE217_I206@DEV_DISCRETE.CAP_A(CHIPS)':
 'B': CDS_PINID='B';
NODE_NAME     C5G10 2
 '@BASEBOARD_FAB2_LIB.BASEBOARD_FAB2(SCH_1):PAGE217_I207@DEV_DISCRETE.CAP_A(CHIPS)':
 'B': CDS_PINID='B';
NODE_NAME     C5T2 2
 '@BASEBOARD_FAB2_LIB.BASEBOARD_FAB2(SCH_1):PAGE217_I208@DEV_DISCRETE.CAP_A(CHIPS)':
 'B': CDS_PINID='B';
NODE_NAME     C5U11 2
 '@BASEBOARD_FAB2_LIB.BASEBOARD_FAB2(SCH_1):PAGE217_I209@DEV_DISCRETE.CAP_A(CHIPS)':
 'B': CDS_PINID='B';
NODE_NAME     C5T13 2
 '@BASEBOARD_FAB2_LIB.BASEBOARD_FAB2(SCH_1):PAGE217_I210@DEV_DISCRETE.CAP_A(CHIPS)':
 'B': CDS_PINID='B';
NODE_NAME     C5T4 2
 '@BASEBOARD_FAB2_LIB.BASEBOARD_FAB2(SCH_1):PAGE217_I211@DEV_DISCRETE.CAP_A(CHIPS)':
 'B': CDS_PINID='B';
NODE_NAME     C5T1 2
 '@BASEBOARD_FAB2_LIB.BASEBOARD_FAB2(SCH_1):PAGE217_I212@DEV_DISCRETE.CAP_A(CHIPS)':
 'B': CDS_PINID='B';
NODE_NAME     C5G19 2
 '@BASEBOARD_FAB2_LIB.BASEBOARD_FAB2(SCH_1):PAGE217_I213@DEV_DISCRETE.CAP_A(CHIPS)':
 'B': CDS_PINID='B';
NODE_NAME     SH4U1 2
 '@BASEBOARD_FAB2_LIB.BASEBOARD_FAB2(SCH_1):PAGE217_I259@MSTR_MISC.SHUNT(CHIPS)':
 'B':NET_SHORT='VSENSE_PVDDQ_ABC_N:GND',
 CDS_PINID='B';
NODE_NAME     C3L2 2
 '@BASEBOARD_FAB2_LIB.BASEBOARD_FAB2(SCH_1):PAGE219_I45@MSTR_DISCRETE.CAP(CHIPS)':
 'B': CDS_PINID='B';
NODE_NAME     C3L4 2
 '@BASEBOARD_FAB2_LIB.BASEBOARD_FAB2(SCH_1):PAGE219_I46@MSTR_DISCRETE.CAP(CHIPS)':
 'B': CDS_PINID='B';
NODE_NAME     C3L13 2
 '@BASEBOARD_FAB2_LIB.BASEBOARD_FAB2(SCH_1):PAGE219_I47@MSTR_DISCRETE.CAP(CHIPS)':
 'B': CDS_PINID='B';
NODE_NAME     C7A11 2
 '@BASEBOARD_FAB2_LIB.BASEBOARD_FAB2(SCH_1):PAGE219_I48@MSTR_DISCRETE.CAP(CHIPS)':
 'B': CDS_PINID='B';
NODE_NAME     C7A16 2
 '@BASEBOARD_FAB2_LIB.BASEBOARD_FAB2(SCH_1):PAGE219_I50@MSTR_DISCRETE.CAP(CHIPS)':
 'B': CDS_PINID='B';
NODE_NAME     C7A5 2
 '@BASEBOARD_FAB2_LIB.BASEBOARD_FAB2(SCH_1):PAGE219_I51@DEV_DISCRETE.CAP_A(CHIPS)':
 'B': CDS_PINID='B';
NODE_NAME     C7A17 2
 '@BASEBOARD_FAB2_LIB.BASEBOARD_FAB2(SCH_1):PAGE219_I54@MSTR_DISCRETE.CAP(CHIPS)':
 'B': CDS_PINID='B';
NODE_NAME     C6A4 2
 '@BASEBOARD_FAB2_LIB.BASEBOARD_FAB2(SCH_1):PAGE219_I68@MSTR_DISCRETE.CAP(CHIPS)':
 'B': CDS_PINID='B';
NODE_NAME     C7A25 2
 '@BASEBOARD_FAB2_LIB.BASEBOARD_FAB2(SCH_1):PAGE219_I72@MSTR_DISCRETE.CAP(CHIPS)':
 'B': CDS_PINID='B';
NODE_NAME     C7A24 2
 '@BASEBOARD_FAB2_LIB.BASEBOARD_FAB2(SCH_1):PAGE219_I77@MSTR_DISCRETE.CAP(CHIPS)':
 'B': CDS_PINID='B';
NODE_NAME     C7A20 2
 '@BASEBOARD_FAB2_LIB.BASEBOARD_FAB2(SCH_1):PAGE219_I78@DEV_DISCRETE.CAP_A(CHIPS)':
 'B': CDS_PINID='B';
NODE_NAME     C7A21 2
 '@BASEBOARD_FAB2_LIB.BASEBOARD_FAB2(SCH_1):PAGE219_I79@MSTR_DISCRETE.CAP(CHIPS)':
 'B': CDS_PINID='B';
NODE_NAME     C3L17 2
 '@BASEBOARD_FAB2_LIB.BASEBOARD_FAB2(SCH_1):PAGE219_I80@MSTR_DISCRETE.CAP(CHIPS)':
 'B': CDS_PINID='B';
NODE_NAME     C3L16 2
 '@BASEBOARD_FAB2_LIB.BASEBOARD_FAB2(SCH_1):PAGE219_I81@MSTR_DISCRETE.CAP(CHIPS)':
 'B': CDS_PINID='B';
NODE_NAME     C3L15 2
 '@BASEBOARD_FAB2_LIB.BASEBOARD_FAB2(SCH_1):PAGE219_I84@MSTR_DISCRETE.CAP(CHIPS)':
 'B': CDS_PINID='B';
NODE_NAME     C6A1 2
 '@BASEBOARD_FAB2_LIB.BASEBOARD_FAB2(SCH_1):PAGE219_I87@MSTR_DISCRETE.CAP(CHIPS)':
 'B': CDS_PINID='B';
NODE_NAME     EU7A1 2
 '@BASEBOARD_FAB2_LIB.BASEBOARD_FAB2(SCH_1):PAGE219_I106@MSTR_DISCRETE.IR354XX(CHIPS)':
 'LGND': CDS_PINID='LGND';
NODE_NAME     EU7A1 5
 '@BASEBOARD_FAB2_LIB.BASEBOARD_FAB2(SCH_1):PAGE219_I106@MSTR_DISCRETE.IR354XX(CHIPS)':
 'PGND'<0>: CDS_PINID='PGND(0)';
NODE_NAME     EU7A1 7
 '@BASEBOARD_FAB2_LIB.BASEBOARD_FAB2(SCH_1):PAGE219_I106@MSTR_DISCRETE.IR354XX(CHIPS)':
 'PGND'<1>: CDS_PINID='PGND(1)';
NODE_NAME     EU7A1 40
 '@BASEBOARD_FAB2_LIB.BASEBOARD_FAB2(SCH_1):PAGE219_I106@MSTR_DISCRETE.IR354XX(CHIPS)':
 'PGND'<2>: CDS_PINID='PGND(2)';
NODE_NAME     EU7A4 2
 '@BASEBOARD_FAB2_LIB.BASEBOARD_FAB2(SCH_1):PAGE219_I107@MSTR_DISCRETE.IR354XX(CHIPS)':
 'LGND': CDS_PINID='LGND';
NODE_NAME     EU7A4 5
 '@BASEBOARD_FAB2_LIB.BASEBOARD_FAB2(SCH_1):PAGE219_I107@MSTR_DISCRETE.IR354XX(CHIPS)':
 'PGND'<0>: CDS_PINID='PGND(0)';
NODE_NAME     EU7A4 7
 '@BASEBOARD_FAB2_LIB.BASEBOARD_FAB2(SCH_1):PAGE219_I107@MSTR_DISCRETE.IR354XX(CHIPS)':
 'PGND'<1>: CDS_PINID='PGND(1)';
NODE_NAME     EU7A4 40
 '@BASEBOARD_FAB2_LIB.BASEBOARD_FAB2(SCH_1):PAGE219_I107@MSTR_DISCRETE.IR354XX(CHIPS)':
 'PGND'<2>: CDS_PINID='PGND(2)';
NODE_NAME     R7A20 2
 '@BASEBOARD_FAB2_LIB.BASEBOARD_FAB2(SCH_1):PAGE219_I108@MSTR_DISCRETE.RES(CHIPS)':
 'B': CDS_PINID='B';
NODE_NAME     R7A21 2
 '@BASEBOARD_FAB2_LIB.BASEBOARD_FAB2(SCH_1):PAGE219_I110@MSTR_DISCRETE.RES(CHIPS)':
 'B': CDS_PINID='B';
NODE_NAME     R4L4 2
 '@BASEBOARD_FAB2_LIB.BASEBOARD_FAB2(SCH_1):PAGE220_I58@MSTR_DISCRETE.RES(CHIPS)':
 'B': CDS_PINID='B';
NODE_NAME     C3L6 2
 '@BASEBOARD_FAB2_LIB.BASEBOARD_FAB2(SCH_1):PAGE220_I75@MSTR_DISCRETE.CAPP(CHIPS)':
 'B': CDS_PINID='B';
NODE_NAME     C3L14 2
 '@BASEBOARD_FAB2_LIB.BASEBOARD_FAB2(SCH_1):PAGE220_I76@MSTR_DISCRETE.CAPP(CHIPS)':
 'B': CDS_PINID='B';
NODE_NAME     C6A5 2
 '@BASEBOARD_FAB2_LIB.BASEBOARD_FAB2(SCH_1):PAGE220_I77@MSTR_DISCRETE.CAPP(CHIPS)':
 'B': CDS_PINID='B';
NODE_NAME     C4L5 2
 '@BASEBOARD_FAB2_LIB.BASEBOARD_FAB2(SCH_1):PAGE220_I78@MSTR_DISCRETE.CAPP(CHIPS)':
 'B': CDS_PINID='B';
NODE_NAME     C5L15 2
 '@BASEBOARD_FAB2_LIB.BASEBOARD_FAB2(SCH_1):PAGE220_I192@DEV_DISCRETE.CAP_A(CHIPS)':
 'B': CDS_PINID='B';
NODE_NAME     C5A5 2
 '@BASEBOARD_FAB2_LIB.BASEBOARD_FAB2(SCH_1):PAGE220_I193@DEV_DISCRETE.CAP_A(CHIPS)':
 'B': CDS_PINID='B';
NODE_NAME     C5B1 2
 '@BASEBOARD_FAB2_LIB.BASEBOARD_FAB2(SCH_1):PAGE220_I194@DEV_DISCRETE.CAP_A(CHIPS)':
 'B': CDS_PINID='B';
NODE_NAME     C5M9 2
 '@BASEBOARD_FAB2_LIB.BASEBOARD_FAB2(SCH_1):PAGE220_I195@DEV_DISCRETE.CAP_A(CHIPS)':
 'B': CDS_PINID='B';
NODE_NAME     C4M5 2
 '@BASEBOARD_FAB2_LIB.BASEBOARD_FAB2(SCH_1):PAGE220_I196@DEV_DISCRETE.CAP_A(CHIPS)':
 'B': CDS_PINID='B';
NODE_NAME     C5B2 2
 '@BASEBOARD_FAB2_LIB.BASEBOARD_FAB2(SCH_1):PAGE220_I197@DEV_DISCRETE.CAP_A(CHIPS)':
 'B': CDS_PINID='B';
NODE_NAME     C5M10 2
 '@BASEBOARD_FAB2_LIB.BASEBOARD_FAB2(SCH_1):PAGE220_I198@DEV_DISCRETE.CAP_A(CHIPS)':
 'B': CDS_PINID='B';
NODE_NAME     C5M3 2
 '@BASEBOARD_FAB2_LIB.BASEBOARD_FAB2(SCH_1):PAGE220_I199@DEV_DISCRETE.CAP_A(CHIPS)':
 'B': CDS_PINID='B';
NODE_NAME     C5M11 2
 '@BASEBOARD_FAB2_LIB.BASEBOARD_FAB2(SCH_1):PAGE220_I200@DEV_DISCRETE.CAP_A(CHIPS)':
 'B': CDS_PINID='B';
NODE_NAME     SH4L1 2
 '@BASEBOARD_FAB2_LIB.BASEBOARD_FAB2(SCH_1):PAGE220_I240@MSTR_MISC.SHUNT(CHIPS)':
 'B':NET_SHORT='VSENSE_PVDDQ_DEF_N:GND',
 CDS_PINID='B';
NODE_NAME     C4G16 2
 '@BASEBOARD_FAB2_LIB.BASEBOARD_FAB2(SCH_1):PAGE221_I22@MSTR_DISCRETE.CAP(CHIPS)':
 'B': CDS_PINID='B';
NODE_NAME     C4G24 2
 '@BASEBOARD_FAB2_LIB.BASEBOARD_FAB2(SCH_1):PAGE221_I24@MSTR_DISCRETE.CAP(CHIPS)':
 'B': CDS_PINID='B';
NODE_NAME     C4A10 2
 '@BASEBOARD_FAB2_LIB.BASEBOARD_FAB2(SCH_1):PAGE222_I12@MSTR_DISCRETE.CAP(CHIPS)':
 'B': CDS_PINID='B';
NODE_NAME     C4A1 2
 '@BASEBOARD_FAB2_LIB.BASEBOARD_FAB2(SCH_1):PAGE222_I28@MSTR_DISCRETE.CAP(CHIPS)':
 'B': CDS_PINID='B';
NODE_NAME     C1G23 2
 '@BASEBOARD_FAB2_LIB.BASEBOARD_FAB2(SCH_1):PAGE223_I44@DEV_DISCRETE.CAP_A(CHIPS)':
 'B': CDS_PINID='B';
NODE_NAME     C1G17 2
 '@BASEBOARD_FAB2_LIB.BASEBOARD_FAB2(SCH_1):PAGE224_I6@MSTR_DISCRETE.CAP(CHIPS)':
 'B': CDS_PINID='B';
NODE_NAME     C9U6 2
 '@BASEBOARD_FAB2_LIB.BASEBOARD_FAB2(SCH_1):PAGE224_I45@MSTR_DISCRETE.CAP(CHIPS)':
 'B': CDS_PINID='B';
NODE_NAME     C9U4 2
 '@BASEBOARD_FAB2_LIB.BASEBOARD_FAB2(SCH_1):PAGE224_I46@MSTR_DISCRETE.CAP(CHIPS)':
 'B': CDS_PINID='B';
NODE_NAME     C9T4 2
 '@BASEBOARD_FAB2_LIB.BASEBOARD_FAB2(SCH_1):PAGE224_I47@MSTR_DISCRETE.CAP(CHIPS)':
 'B': CDS_PINID='B';
NODE_NAME     C1F27 2
 '@BASEBOARD_FAB2_LIB.BASEBOARD_FAB2(SCH_1):PAGE224_I48@MSTR_DISCRETE.CAP(CHIPS)':
 'B': CDS_PINID='B';
NODE_NAME     C1G6 2
 '@BASEBOARD_FAB2_LIB.BASEBOARD_FAB2(SCH_1):PAGE224_I50@MSTR_DISCRETE.CAP(CHIPS)':
 'B': CDS_PINID='B';
NODE_NAME     C1G14 2
 '@BASEBOARD_FAB2_LIB.BASEBOARD_FAB2(SCH_1):PAGE224_I51@DEV_DISCRETE.CAP_A(CHIPS)':
 'B': CDS_PINID='B';
NODE_NAME     C1G5 2
 '@BASEBOARD_FAB2_LIB.BASEBOARD_FAB2(SCH_1):PAGE224_I54@MSTR_DISCRETE.CAP(CHIPS)':
 'B': CDS_PINID='B';
NODE_NAME     C1G20 2
 '@BASEBOARD_FAB2_LIB.BASEBOARD_FAB2(SCH_1):PAGE224_I68@MSTR_DISCRETE.CAP(CHIPS)':
 'B': CDS_PINID='B';
NODE_NAME     C1G29 2
 '@BASEBOARD_FAB2_LIB.BASEBOARD_FAB2(SCH_1):PAGE224_I72@MSTR_DISCRETE.CAP(CHIPS)':
 'B': CDS_PINID='B';
NODE_NAME     C1G28 2
 '@BASEBOARD_FAB2_LIB.BASEBOARD_FAB2(SCH_1):PAGE224_I77@MSTR_DISCRETE.CAP(CHIPS)':
 'B': CDS_PINID='B';
NODE_NAME     C1F28 2
 '@BASEBOARD_FAB2_LIB.BASEBOARD_FAB2(SCH_1):PAGE224_I78@DEV_DISCRETE.CAP_A(CHIPS)':
 'B': CDS_PINID='B';
NODE_NAME     C1G13 2
 '@BASEBOARD_FAB2_LIB.BASEBOARD_FAB2(SCH_1):PAGE224_I79@MSTR_DISCRETE.CAP(CHIPS)':
 'B': CDS_PINID='B';
NODE_NAME     C9U3 2
 '@BASEBOARD_FAB2_LIB.BASEBOARD_FAB2(SCH_1):PAGE224_I80@MSTR_DISCRETE.CAP(CHIPS)':
 'B': CDS_PINID='B';
NODE_NAME     C9T6 2
 '@BASEBOARD_FAB2_LIB.BASEBOARD_FAB2(SCH_1):PAGE224_I81@MSTR_DISCRETE.CAP(CHIPS)':
 'B': CDS_PINID='B';
NODE_NAME     C9T9 2
 '@BASEBOARD_FAB2_LIB.BASEBOARD_FAB2(SCH_1):PAGE224_I84@MSTR_DISCRETE.CAP(CHIPS)':
 'B': CDS_PINID='B';
NODE_NAME     EU1G1 2
 '@BASEBOARD_FAB2_LIB.BASEBOARD_FAB2(SCH_1):PAGE224_I110@MSTR_DISCRETE.IR354XX(CHIPS)':
 'LGND': CDS_PINID='LGND';
NODE_NAME     EU1G1 5
 '@BASEBOARD_FAB2_LIB.BASEBOARD_FAB2(SCH_1):PAGE224_I110@MSTR_DISCRETE.IR354XX(CHIPS)':
 'PGND'<0>: CDS_PINID='PGND(0)';
NODE_NAME     EU1G1 7
 '@BASEBOARD_FAB2_LIB.BASEBOARD_FAB2(SCH_1):PAGE224_I110@MSTR_DISCRETE.IR354XX(CHIPS)':
 'PGND'<1>: CDS_PINID='PGND(1)';
NODE_NAME     EU1G1 40
 '@BASEBOARD_FAB2_LIB.BASEBOARD_FAB2(SCH_1):PAGE224_I110@MSTR_DISCRETE.IR354XX(CHIPS)':
 'PGND'<2>: CDS_PINID='PGND(2)';
NODE_NAME     EU1F1 2
 '@BASEBOARD_FAB2_LIB.BASEBOARD_FAB2(SCH_1):PAGE224_I111@MSTR_DISCRETE.IR354XX(CHIPS)':
 'LGND': CDS_PINID='LGND';
NODE_NAME     EU1F1 5
 '@BASEBOARD_FAB2_LIB.BASEBOARD_FAB2(SCH_1):PAGE224_I111@MSTR_DISCRETE.IR354XX(CHIPS)':
 'PGND'<0>: CDS_PINID='PGND(0)';
NODE_NAME     EU1F1 7
 '@BASEBOARD_FAB2_LIB.BASEBOARD_FAB2(SCH_1):PAGE224_I111@MSTR_DISCRETE.IR354XX(CHIPS)':
 'PGND'<1>: CDS_PINID='PGND(1)';
NODE_NAME     EU1F1 40
 '@BASEBOARD_FAB2_LIB.BASEBOARD_FAB2(SCH_1):PAGE224_I111@MSTR_DISCRETE.IR354XX(CHIPS)':
 'PGND'<2>: CDS_PINID='PGND(2)';
NODE_NAME     R1G26 2
 '@BASEBOARD_FAB2_LIB.BASEBOARD_FAB2(SCH_1):PAGE224_I112@MSTR_DISCRETE.RES(CHIPS)':
 'B': CDS_PINID='B';
NODE_NAME     R1G25 2
 '@BASEBOARD_FAB2_LIB.BASEBOARD_FAB2(SCH_1):PAGE224_I114@MSTR_DISCRETE.RES(CHIPS)':
 'B': CDS_PINID='B';
NODE_NAME     R1G20 2
 '@BASEBOARD_FAB2_LIB.BASEBOARD_FAB2(SCH_1):PAGE225_I58@MSTR_DISCRETE.RES(CHIPS)':
 'B': CDS_PINID='B';
NODE_NAME     C9T5 2
 '@BASEBOARD_FAB2_LIB.BASEBOARD_FAB2(SCH_1):PAGE225_I75@MSTR_DISCRETE.CAPP(CHIPS)':
 'B': CDS_PINID='B';
NODE_NAME     C9U2 2
 '@BASEBOARD_FAB2_LIB.BASEBOARD_FAB2(SCH_1):PAGE225_I76@MSTR_DISCRETE.CAPP(CHIPS)':
 'B': CDS_PINID='B';
NODE_NAME     C9U9 2
 '@BASEBOARD_FAB2_LIB.BASEBOARD_FAB2(SCH_1):PAGE225_I77@MSTR_DISCRETE.CAPP(CHIPS)':
 'B': CDS_PINID='B';
NODE_NAME     C9U5 2
 '@BASEBOARD_FAB2_LIB.BASEBOARD_FAB2(SCH_1):PAGE225_I78@MSTR_DISCRETE.CAPP(CHIPS)':
 'B': CDS_PINID='B';
NODE_NAME     C8T4 2
 '@BASEBOARD_FAB2_LIB.BASEBOARD_FAB2(SCH_1):PAGE225_I196@DEV_DISCRETE.CAP_A(CHIPS)':
 'B': CDS_PINID='B';
NODE_NAME     C2G8 2
 '@BASEBOARD_FAB2_LIB.BASEBOARD_FAB2(SCH_1):PAGE225_I197@DEV_DISCRETE.CAP_A(CHIPS)':
 'B': CDS_PINID='B';
NODE_NAME     C8T2 2
 '@BASEBOARD_FAB2_LIB.BASEBOARD_FAB2(SCH_1):PAGE225_I198@DEV_DISCRETE.CAP_A(CHIPS)':
 'B': CDS_PINID='B';
NODE_NAME     C8U13 2
 '@BASEBOARD_FAB2_LIB.BASEBOARD_FAB2(SCH_1):PAGE225_I199@DEV_DISCRETE.CAP_A(CHIPS)':
 'B': CDS_PINID='B';
NODE_NAME     C2G15 2
 '@BASEBOARD_FAB2_LIB.BASEBOARD_FAB2(SCH_1):PAGE225_I200@DEV_DISCRETE.CAP_A(CHIPS)':
 'B': CDS_PINID='B';
NODE_NAME     C2F1 2
 '@BASEBOARD_FAB2_LIB.BASEBOARD_FAB2(SCH_1):PAGE225_I201@DEV_DISCRETE.CAP_A(CHIPS)':
 'B': CDS_PINID='B';
NODE_NAME     C8T1 2
 '@BASEBOARD_FAB2_LIB.BASEBOARD_FAB2(SCH_1):PAGE225_I202@DEV_DISCRETE.CAP_A(CHIPS)':
 'B': CDS_PINID='B';
NODE_NAME     C8U9 2
 '@BASEBOARD_FAB2_LIB.BASEBOARD_FAB2(SCH_1):PAGE225_I203@DEV_DISCRETE.CAP_A(CHIPS)':
 'B': CDS_PINID='B';
NODE_NAME     C8T11 2
 '@BASEBOARD_FAB2_LIB.BASEBOARD_FAB2(SCH_1):PAGE225_I204@DEV_DISCRETE.CAP_A(CHIPS)':
 'B': CDS_PINID='B';
NODE_NAME     SH7U2 2
 '@BASEBOARD_FAB2_LIB.BASEBOARD_FAB2(SCH_1):PAGE225_I244@MSTR_MISC.SHUNT(CHIPS)':
 'B':NET_SHORT='VSENSE_PVDDQ_GHJ_N:GND',
 CDS_PINID='B';
NODE_NAME     C1B2 2
 '@BASEBOARD_FAB2_LIB.BASEBOARD_FAB2(SCH_1):PAGE226_I44@DEV_DISCRETE.CAP_A(CHIPS)':
 'B': CDS_PINID='B';
NODE_NAME     C1A12 2
 '@BASEBOARD_FAB2_LIB.BASEBOARD_FAB2(SCH_1):PAGE227_I6@MSTR_DISCRETE.CAP(CHIPS)':
 'B': CDS_PINID='B';
NODE_NAME     C9L11 2
 '@BASEBOARD_FAB2_LIB.BASEBOARD_FAB2(SCH_1):PAGE227_I45@MSTR_DISCRETE.CAP(CHIPS)':
 'B': CDS_PINID='B';
NODE_NAME     C9L10 2
 '@BASEBOARD_FAB2_LIB.BASEBOARD_FAB2(SCH_1):PAGE227_I46@MSTR_DISCRETE.CAP(CHIPS)':
 'B': CDS_PINID='B';
NODE_NAME     C9L6 2
 '@BASEBOARD_FAB2_LIB.BASEBOARD_FAB2(SCH_1):PAGE227_I47@MSTR_DISCRETE.CAP(CHIPS)':
 'B': CDS_PINID='B';
NODE_NAME     C1A19 2
 '@BASEBOARD_FAB2_LIB.BASEBOARD_FAB2(SCH_1):PAGE227_I48@MSTR_DISCRETE.CAP(CHIPS)':
 'B': CDS_PINID='B';
NODE_NAME     C1B20 2
 '@BASEBOARD_FAB2_LIB.BASEBOARD_FAB2(SCH_1):PAGE227_I50@MSTR_DISCRETE.CAP(CHIPS)':
 'B': CDS_PINID='B';
NODE_NAME     C1A10 2
 '@BASEBOARD_FAB2_LIB.BASEBOARD_FAB2(SCH_1):PAGE227_I51@DEV_DISCRETE.CAP_A(CHIPS)':
 'B': CDS_PINID='B';
NODE_NAME     C1B21 2
 '@BASEBOARD_FAB2_LIB.BASEBOARD_FAB2(SCH_1):PAGE227_I54@MSTR_DISCRETE.CAP(CHIPS)':
 'B': CDS_PINID='B';
NODE_NAME     C1A1 2
 '@BASEBOARD_FAB2_LIB.BASEBOARD_FAB2(SCH_1):PAGE227_I68@MSTR_DISCRETE.CAP(CHIPS)':
 'B': CDS_PINID='B';
NODE_NAME     C1A13 2
 '@BASEBOARD_FAB2_LIB.BASEBOARD_FAB2(SCH_1):PAGE227_I72@MSTR_DISCRETE.CAP(CHIPS)':
 'B': CDS_PINID='B';
NODE_NAME     C1A6 2
 '@BASEBOARD_FAB2_LIB.BASEBOARD_FAB2(SCH_1):PAGE227_I77@MSTR_DISCRETE.CAP(CHIPS)':
 'B': CDS_PINID='B';
NODE_NAME     C1A20 2
 '@BASEBOARD_FAB2_LIB.BASEBOARD_FAB2(SCH_1):PAGE227_I78@DEV_DISCRETE.CAP_A(CHIPS)':
 'B': CDS_PINID='B';
NODE_NAME     C1A9 2
 '@BASEBOARD_FAB2_LIB.BASEBOARD_FAB2(SCH_1):PAGE227_I79@MSTR_DISCRETE.CAP(CHIPS)':
 'B': CDS_PINID='B';
NODE_NAME     C9L5 2
 '@BASEBOARD_FAB2_LIB.BASEBOARD_FAB2(SCH_1):PAGE227_I80@MSTR_DISCRETE.CAP(CHIPS)':
 'B': CDS_PINID='B';
NODE_NAME     C9L13 2
 '@BASEBOARD_FAB2_LIB.BASEBOARD_FAB2(SCH_1):PAGE227_I81@MSTR_DISCRETE.CAP(CHIPS)':
 'B': CDS_PINID='B';
NODE_NAME     C9L14 2
 '@BASEBOARD_FAB2_LIB.BASEBOARD_FAB2(SCH_1):PAGE227_I84@MSTR_DISCRETE.CAP(CHIPS)':
 'B': CDS_PINID='B';
NODE_NAME     EU1A2 2
 '@BASEBOARD_FAB2_LIB.BASEBOARD_FAB2(SCH_1):PAGE227_I101@MSTR_DISCRETE.IR354XX(CHIPS)':
 'LGND': CDS_PINID='LGND';
NODE_NAME     EU1A2 5
 '@BASEBOARD_FAB2_LIB.BASEBOARD_FAB2(SCH_1):PAGE227_I101@MSTR_DISCRETE.IR354XX(CHIPS)':
 'PGND'<0>: CDS_PINID='PGND(0)';
NODE_NAME     EU1A2 7
 '@BASEBOARD_FAB2_LIB.BASEBOARD_FAB2(SCH_1):PAGE227_I101@MSTR_DISCRETE.IR354XX(CHIPS)':
 'PGND'<1>: CDS_PINID='PGND(1)';
NODE_NAME     EU1A2 40
 '@BASEBOARD_FAB2_LIB.BASEBOARD_FAB2(SCH_1):PAGE227_I101@MSTR_DISCRETE.IR354XX(CHIPS)':
 'PGND'<2>: CDS_PINID='PGND(2)';
NODE_NAME     EU1A1 2
 '@BASEBOARD_FAB2_LIB.BASEBOARD_FAB2(SCH_1):PAGE227_I102@MSTR_DISCRETE.IR354XX(CHIPS)':
 'LGND': CDS_PINID='LGND';
NODE_NAME     EU1A1 5
 '@BASEBOARD_FAB2_LIB.BASEBOARD_FAB2(SCH_1):PAGE227_I102@MSTR_DISCRETE.IR354XX(CHIPS)':
 'PGND'<0>: CDS_PINID='PGND(0)';
NODE_NAME     EU1A1 7
 '@BASEBOARD_FAB2_LIB.BASEBOARD_FAB2(SCH_1):PAGE227_I102@MSTR_DISCRETE.IR354XX(CHIPS)':
 'PGND'<1>: CDS_PINID='PGND(1)';
NODE_NAME     EU1A1 40
 '@BASEBOARD_FAB2_LIB.BASEBOARD_FAB2(SCH_1):PAGE227_I102@MSTR_DISCRETE.IR354XX(CHIPS)':
 'PGND'<2>: CDS_PINID='PGND(2)';
NODE_NAME     R1A3 2
 '@BASEBOARD_FAB2_LIB.BASEBOARD_FAB2(SCH_1):PAGE227_I103@MSTR_DISCRETE.RES(CHIPS)':
 'B': CDS_PINID='B';
NODE_NAME     R1A2 2
 '@BASEBOARD_FAB2_LIB.BASEBOARD_FAB2(SCH_1):PAGE227_I105@MSTR_DISCRETE.RES(CHIPS)':
 'B': CDS_PINID='B';
NODE_NAME     R1A1 2
 '@BASEBOARD_FAB2_LIB.BASEBOARD_FAB2(SCH_1):PAGE228_I58@MSTR_DISCRETE.RES(CHIPS)':
 'B': CDS_PINID='B';
NODE_NAME     C9L9 2
 '@BASEBOARD_FAB2_LIB.BASEBOARD_FAB2(SCH_1):PAGE228_I75@MSTR_DISCRETE.CAPP(CHIPS)':
 'B': CDS_PINID='B';
NODE_NAME     C9L12 2
 '@BASEBOARD_FAB2_LIB.BASEBOARD_FAB2(SCH_1):PAGE228_I76@MSTR_DISCRETE.CAPP(CHIPS)':
 'B': CDS_PINID='B';
NODE_NAME     C9L4 2
 '@BASEBOARD_FAB2_LIB.BASEBOARD_FAB2(SCH_1):PAGE228_I77@MSTR_DISCRETE.CAPP(CHIPS)':
 'B': CDS_PINID='B';
NODE_NAME     C9L2 2
 '@BASEBOARD_FAB2_LIB.BASEBOARD_FAB2(SCH_1):PAGE228_I78@MSTR_DISCRETE.CAPP(CHIPS)':
 'B': CDS_PINID='B';
NODE_NAME     C1B10 2
 '@BASEBOARD_FAB2_LIB.BASEBOARD_FAB2(SCH_1):PAGE228_I175@MSTR_DISCRETE.CAPP(CHIPS)':
 'B': CDS_PINID='B';
NODE_NAME     C8M8 2
 '@BASEBOARD_FAB2_LIB.BASEBOARD_FAB2(SCH_1):PAGE228_I198@DEV_DISCRETE.CAP_A(CHIPS)':
 'B': CDS_PINID='B';
NODE_NAME     C2A5 2
 '@BASEBOARD_FAB2_LIB.BASEBOARD_FAB2(SCH_1):PAGE228_I199@DEV_DISCRETE.CAP_A(CHIPS)':
 'B': CDS_PINID='B';
NODE_NAME     C2B1 2
 '@BASEBOARD_FAB2_LIB.BASEBOARD_FAB2(SCH_1):PAGE228_I200@DEV_DISCRETE.CAP_A(CHIPS)':
 'B': CDS_PINID='B';
NODE_NAME     C8L12 2
 '@BASEBOARD_FAB2_LIB.BASEBOARD_FAB2(SCH_1):PAGE228_I201@DEV_DISCRETE.CAP_A(CHIPS)':
 'B': CDS_PINID='B';
NODE_NAME     C7M5 2
 '@BASEBOARD_FAB2_LIB.BASEBOARD_FAB2(SCH_1):PAGE228_I202@DEV_DISCRETE.CAP_A(CHIPS)':
 'B': CDS_PINID='B';
NODE_NAME     C8M10 2
 '@BASEBOARD_FAB2_LIB.BASEBOARD_FAB2(SCH_1):PAGE228_I203@DEV_DISCRETE.CAP_A(CHIPS)':
 'B': CDS_PINID='B';
NODE_NAME     C2B2 2
 '@BASEBOARD_FAB2_LIB.BASEBOARD_FAB2(SCH_1):PAGE228_I204@DEV_DISCRETE.CAP_A(CHIPS)':
 'B': CDS_PINID='B';
NODE_NAME     C8M9 2
 '@BASEBOARD_FAB2_LIB.BASEBOARD_FAB2(SCH_1):PAGE228_I205@DEV_DISCRETE.CAP_A(CHIPS)':
 'B': CDS_PINID='B';
NODE_NAME     C8M2 2
 '@BASEBOARD_FAB2_LIB.BASEBOARD_FAB2(SCH_1):PAGE228_I206@DEV_DISCRETE.CAP_A(CHIPS)':
 'B': CDS_PINID='B';
NODE_NAME     SH7L1 2
 '@BASEBOARD_FAB2_LIB.BASEBOARD_FAB2(SCH_1):PAGE228_I246@MSTR_MISC.SHUNT(CHIPS)':
 'B':NET_SHORT='VSENSE_PVDDQ_KLM_N:GND',
 CDS_PINID='B';
NODE_NAME     C4G21 2
 '@BASEBOARD_FAB2_LIB.BASEBOARD_FAB2(SCH_1):PAGE229_I21@MSTR_DISCRETE.CAP(CHIPS)':
 'B': CDS_PINID='B';
NODE_NAME     C6F6 2
 '@BASEBOARD_FAB2_LIB.BASEBOARD_FAB2(SCH_1):PAGE231_I122@MSTR_DISCRETE.CAP(CHIPS)':
 'B': CDS_PINID='B';
NODE_NAME     C4T6 2
 '@BASEBOARD_FAB2_LIB.BASEBOARD_FAB2(SCH_1):PAGE231_I124@MSTR_DISCRETE.CAP(CHIPS)':
 'B': CDS_PINID='B';
NODE_NAME     C4T5 2
 '@BASEBOARD_FAB2_LIB.BASEBOARD_FAB2(SCH_1):PAGE231_I125@MSTR_DISCRETE.CAP(CHIPS)':
 'B': CDS_PINID='B';
NODE_NAME     C6G1 2
 '@BASEBOARD_FAB2_LIB.BASEBOARD_FAB2(SCH_1):PAGE231_I126@MSTR_DISCRETE.CAP(CHIPS)':
 'B': CDS_PINID='B';
NODE_NAME     C6G2 2
 '@BASEBOARD_FAB2_LIB.BASEBOARD_FAB2(SCH_1):PAGE231_I128@MSTR_DISCRETE.CAP(CHIPS)':
 'B': CDS_PINID='B';
NODE_NAME     C4U2 2
 '@BASEBOARD_FAB2_LIB.BASEBOARD_FAB2(SCH_1):PAGE231_I129@MSTR_DISCRETE.CAP(CHIPS)':
 'B': CDS_PINID='B';
NODE_NAME     C4U1 2
 '@BASEBOARD_FAB2_LIB.BASEBOARD_FAB2(SCH_1):PAGE231_I130@MSTR_DISCRETE.CAP(CHIPS)':
 'B': CDS_PINID='B';
NODE_NAME     C6G4 2
 '@BASEBOARD_FAB2_LIB.BASEBOARD_FAB2(SCH_1):PAGE231_I131@MSTR_DISCRETE.CAP(CHIPS)':
 'B': CDS_PINID='B';
NODE_NAME     R7F14 2
 '@BASEBOARD_FAB2_LIB.BASEBOARD_FAB2(SCH_1):PAGE231_I136@MSTR_DISCRETE.RES(CHIPS)':
 'B': CDS_PINID='B';
NODE_NAME     C7F11 2
 '@BASEBOARD_FAB2_LIB.BASEBOARD_FAB2(SCH_1):PAGE231_I142@MSTR_DISCRETE.CAP(CHIPS)':
 'B': CDS_PINID='B';
NODE_NAME     C6G5 2
 '@BASEBOARD_FAB2_LIB.BASEBOARD_FAB2(SCH_1):PAGE231_I145@MSTR_DISCRETE.CAP(CHIPS)':
 'B': CDS_PINID='B';
NODE_NAME     C4U4 2
 '@BASEBOARD_FAB2_LIB.BASEBOARD_FAB2(SCH_1):PAGE231_I146@MSTR_DISCRETE.CAP(CHIPS)':
 'B': CDS_PINID='B';
NODE_NAME     C4U3 2
 '@BASEBOARD_FAB2_LIB.BASEBOARD_FAB2(SCH_1):PAGE231_I148@MSTR_DISCRETE.CAP(CHIPS)':
 'B': CDS_PINID='B';
NODE_NAME     C6F5 2
 '@BASEBOARD_FAB2_LIB.BASEBOARD_FAB2(SCH_1):PAGE231_I149@MSTR_DISCRETE.CAP(CHIPS)':
 'B': CDS_PINID='B';
NODE_NAME     C3T10 2
 '@BASEBOARD_FAB2_LIB.BASEBOARD_FAB2(SCH_1):PAGE231_I161@MSTR_DISCRETE.CAP(CHIPS)':
 'B': CDS_PINID='B';
NODE_NAME     R7F35 1
 '@BASEBOARD_FAB2_LIB.BASEBOARD_FAB2(SCH_1):PAGE231_I170@MSTR_DISCRETE.RES(CHIPS)':
 'A': CDS_PINID='A';
NODE_NAME     R7F7 2
 '@BASEBOARD_FAB2_LIB.BASEBOARD_FAB2(SCH_1):PAGE231_I174@MSTR_DISCRETE.RES(CHIPS)':
 'B': CDS_PINID='B';
NODE_NAME     R7F10 2
 '@BASEBOARD_FAB2_LIB.BASEBOARD_FAB2(SCH_1):PAGE231_I177@MSTR_DISCRETE.RES(CHIPS)':
 'B': CDS_PINID='B';
NODE_NAME     C6F4 2
 '@BASEBOARD_FAB2_LIB.BASEBOARD_FAB2(SCH_1):PAGE231_I180@MSTR_DISCRETE.CAPP(CHIPS)':
 'B': CDS_PINID='B';
NODE_NAME     C3T7 2
 '@BASEBOARD_FAB2_LIB.BASEBOARD_FAB2(SCH_1):PAGE231_I184@MSTR_DISCRETE.CAP(CHIPS)':
 'B': CDS_PINID='B';
NODE_NAME     C3T9 2
 '@BASEBOARD_FAB2_LIB.BASEBOARD_FAB2(SCH_1):PAGE231_I186@MSTR_DISCRETE.CAP(CHIPS)':
 'B': CDS_PINID='B';
NODE_NAME     EU7F1 41
 '@BASEBOARD_FAB2_LIB.BASEBOARD_FAB2(SCH_1):PAGE231_I193@MSTR_VREG.NCP3232L(CHIPS)':
 'GND': CDS_PINID='GND';
NODE_NAME     EU7F1 16
 '@BASEBOARD_FAB2_LIB.BASEBOARD_FAB2(SCH_1):PAGE231_I193@MSTR_VREG.NCP3232L(CHIPS)':
 'PGND'<0>: CDS_PINID='PGND(0)';
NODE_NAME     EU7F1 17
 '@BASEBOARD_FAB2_LIB.BASEBOARD_FAB2(SCH_1):PAGE231_I193@MSTR_VREG.NCP3232L(CHIPS)':
 'PGND'<1>: CDS_PINID='PGND(1)';
NODE_NAME     EU7F1 18
 '@BASEBOARD_FAB2_LIB.BASEBOARD_FAB2(SCH_1):PAGE231_I193@MSTR_VREG.NCP3232L(CHIPS)':
 'PGND'<2>: CDS_PINID='PGND(2)';
NODE_NAME     EU7F1 19
 '@BASEBOARD_FAB2_LIB.BASEBOARD_FAB2(SCH_1):PAGE231_I193@MSTR_VREG.NCP3232L(CHIPS)':
 'PGND'<3>: CDS_PINID='PGND(3)';
NODE_NAME     EU7F1 20
 '@BASEBOARD_FAB2_LIB.BASEBOARD_FAB2(SCH_1):PAGE231_I193@MSTR_VREG.NCP3232L(CHIPS)':
 'PGND'<4>: CDS_PINID='PGND(4)';
NODE_NAME     EU7F1 21
 '@BASEBOARD_FAB2_LIB.BASEBOARD_FAB2(SCH_1):PAGE231_I193@MSTR_VREG.NCP3232L(CHIPS)':
 'PGND'<5>: CDS_PINID='PGND(5)';
NODE_NAME     EU7F1 22
 '@BASEBOARD_FAB2_LIB.BASEBOARD_FAB2(SCH_1):PAGE231_I193@MSTR_VREG.NCP3232L(CHIPS)':
 'PGND'<6>: CDS_PINID='PGND(6)';
NODE_NAME     EU7F1 23
 '@BASEBOARD_FAB2_LIB.BASEBOARD_FAB2(SCH_1):PAGE231_I193@MSTR_VREG.NCP3232L(CHIPS)':
 'PGND'<7>: CDS_PINID='PGND(7)';
NODE_NAME     EU7F1 24
 '@BASEBOARD_FAB2_LIB.BASEBOARD_FAB2(SCH_1):PAGE231_I193@MSTR_VREG.NCP3232L(CHIPS)':
 'PGND'<8>: CDS_PINID='PGND(8)';
NODE_NAME     EU7F1 25
 '@BASEBOARD_FAB2_LIB.BASEBOARD_FAB2(SCH_1):PAGE231_I193@MSTR_VREG.NCP3232L(CHIPS)':
 'PGND'<9>: CDS_PINID='PGND(9)';
NODE_NAME     EU7F1 26
 '@BASEBOARD_FAB2_LIB.BASEBOARD_FAB2(SCH_1):PAGE231_I193@MSTR_VREG.NCP3232L(CHIPS)':
 'PGND'<10>: CDS_PINID='PGND(10)';
NODE_NAME     EU7F1 27
 '@BASEBOARD_FAB2_LIB.BASEBOARD_FAB2(SCH_1):PAGE231_I193@MSTR_VREG.NCP3232L(CHIPS)':
 'PGND'<11>: CDS_PINID='PGND(11)';
NODE_NAME     EU7F1 28
 '@BASEBOARD_FAB2_LIB.BASEBOARD_FAB2(SCH_1):PAGE231_I193@MSTR_VREG.NCP3232L(CHIPS)':
 'PGND'<12>: CDS_PINID='PGND(12)';
NODE_NAME     EU7F1 37
 '@BASEBOARD_FAB2_LIB.BASEBOARD_FAB2(SCH_1):PAGE231_I193@MSTR_VREG.NCP3232L(CHIPS)':
 'PGND'<13>: CDS_PINID='PGND(13)';
NODE_NAME     C7F6 2
 '@BASEBOARD_FAB2_LIB.BASEBOARD_FAB2(SCH_1):PAGE231_I205@DEV_DISCRETE.CAP_A(CHIPS)':
 'B': CDS_PINID='B';
NODE_NAME     C7F5 2
 '@BASEBOARD_FAB2_LIB.BASEBOARD_FAB2(SCH_1):PAGE231_I209@MSTR_DISCRETE.CAP(CHIPS)':
 'B': CDS_PINID='B';
NODE_NAME     C3T8 2
 '@BASEBOARD_FAB2_LIB.BASEBOARD_FAB2(SCH_1):PAGE231_I210@MSTR_DISCRETE.CAP(CHIPS)':
 'B': CDS_PINID='B';
NODE_NAME     C3T14 2
 '@BASEBOARD_FAB2_LIB.BASEBOARD_FAB2(SCH_1):PAGE231_I211@MSTR_DISCRETE.CAP(CHIPS)':
 'B': CDS_PINID='B';
NODE_NAME     C3T12 2
 '@BASEBOARD_FAB2_LIB.BASEBOARD_FAB2(SCH_1):PAGE231_I215@MSTR_DISCRETE.CAP(CHIPS)':
 'B': CDS_PINID='B';
NODE_NAME     C4T3 2
 '@BASEBOARD_FAB2_LIB.BASEBOARD_FAB2(SCH_1):PAGE231_I217@MSTR_DISCRETE.CAPP(CHIPS)':
 'B': CDS_PINID='B';
NODE_NAME     C4L2 2
 '@BASEBOARD_FAB2_LIB.BASEBOARD_FAB2(SCH_1):PAGE232_I102@MSTR_DISCRETE.CAP(CHIPS)':
 'B': CDS_PINID='B';
NODE_NAME     C6A3 2
 '@BASEBOARD_FAB2_LIB.BASEBOARD_FAB2(SCH_1):PAGE232_I104@MSTR_DISCRETE.CAP(CHIPS)':
 'B': CDS_PINID='B';
NODE_NAME     C6A2 2
 '@BASEBOARD_FAB2_LIB.BASEBOARD_FAB2(SCH_1):PAGE232_I105@MSTR_DISCRETE.CAP(CHIPS)':
 'B': CDS_PINID='B';
NODE_NAME     C4L3 2
 '@BASEBOARD_FAB2_LIB.BASEBOARD_FAB2(SCH_1):PAGE232_I106@MSTR_DISCRETE.CAP(CHIPS)':
 'B': CDS_PINID='B';
NODE_NAME     C4L4 2
 '@BASEBOARD_FAB2_LIB.BASEBOARD_FAB2(SCH_1):PAGE232_I108@MSTR_DISCRETE.CAP(CHIPS)':
 'B': CDS_PINID='B';
NODE_NAME     C6A7 2
 '@BASEBOARD_FAB2_LIB.BASEBOARD_FAB2(SCH_1):PAGE232_I109@MSTR_DISCRETE.CAP(CHIPS)':
 'B': CDS_PINID='B';
NODE_NAME     C6A6 2
 '@BASEBOARD_FAB2_LIB.BASEBOARD_FAB2(SCH_1):PAGE232_I110@MSTR_DISCRETE.CAP(CHIPS)':
 'B': CDS_PINID='B';
NODE_NAME     C4M3 2
 '@BASEBOARD_FAB2_LIB.BASEBOARD_FAB2(SCH_1):PAGE232_I111@MSTR_DISCRETE.CAP(CHIPS)':
 'B': CDS_PINID='B';
NODE_NAME     C4M4 2
 '@BASEBOARD_FAB2_LIB.BASEBOARD_FAB2(SCH_1):PAGE232_I125@MSTR_DISCRETE.CAP(CHIPS)':
 'B': CDS_PINID='B';
NODE_NAME     C6B2 2
 '@BASEBOARD_FAB2_LIB.BASEBOARD_FAB2(SCH_1):PAGE232_I126@MSTR_DISCRETE.CAP(CHIPS)':
 'B': CDS_PINID='B';
NODE_NAME     C6B1 2
 '@BASEBOARD_FAB2_LIB.BASEBOARD_FAB2(SCH_1):PAGE232_I128@MSTR_DISCRETE.CAP(CHIPS)':
 'B': CDS_PINID='B';
NODE_NAME     C4L1 2
 '@BASEBOARD_FAB2_LIB.BASEBOARD_FAB2(SCH_1):PAGE232_I129@MSTR_DISCRETE.CAP(CHIPS)':
 'B': CDS_PINID='B';
NODE_NAME     R7B20 1
 '@BASEBOARD_FAB2_LIB.BASEBOARD_FAB2(SCH_1):PAGE232_I150@MSTR_DISCRETE.RES(CHIPS)':
 'A': CDS_PINID='A';
NODE_NAME     C3M9 2
 '@BASEBOARD_FAB2_LIB.BASEBOARD_FAB2(SCH_1):PAGE232_I207@MSTR_DISCRETE.CAP(CHIPS)':
 'B': CDS_PINID='B';
NODE_NAME     C7B12 2
 '@BASEBOARD_FAB2_LIB.BASEBOARD_FAB2(SCH_1):PAGE232_I209@MSTR_DISCRETE.CAP(CHIPS)':
 'B': CDS_PINID='B';
NODE_NAME     EU7B1 41
 '@BASEBOARD_FAB2_LIB.BASEBOARD_FAB2(SCH_1):PAGE232_I214@MSTR_VREG.NCP3232L(CHIPS)':
 'GND': CDS_PINID='GND';
NODE_NAME     EU7B1 16
 '@BASEBOARD_FAB2_LIB.BASEBOARD_FAB2(SCH_1):PAGE232_I214@MSTR_VREG.NCP3232L(CHIPS)':
 'PGND'<0>: CDS_PINID='PGND(0)';
NODE_NAME     EU7B1 17
 '@BASEBOARD_FAB2_LIB.BASEBOARD_FAB2(SCH_1):PAGE232_I214@MSTR_VREG.NCP3232L(CHIPS)':
 'PGND'<1>: CDS_PINID='PGND(1)';
NODE_NAME     EU7B1 18
 '@BASEBOARD_FAB2_LIB.BASEBOARD_FAB2(SCH_1):PAGE232_I214@MSTR_VREG.NCP3232L(CHIPS)':
 'PGND'<2>: CDS_PINID='PGND(2)';
NODE_NAME     EU7B1 19
 '@BASEBOARD_FAB2_LIB.BASEBOARD_FAB2(SCH_1):PAGE232_I214@MSTR_VREG.NCP3232L(CHIPS)':
 'PGND'<3>: CDS_PINID='PGND(3)';
NODE_NAME     EU7B1 20
 '@BASEBOARD_FAB2_LIB.BASEBOARD_FAB2(SCH_1):PAGE232_I214@MSTR_VREG.NCP3232L(CHIPS)':
 'PGND'<4>: CDS_PINID='PGND(4)';
NODE_NAME     EU7B1 21
 '@BASEBOARD_FAB2_LIB.BASEBOARD_FAB2(SCH_1):PAGE232_I214@MSTR_VREG.NCP3232L(CHIPS)':
 'PGND'<5>: CDS_PINID='PGND(5)';
NODE_NAME     EU7B1 22
 '@BASEBOARD_FAB2_LIB.BASEBOARD_FAB2(SCH_1):PAGE232_I214@MSTR_VREG.NCP3232L(CHIPS)':
 'PGND'<6>: CDS_PINID='PGND(6)';
NODE_NAME     EU7B1 23
 '@BASEBOARD_FAB2_LIB.BASEBOARD_FAB2(SCH_1):PAGE232_I214@MSTR_VREG.NCP3232L(CHIPS)':
 'PGND'<7>: CDS_PINID='PGND(7)';
NODE_NAME     EU7B1 24
 '@BASEBOARD_FAB2_LIB.BASEBOARD_FAB2(SCH_1):PAGE232_I214@MSTR_VREG.NCP3232L(CHIPS)':
 'PGND'<8>: CDS_PINID='PGND(8)';
NODE_NAME     EU7B1 25
 '@BASEBOARD_FAB2_LIB.BASEBOARD_FAB2(SCH_1):PAGE232_I214@MSTR_VREG.NCP3232L(CHIPS)':
 'PGND'<9>: CDS_PINID='PGND(9)';
NODE_NAME     EU7B1 26
 '@BASEBOARD_FAB2_LIB.BASEBOARD_FAB2(SCH_1):PAGE232_I214@MSTR_VREG.NCP3232L(CHIPS)':
 'PGND'<10>: CDS_PINID='PGND(10)';
NODE_NAME     EU7B1 27
 '@BASEBOARD_FAB2_LIB.BASEBOARD_FAB2(SCH_1):PAGE232_I214@MSTR_VREG.NCP3232L(CHIPS)':
 'PGND'<11>: CDS_PINID='PGND(11)';
NODE_NAME     EU7B1 28
 '@BASEBOARD_FAB2_LIB.BASEBOARD_FAB2(SCH_1):PAGE232_I214@MSTR_VREG.NCP3232L(CHIPS)':
 'PGND'<12>: CDS_PINID='PGND(12)';
NODE_NAME     EU7B1 37
 '@BASEBOARD_FAB2_LIB.BASEBOARD_FAB2(SCH_1):PAGE232_I214@MSTR_VREG.NCP3232L(CHIPS)':
 'PGND'<13>: CDS_PINID='PGND(13)';
NODE_NAME     R7A15 2
 '@BASEBOARD_FAB2_LIB.BASEBOARD_FAB2(SCH_1):PAGE232_I218@MSTR_DISCRETE.RES(CHIPS)':
 'B': CDS_PINID='B';
NODE_NAME     R7B10 2
 '@BASEBOARD_FAB2_LIB.BASEBOARD_FAB2(SCH_1):PAGE232_I227@MSTR_DISCRETE.RES(CHIPS)':
 'B': CDS_PINID='B';
NODE_NAME     C6B7 2
 '@BASEBOARD_FAB2_LIB.BASEBOARD_FAB2(SCH_1):PAGE232_I229@MSTR_DISCRETE.CAPP(CHIPS)':
 'B': CDS_PINID='B';
NODE_NAME     C6B3 2
 '@BASEBOARD_FAB2_LIB.BASEBOARD_FAB2(SCH_1):PAGE232_I236@MSTR_DISCRETE.CAP(CHIPS)':
 'B': CDS_PINID='B';
NODE_NAME     C7B7 2
 '@BASEBOARD_FAB2_LIB.BASEBOARD_FAB2(SCH_1):PAGE232_I238@MSTR_DISCRETE.CAP(CHIPS)':
 'B': CDS_PINID='B';
NODE_NAME     C7B6 2
 '@BASEBOARD_FAB2_LIB.BASEBOARD_FAB2(SCH_1):PAGE232_I252@DEV_DISCRETE.CAP_A(CHIPS)':
 'B': CDS_PINID='B';
NODE_NAME     C3M8 2
 '@BASEBOARD_FAB2_LIB.BASEBOARD_FAB2(SCH_1):PAGE232_I259@MSTR_DISCRETE.CAP(CHIPS)':
 'B': CDS_PINID='B';
NODE_NAME     C3M15 2
 '@BASEBOARD_FAB2_LIB.BASEBOARD_FAB2(SCH_1):PAGE232_I260@MSTR_DISCRETE.CAP(CHIPS)':
 'B': CDS_PINID='B';
NODE_NAME     C3M16 2
 '@BASEBOARD_FAB2_LIB.BASEBOARD_FAB2(SCH_1):PAGE232_I261@MSTR_DISCRETE.CAP(CHIPS)':
 'B': CDS_PINID='B';
NODE_NAME     C7B5 2
 '@BASEBOARD_FAB2_LIB.BASEBOARD_FAB2(SCH_1):PAGE232_I262@MSTR_DISCRETE.CAP(CHIPS)':
 'B': CDS_PINID='B';
NODE_NAME     C4M1 2
 '@BASEBOARD_FAB2_LIB.BASEBOARD_FAB2(SCH_1):PAGE232_I267@MSTR_DISCRETE.CAPP(CHIPS)':
 'B': CDS_PINID='B';
NODE_NAME     C7U4 2
 '@BASEBOARD_FAB2_LIB.BASEBOARD_FAB2(SCH_1):PAGE233_I109@MSTR_DISCRETE.CAP(CHIPS)':
 'B': CDS_PINID='B';
NODE_NAME     C7U5 2
 '@BASEBOARD_FAB2_LIB.BASEBOARD_FAB2(SCH_1):PAGE233_I111@MSTR_DISCRETE.CAP(CHIPS)':
 'B': CDS_PINID='B';
NODE_NAME     C7T2 2
 '@BASEBOARD_FAB2_LIB.BASEBOARD_FAB2(SCH_1):PAGE233_I112@MSTR_DISCRETE.CAP(CHIPS)':
 'B': CDS_PINID='B';
NODE_NAME     C7T3 2
 '@BASEBOARD_FAB2_LIB.BASEBOARD_FAB2(SCH_1):PAGE233_I113@MSTR_DISCRETE.CAP(CHIPS)':
 'B': CDS_PINID='B';
NODE_NAME     C7U6 2
 '@BASEBOARD_FAB2_LIB.BASEBOARD_FAB2(SCH_1):PAGE233_I115@MSTR_DISCRETE.CAP(CHIPS)':
 'B': CDS_PINID='B';
NODE_NAME     C3F3 2
 '@BASEBOARD_FAB2_LIB.BASEBOARD_FAB2(SCH_1):PAGE233_I116@MSTR_DISCRETE.CAP(CHIPS)':
 'B': CDS_PINID='B';
NODE_NAME     C3F4 2
 '@BASEBOARD_FAB2_LIB.BASEBOARD_FAB2(SCH_1):PAGE233_I117@MSTR_DISCRETE.CAP(CHIPS)':
 'B': CDS_PINID='B';
NODE_NAME     C3G3 2
 '@BASEBOARD_FAB2_LIB.BASEBOARD_FAB2(SCH_1):PAGE233_I118@MSTR_DISCRETE.CAP(CHIPS)':
 'B': CDS_PINID='B';
NODE_NAME     C3G7 2
 '@BASEBOARD_FAB2_LIB.BASEBOARD_FAB2(SCH_1):PAGE233_I132@MSTR_DISCRETE.CAP(CHIPS)':
 'B': CDS_PINID='B';
NODE_NAME     C3G4 2
 '@BASEBOARD_FAB2_LIB.BASEBOARD_FAB2(SCH_1):PAGE233_I133@MSTR_DISCRETE.CAP(CHIPS)':
 'B': CDS_PINID='B';
NODE_NAME     C3G8 2
 '@BASEBOARD_FAB2_LIB.BASEBOARD_FAB2(SCH_1):PAGE233_I135@MSTR_DISCRETE.CAP(CHIPS)':
 'B': CDS_PINID='B';
NODE_NAME     C7U3 2
 '@BASEBOARD_FAB2_LIB.BASEBOARD_FAB2(SCH_1):PAGE233_I136@MSTR_DISCRETE.CAP(CHIPS)':
 'B': CDS_PINID='B';
NODE_NAME     R4G25 1
 '@BASEBOARD_FAB2_LIB.BASEBOARD_FAB2(SCH_1):PAGE233_I157@MSTR_DISCRETE.RES(CHIPS)':
 'A': CDS_PINID='A';
NODE_NAME     R4G5 2
 '@BASEBOARD_FAB2_LIB.BASEBOARD_FAB2(SCH_1):PAGE233_I182@MSTR_DISCRETE.RES(CHIPS)':
 'B': CDS_PINID='B';
NODE_NAME     C4G4 2
 '@BASEBOARD_FAB2_LIB.BASEBOARD_FAB2(SCH_1):PAGE233_I196@MSTR_DISCRETE.CAP(CHIPS)':
 'B': CDS_PINID='B';
NODE_NAME     C4G9 2
 '@BASEBOARD_FAB2_LIB.BASEBOARD_FAB2(SCH_1):PAGE233_I201@MSTR_DISCRETE.CAP(CHIPS)':
 'B': CDS_PINID='B';
NODE_NAME     R4F6 2
 '@BASEBOARD_FAB2_LIB.BASEBOARD_FAB2(SCH_1):PAGE233_I208@MSTR_DISCRETE.RES(CHIPS)':
 'B': CDS_PINID='B';
NODE_NAME     R4G6 2
 '@BASEBOARD_FAB2_LIB.BASEBOARD_FAB2(SCH_1):PAGE233_I211@MSTR_DISCRETE.RES(CHIPS)':
 'B': CDS_PINID='B';
NODE_NAME     C4F7 2
 '@BASEBOARD_FAB2_LIB.BASEBOARD_FAB2(SCH_1):PAGE233_I217@MSTR_DISCRETE.CAPP(CHIPS)':
 'B': CDS_PINID='B';
NODE_NAME     C6U3 2
 '@BASEBOARD_FAB2_LIB.BASEBOARD_FAB2(SCH_1):PAGE233_I221@MSTR_DISCRETE.CAP(CHIPS)':
 'B': CDS_PINID='B';
NODE_NAME     C6U2 2
 '@BASEBOARD_FAB2_LIB.BASEBOARD_FAB2(SCH_1):PAGE233_I223@MSTR_DISCRETE.CAP(CHIPS)':
 'B': CDS_PINID='B';
NODE_NAME     EU4G1 41
 '@BASEBOARD_FAB2_LIB.BASEBOARD_FAB2(SCH_1):PAGE233_I225@MSTR_VREG.NCP3232L(CHIPS)':
 'GND': CDS_PINID='GND';
NODE_NAME     EU4G1 16
 '@BASEBOARD_FAB2_LIB.BASEBOARD_FAB2(SCH_1):PAGE233_I225@MSTR_VREG.NCP3232L(CHIPS)':
 'PGND'<0>: CDS_PINID='PGND(0)';
NODE_NAME     EU4G1 17
 '@BASEBOARD_FAB2_LIB.BASEBOARD_FAB2(SCH_1):PAGE233_I225@MSTR_VREG.NCP3232L(CHIPS)':
 'PGND'<1>: CDS_PINID='PGND(1)';
NODE_NAME     EU4G1 18
 '@BASEBOARD_FAB2_LIB.BASEBOARD_FAB2(SCH_1):PAGE233_I225@MSTR_VREG.NCP3232L(CHIPS)':
 'PGND'<2>: CDS_PINID='PGND(2)';
NODE_NAME     EU4G1 19
 '@BASEBOARD_FAB2_LIB.BASEBOARD_FAB2(SCH_1):PAGE233_I225@MSTR_VREG.NCP3232L(CHIPS)':
 'PGND'<3>: CDS_PINID='PGND(3)';
NODE_NAME     EU4G1 20
 '@BASEBOARD_FAB2_LIB.BASEBOARD_FAB2(SCH_1):PAGE233_I225@MSTR_VREG.NCP3232L(CHIPS)':
 'PGND'<4>: CDS_PINID='PGND(4)';
NODE_NAME     EU4G1 21
 '@BASEBOARD_FAB2_LIB.BASEBOARD_FAB2(SCH_1):PAGE233_I225@MSTR_VREG.NCP3232L(CHIPS)':
 'PGND'<5>: CDS_PINID='PGND(5)';
NODE_NAME     EU4G1 22
 '@BASEBOARD_FAB2_LIB.BASEBOARD_FAB2(SCH_1):PAGE233_I225@MSTR_VREG.NCP3232L(CHIPS)':
 'PGND'<6>: CDS_PINID='PGND(6)';
NODE_NAME     EU4G1 23
 '@BASEBOARD_FAB2_LIB.BASEBOARD_FAB2(SCH_1):PAGE233_I225@MSTR_VREG.NCP3232L(CHIPS)':
 'PGND'<7>: CDS_PINID='PGND(7)';
NODE_NAME     EU4G1 24
 '@BASEBOARD_FAB2_LIB.BASEBOARD_FAB2(SCH_1):PAGE233_I225@MSTR_VREG.NCP3232L(CHIPS)':
 'PGND'<8>: CDS_PINID='PGND(8)';
NODE_NAME     EU4G1 25
 '@BASEBOARD_FAB2_LIB.BASEBOARD_FAB2(SCH_1):PAGE233_I225@MSTR_VREG.NCP3232L(CHIPS)':
 'PGND'<9>: CDS_PINID='PGND(9)';
NODE_NAME     EU4G1 26
 '@BASEBOARD_FAB2_LIB.BASEBOARD_FAB2(SCH_1):PAGE233_I225@MSTR_VREG.NCP3232L(CHIPS)':
 'PGND'<10>: CDS_PINID='PGND(10)';
NODE_NAME     EU4G1 27
 '@BASEBOARD_FAB2_LIB.BASEBOARD_FAB2(SCH_1):PAGE233_I225@MSTR_VREG.NCP3232L(CHIPS)':
 'PGND'<11>: CDS_PINID='PGND(11)';
NODE_NAME     EU4G1 28
 '@BASEBOARD_FAB2_LIB.BASEBOARD_FAB2(SCH_1):PAGE233_I225@MSTR_VREG.NCP3232L(CHIPS)':
 'PGND'<12>: CDS_PINID='PGND(12)';
NODE_NAME     EU4G1 37
 '@BASEBOARD_FAB2_LIB.BASEBOARD_FAB2(SCH_1):PAGE233_I225@MSTR_VREG.NCP3232L(CHIPS)':
 'PGND'<13>: CDS_PINID='PGND(13)';
NODE_NAME     C6U5 2
 '@BASEBOARD_FAB2_LIB.BASEBOARD_FAB2(SCH_1):PAGE233_I242@DEV_DISCRETE.CAP_A(CHIPS)':
 'B': CDS_PINID='B';
NODE_NAME     C6U4 2
 '@BASEBOARD_FAB2_LIB.BASEBOARD_FAB2(SCH_1):PAGE233_I248@MSTR_DISCRETE.CAP(CHIPS)':
 'B': CDS_PINID='B';
NODE_NAME     C4G2 2
 '@BASEBOARD_FAB2_LIB.BASEBOARD_FAB2(SCH_1):PAGE233_I253@MSTR_DISCRETE.CAP(CHIPS)':
 'B': CDS_PINID='B';
NODE_NAME     C6U7 2
 '@BASEBOARD_FAB2_LIB.BASEBOARD_FAB2(SCH_1):PAGE233_I254@MSTR_DISCRETE.CAP(CHIPS)':
 'B': CDS_PINID='B';
NODE_NAME     C6U8 2
 '@BASEBOARD_FAB2_LIB.BASEBOARD_FAB2(SCH_1):PAGE233_I255@MSTR_DISCRETE.CAP(CHIPS)':
 'B': CDS_PINID='B';
NODE_NAME     C4F11 2
 '@BASEBOARD_FAB2_LIB.BASEBOARD_FAB2(SCH_1):PAGE233_I256@MSTR_DISCRETE.CAPP(CHIPS)':
 'B': CDS_PINID='B';
NODE_NAME     R4B14 1
 '@BASEBOARD_FAB2_LIB.BASEBOARD_FAB2(SCH_1):PAGE234_I29@MSTR_DISCRETE.RES(CHIPS)':
 'A': CDS_PINID='A';
NODE_NAME     C3B2 2
 '@BASEBOARD_FAB2_LIB.BASEBOARD_FAB2(SCH_1):PAGE234_I84@MSTR_DISCRETE.CAP(CHIPS)':
 'B': CDS_PINID='B';
NODE_NAME     C3A8 2
 '@BASEBOARD_FAB2_LIB.BASEBOARD_FAB2(SCH_1):PAGE234_I86@MSTR_DISCRETE.CAP(CHIPS)':
 'B': CDS_PINID='B';
NODE_NAME     C7L3 2
 '@BASEBOARD_FAB2_LIB.BASEBOARD_FAB2(SCH_1):PAGE234_I87@MSTR_DISCRETE.CAP(CHIPS)':
 'B': CDS_PINID='B';
NODE_NAME     C7L2 2
 '@BASEBOARD_FAB2_LIB.BASEBOARD_FAB2(SCH_1):PAGE234_I88@MSTR_DISCRETE.CAP(CHIPS)':
 'B': CDS_PINID='B';
NODE_NAME     C7L7 2
 '@BASEBOARD_FAB2_LIB.BASEBOARD_FAB2(SCH_1):PAGE234_I89@MSTR_DISCRETE.CAP(CHIPS)':
 'B': CDS_PINID='B';
NODE_NAME     C7L6 2
 '@BASEBOARD_FAB2_LIB.BASEBOARD_FAB2(SCH_1):PAGE234_I90@MSTR_DISCRETE.CAP(CHIPS)':
 'B': CDS_PINID='B';
NODE_NAME     C7M4 2
 '@BASEBOARD_FAB2_LIB.BASEBOARD_FAB2(SCH_1):PAGE234_I91@MSTR_DISCRETE.CAP(CHIPS)':
 'B': CDS_PINID='B';
NODE_NAME     C7M3 2
 '@BASEBOARD_FAB2_LIB.BASEBOARD_FAB2(SCH_1):PAGE234_I92@MSTR_DISCRETE.CAP(CHIPS)':
 'B': CDS_PINID='B';
NODE_NAME     C3A4 2
 '@BASEBOARD_FAB2_LIB.BASEBOARD_FAB2(SCH_1):PAGE234_I93@MSTR_DISCRETE.CAP(CHIPS)':
 'B': CDS_PINID='B';
NODE_NAME     C3B1 2
 '@BASEBOARD_FAB2_LIB.BASEBOARD_FAB2(SCH_1):PAGE234_I94@MSTR_DISCRETE.CAP(CHIPS)':
 'B': CDS_PINID='B';
NODE_NAME     C3A7 2
 '@BASEBOARD_FAB2_LIB.BASEBOARD_FAB2(SCH_1):PAGE234_I95@MSTR_DISCRETE.CAP(CHIPS)':
 'B': CDS_PINID='B';
NODE_NAME     C3A3 2
 '@BASEBOARD_FAB2_LIB.BASEBOARD_FAB2(SCH_1):PAGE234_I97@MSTR_DISCRETE.CAP(CHIPS)':
 'B': CDS_PINID='B';
NODE_NAME     C4B8 2
 '@BASEBOARD_FAB2_LIB.BASEBOARD_FAB2(SCH_1):PAGE234_I139@MSTR_DISCRETE.CAP(CHIPS)':
 'B': CDS_PINID='B';
NODE_NAME     C6L11 2
 '@BASEBOARD_FAB2_LIB.BASEBOARD_FAB2(SCH_1):PAGE234_I152@MSTR_DISCRETE.CAP(CHIPS)':
 'B': CDS_PINID='B';
NODE_NAME     R4A7 2
 '@BASEBOARD_FAB2_LIB.BASEBOARD_FAB2(SCH_1):PAGE234_I162@MSTR_DISCRETE.RES(CHIPS)':
 'B': CDS_PINID='B';
NODE_NAME     C3B3 2
 '@BASEBOARD_FAB2_LIB.BASEBOARD_FAB2(SCH_1):PAGE234_I167@MSTR_DISCRETE.CAPP(CHIPS)':
 'B': CDS_PINID='B';
NODE_NAME     C4B3 2
 '@BASEBOARD_FAB2_LIB.BASEBOARD_FAB2(SCH_1):PAGE234_I177@MSTR_DISCRETE.CAP(CHIPS)':
 'B': CDS_PINID='B';
NODE_NAME     C4B2 2
 '@BASEBOARD_FAB2_LIB.BASEBOARD_FAB2(SCH_1):PAGE234_I180@MSTR_DISCRETE.CAP(CHIPS)':
 'B': CDS_PINID='B';
NODE_NAME     R4B2 2
 '@BASEBOARD_FAB2_LIB.BASEBOARD_FAB2(SCH_1):PAGE234_I183@MSTR_DISCRETE.RES(CHIPS)':
 'B': CDS_PINID='B';
NODE_NAME     EU4A3 41
 '@BASEBOARD_FAB2_LIB.BASEBOARD_FAB2(SCH_1):PAGE234_I184@MSTR_VREG.NCP3232L(CHIPS)':
 'GND': CDS_PINID='GND';
NODE_NAME     EU4A3 16
 '@BASEBOARD_FAB2_LIB.BASEBOARD_FAB2(SCH_1):PAGE234_I184@MSTR_VREG.NCP3232L(CHIPS)':
 'PGND'<0>: CDS_PINID='PGND(0)';
NODE_NAME     EU4A3 17
 '@BASEBOARD_FAB2_LIB.BASEBOARD_FAB2(SCH_1):PAGE234_I184@MSTR_VREG.NCP3232L(CHIPS)':
 'PGND'<1>: CDS_PINID='PGND(1)';
NODE_NAME     EU4A3 18
 '@BASEBOARD_FAB2_LIB.BASEBOARD_FAB2(SCH_1):PAGE234_I184@MSTR_VREG.NCP3232L(CHIPS)':
 'PGND'<2>: CDS_PINID='PGND(2)';
NODE_NAME     EU4A3 19
 '@BASEBOARD_FAB2_LIB.BASEBOARD_FAB2(SCH_1):PAGE234_I184@MSTR_VREG.NCP3232L(CHIPS)':
 'PGND'<3>: CDS_PINID='PGND(3)';
NODE_NAME     EU4A3 20
 '@BASEBOARD_FAB2_LIB.BASEBOARD_FAB2(SCH_1):PAGE234_I184@MSTR_VREG.NCP3232L(CHIPS)':
 'PGND'<4>: CDS_PINID='PGND(4)';
NODE_NAME     EU4A3 21
 '@BASEBOARD_FAB2_LIB.BASEBOARD_FAB2(SCH_1):PAGE234_I184@MSTR_VREG.NCP3232L(CHIPS)':
 'PGND'<5>: CDS_PINID='PGND(5)';
NODE_NAME     EU4A3 22
 '@BASEBOARD_FAB2_LIB.BASEBOARD_FAB2(SCH_1):PAGE234_I184@MSTR_VREG.NCP3232L(CHIPS)':
 'PGND'<6>: CDS_PINID='PGND(6)';
NODE_NAME     EU4A3 23
 '@BASEBOARD_FAB2_LIB.BASEBOARD_FAB2(SCH_1):PAGE234_I184@MSTR_VREG.NCP3232L(CHIPS)':
 'PGND'<7>: CDS_PINID='PGND(7)';
NODE_NAME     EU4A3 24
 '@BASEBOARD_FAB2_LIB.BASEBOARD_FAB2(SCH_1):PAGE234_I184@MSTR_VREG.NCP3232L(CHIPS)':
 'PGND'<8>: CDS_PINID='PGND(8)';
NODE_NAME     EU4A3 25
 '@BASEBOARD_FAB2_LIB.BASEBOARD_FAB2(SCH_1):PAGE234_I184@MSTR_VREG.NCP3232L(CHIPS)':
 'PGND'<9>: CDS_PINID='PGND(9)';
NODE_NAME     EU4A3 26
 '@BASEBOARD_FAB2_LIB.BASEBOARD_FAB2(SCH_1):PAGE234_I184@MSTR_VREG.NCP3232L(CHIPS)':
 'PGND'<10>: CDS_PINID='PGND(10)';
NODE_NAME     EU4A3 27
 '@BASEBOARD_FAB2_LIB.BASEBOARD_FAB2(SCH_1):PAGE234_I184@MSTR_VREG.NCP3232L(CHIPS)':
 'PGND'<11>: CDS_PINID='PGND(11)';
NODE_NAME     EU4A3 28
 '@BASEBOARD_FAB2_LIB.BASEBOARD_FAB2(SCH_1):PAGE234_I184@MSTR_VREG.NCP3232L(CHIPS)':
 'PGND'<12>: CDS_PINID='PGND(12)';
NODE_NAME     EU4A3 37
 '@BASEBOARD_FAB2_LIB.BASEBOARD_FAB2(SCH_1):PAGE234_I184@MSTR_VREG.NCP3232L(CHIPS)':
 'PGND'<13>: CDS_PINID='PGND(13)';
NODE_NAME     C4A20 2
 '@BASEBOARD_FAB2_LIB.BASEBOARD_FAB2(SCH_1):PAGE234_I199@DEV_DISCRETE.CAP_A(CHIPS)':
 'B': CDS_PINID='B';
NODE_NAME     C6L10 2
 '@BASEBOARD_FAB2_LIB.BASEBOARD_FAB2(SCH_1):PAGE234_I202@MSTR_DISCRETE.CAP(CHIPS)':
 'B': CDS_PINID='B';
NODE_NAME     C6M3 2
 '@BASEBOARD_FAB2_LIB.BASEBOARD_FAB2(SCH_1):PAGE234_I203@MSTR_DISCRETE.CAP(CHIPS)':
 'B': CDS_PINID='B';
NODE_NAME     C6M5 2
 '@BASEBOARD_FAB2_LIB.BASEBOARD_FAB2(SCH_1):PAGE234_I204@MSTR_DISCRETE.CAP(CHIPS)':
 'B': CDS_PINID='B';
NODE_NAME     C4A19 2
 '@BASEBOARD_FAB2_LIB.BASEBOARD_FAB2(SCH_1):PAGE234_I205@MSTR_DISCRETE.CAP(CHIPS)':
 'B': CDS_PINID='B';
NODE_NAME     C6L8 2
 '@BASEBOARD_FAB2_LIB.BASEBOARD_FAB2(SCH_1):PAGE234_I210@MSTR_DISCRETE.CAPP(CHIPS)':
 'B': CDS_PINID='B';
NODE_NAME     C8A7 2
 '@BASEBOARD_FAB2_LIB.BASEBOARD_FAB2(SCH_1):PAGE235_I143@DEV_DISCRETE.CAP_A(CHIPS)':
 'B': CDS_PINID='B';
NODE_NAME     C8A8 2
 '@BASEBOARD_FAB2_LIB.BASEBOARD_FAB2(SCH_1):PAGE235_I145@DEV_DISCRETE.CAP_A(CHIPS)':
 'B': CDS_PINID='B';
NODE_NAME     C2L8 2
 '@BASEBOARD_FAB2_LIB.BASEBOARD_FAB2(SCH_1):PAGE235_I151@DEV_DISCRETE.CAP_A(CHIPS)':
 'B': CDS_PINID='B';
NODE_NAME     R2L10 2
 '@BASEBOARD_FAB2_LIB.BASEBOARD_FAB2(SCH_1):PAGE235_I166@MSTR_DISCRETE.RES(CHIPS)':
 'B': CDS_PINID='B';
NODE_NAME     C2L11 2
 '@BASEBOARD_FAB2_LIB.BASEBOARD_FAB2(SCH_1):PAGE235_I169@DEV_DISCRETE.CAP_A(CHIPS)':
 'B': CDS_PINID='B';
NODE_NAME     R8A2 2
 '@BASEBOARD_FAB2_LIB.BASEBOARD_FAB2(SCH_1):PAGE235_I217@MSTR_DISCRETE.RES(CHIPS)':
 'B': CDS_PINID='B';
NODE_NAME     C8A9 2
 '@BASEBOARD_FAB2_LIB.BASEBOARD_FAB2(SCH_1):PAGE235_I218@MSTR_DISCRETE.CAP(CHIPS)':
 'B': CDS_PINID='B';
NODE_NAME     EU8A1 27
 '@BASEBOARD_FAB2_LIB.BASEBOARD_FAB2(SCH_1):PAGE235_I229@MSTR_CONTROLLER.PXE1110B(CHIPS)':
 'GND'<0>: CDS_PINID='GND(0)';
NODE_NAME     EU8A1 23
 '@BASEBOARD_FAB2_LIB.BASEBOARD_FAB2(SCH_1):PAGE235_I229@MSTR_CONTROLLER.PXE1110B(CHIPS)':
 'GND'<1>: CDS_PINID='GND(1)';
NODE_NAME     EU8A1 41
 '@BASEBOARD_FAB2_LIB.BASEBOARD_FAB2(SCH_1):PAGE235_I229@MSTR_CONTROLLER.PXE1110B(CHIPS)':
 'THPAD': CDS_PINID='THPAD';
NODE_NAME     C7A30 2
 '@BASEBOARD_FAB2_LIB.BASEBOARD_FAB2(SCH_1):PAGE236_I9@MSTR_DISCRETE.CAP(CHIPS)':
 'B': CDS_PINID='B';
NODE_NAME     C7A8 2
 '@BASEBOARD_FAB2_LIB.BASEBOARD_FAB2(SCH_1):PAGE236_I16@MSTR_DISCRETE.CAP(CHIPS)':
 'B': CDS_PINID='B';
NODE_NAME     C7A6 2
 '@BASEBOARD_FAB2_LIB.BASEBOARD_FAB2(SCH_1):PAGE236_I19@MSTR_DISCRETE.CAP(CHIPS)':
 'B': CDS_PINID='B';
NODE_NAME     C7A39 2
 '@BASEBOARD_FAB2_LIB.BASEBOARD_FAB2(SCH_1):PAGE236_I20@DEV_DISCRETE.CAP_A(CHIPS)':
 'B': CDS_PINID='B';
NODE_NAME     C7A7 2
 '@BASEBOARD_FAB2_LIB.BASEBOARD_FAB2(SCH_1):PAGE236_I22@MSTR_DISCRETE.CAP(CHIPS)':
 'B': CDS_PINID='B';
NODE_NAME     C3L12 2
 '@BASEBOARD_FAB2_LIB.BASEBOARD_FAB2(SCH_1):PAGE236_I23@MSTR_DISCRETE.CAP(CHIPS)':
 'B': CDS_PINID='B';
NODE_NAME     C3L11 2
 '@BASEBOARD_FAB2_LIB.BASEBOARD_FAB2(SCH_1):PAGE236_I24@MSTR_DISCRETE.CAP(CHIPS)':
 'B': CDS_PINID='B';
NODE_NAME     C3L8 2
 '@BASEBOARD_FAB2_LIB.BASEBOARD_FAB2(SCH_1):PAGE236_I26@MSTR_DISCRETE.CAP(CHIPS)':
 'B': CDS_PINID='B';
NODE_NAME     C3L9 2
 '@BASEBOARD_FAB2_LIB.BASEBOARD_FAB2(SCH_1):PAGE236_I29@MSTR_DISCRETE.CAP(CHIPS)':
 'B': CDS_PINID='B';
NODE_NAME     C3L7 2
 '@BASEBOARD_FAB2_LIB.BASEBOARD_FAB2(SCH_1):PAGE236_I31@MSTR_DISCRETE.CAP(CHIPS)':
 'B': CDS_PINID='B';
NODE_NAME     C3L10 2
 '@BASEBOARD_FAB2_LIB.BASEBOARD_FAB2(SCH_1):PAGE236_I32@MSTR_DISCRETE.CAP(CHIPS)':
 'B': CDS_PINID='B';
NODE_NAME     C7A9 2
 '@BASEBOARD_FAB2_LIB.BASEBOARD_FAB2(SCH_1):PAGE236_I33@MSTR_DISCRETE.CAP(CHIPS)':
 'B': CDS_PINID='B';
NODE_NAME     C7A40 2
 '@BASEBOARD_FAB2_LIB.BASEBOARD_FAB2(SCH_1):PAGE236_I35@DEV_DISCRETE.CAP_A(CHIPS)':
 'B': CDS_PINID='B';
NODE_NAME     C7A10 2
 '@BASEBOARD_FAB2_LIB.BASEBOARD_FAB2(SCH_1):PAGE236_I36@MSTR_DISCRETE.CAP(CHIPS)':
 'B': CDS_PINID='B';
NODE_NAME     C7A41 2
 '@BASEBOARD_FAB2_LIB.BASEBOARD_FAB2(SCH_1):PAGE236_I39@MSTR_DISCRETE.CAP(CHIPS)':
 'B': CDS_PINID='B';
NODE_NAME     C7A42 2
 '@BASEBOARD_FAB2_LIB.BASEBOARD_FAB2(SCH_1):PAGE236_I46@MSTR_DISCRETE.CAP(CHIPS)':
 'B': CDS_PINID='B';
NODE_NAME     R8B12 2
 '@BASEBOARD_FAB2_LIB.BASEBOARD_FAB2(SCH_1):PAGE236_I59@MSTR_DISCRETE.RES(CHIPS)':
 'B': CDS_PINID='B';
NODE_NAME     C3L18 2
 '@BASEBOARD_FAB2_LIB.BASEBOARD_FAB2(SCH_1):PAGE236_I71@MSTR_DISCRETE.CAPP(CHIPS)':
 'B': CDS_PINID='B';
NODE_NAME     C3L20 2
 '@BASEBOARD_FAB2_LIB.BASEBOARD_FAB2(SCH_1):PAGE236_I73@MSTR_DISCRETE.CAPP(CHIPS)':
 'B': CDS_PINID='B';
NODE_NAME     C3L21 2
 '@BASEBOARD_FAB2_LIB.BASEBOARD_FAB2(SCH_1):PAGE236_I74@MSTR_DISCRETE.CAPP(CHIPS)':
 'B': CDS_PINID='B';
NODE_NAME     C7A27 2
 '@BASEBOARD_FAB2_LIB.BASEBOARD_FAB2(SCH_1):PAGE236_I75@MSTR_DISCRETE.CAPP(CHIPS)':
 'B': CDS_PINID='B';
NODE_NAME     C3L19 2
 '@BASEBOARD_FAB2_LIB.BASEBOARD_FAB2(SCH_1):PAGE236_I76@MSTR_DISCRETE.CAPP(CHIPS)':
 'B': CDS_PINID='B';
NODE_NAME     C2L46 2
 '@BASEBOARD_FAB2_LIB.BASEBOARD_FAB2(SCH_1):PAGE236_I77@MSTR_DISCRETE.CAPP(CHIPS)':
 'B': CDS_PINID='B';
NODE_NAME     C8A15 2
 '@BASEBOARD_FAB2_LIB.BASEBOARD_FAB2(SCH_1):PAGE236_I78@MSTR_DISCRETE.CAPP(CHIPS)':
 'B': CDS_PINID='B';
NODE_NAME     C2L25 2
 '@BASEBOARD_FAB2_LIB.BASEBOARD_FAB2(SCH_1):PAGE236_I79@MSTR_DISCRETE.CAPP(CHIPS)':
 'B': CDS_PINID='B';
NODE_NAME     R7A18 1
 '@BASEBOARD_FAB2_LIB.BASEBOARD_FAB2(SCH_1):PAGE236_I92@MSTR_DISCRETE.RES(CHIPS)':
 'A': CDS_PINID='A';
NODE_NAME     EU7A3 2
 '@BASEBOARD_FAB2_LIB.BASEBOARD_FAB2(SCH_1):PAGE236_I116@MSTR_DISCRETE.IR354XX(CHIPS)':
 'LGND': CDS_PINID='LGND';
NODE_NAME     EU7A3 5
 '@BASEBOARD_FAB2_LIB.BASEBOARD_FAB2(SCH_1):PAGE236_I116@MSTR_DISCRETE.IR354XX(CHIPS)':
 'PGND'<0>: CDS_PINID='PGND(0)';
NODE_NAME     EU7A3 7
 '@BASEBOARD_FAB2_LIB.BASEBOARD_FAB2(SCH_1):PAGE236_I116@MSTR_DISCRETE.IR354XX(CHIPS)':
 'PGND'<1>: CDS_PINID='PGND(1)';
NODE_NAME     EU7A3 40
 '@BASEBOARD_FAB2_LIB.BASEBOARD_FAB2(SCH_1):PAGE236_I116@MSTR_DISCRETE.IR354XX(CHIPS)':
 'PGND'<2>: CDS_PINID='PGND(2)';
NODE_NAME     EU7A2 2
 '@BASEBOARD_FAB2_LIB.BASEBOARD_FAB2(SCH_1):PAGE236_I117@MSTR_DISCRETE.IR354XX(CHIPS)':
 'LGND': CDS_PINID='LGND';
NODE_NAME     EU7A2 5
 '@BASEBOARD_FAB2_LIB.BASEBOARD_FAB2(SCH_1):PAGE236_I117@MSTR_DISCRETE.IR354XX(CHIPS)':
 'PGND'<0>: CDS_PINID='PGND(0)';
NODE_NAME     EU7A2 7
 '@BASEBOARD_FAB2_LIB.BASEBOARD_FAB2(SCH_1):PAGE236_I117@MSTR_DISCRETE.IR354XX(CHIPS)':
 'PGND'<1>: CDS_PINID='PGND(1)';
NODE_NAME     EU7A2 40
 '@BASEBOARD_FAB2_LIB.BASEBOARD_FAB2(SCH_1):PAGE236_I117@MSTR_DISCRETE.IR354XX(CHIPS)':
 'PGND'<2>: CDS_PINID='PGND(2)';
NODE_NAME     R3L15 2
 '@BASEBOARD_FAB2_LIB.BASEBOARD_FAB2(SCH_1):PAGE236_I118@MSTR_DISCRETE.RES(CHIPS)':
 'B': CDS_PINID='B';
NODE_NAME     R3L14 2
 '@BASEBOARD_FAB2_LIB.BASEBOARD_FAB2(SCH_1):PAGE236_I120@MSTR_DISCRETE.RES(CHIPS)':
 'B': CDS_PINID='B';
NODE_NAME     C8A11 2
 '@BASEBOARD_FAB2_LIB.BASEBOARD_FAB2(SCH_1):PAGE237_I5@MSTR_DISCRETE.CAP(CHIPS)':
 'B': CDS_PINID='B';
NODE_NAME     C2L45 2
 '@BASEBOARD_FAB2_LIB.BASEBOARD_FAB2(SCH_1):PAGE237_I12@MSTR_DISCRETE.CAP(CHIPS)':
 'B': CDS_PINID='B';
NODE_NAME     C8A14 2
 '@BASEBOARD_FAB2_LIB.BASEBOARD_FAB2(SCH_1):PAGE237_I13@MSTR_DISCRETE.CAP(CHIPS)':
 'B': CDS_PINID='B';
NODE_NAME     R8A12 2
 '@BASEBOARD_FAB2_LIB.BASEBOARD_FAB2(SCH_1):PAGE237_I15@MSTR_DISCRETE.RES(CHIPS)':
 'B': CDS_PINID='B';
NODE_NAME     C8A6 2
 '@BASEBOARD_FAB2_LIB.BASEBOARD_FAB2(SCH_1):PAGE237_I29@MSTR_DISCRETE.CAP(CHIPS)':
 'B': CDS_PINID='B';
NODE_NAME     C8A4 2
 '@BASEBOARD_FAB2_LIB.BASEBOARD_FAB2(SCH_1):PAGE237_I31@MSTR_DISCRETE.CAP(CHIPS)':
 'B': CDS_PINID='B';
NODE_NAME     C8A10 2
 '@BASEBOARD_FAB2_LIB.BASEBOARD_FAB2(SCH_1):PAGE237_I55@MSTR_DISCRETE.CAP(CHIPS)':
 'B': CDS_PINID='B';
NODE_NAME     C8A12 2
 '@BASEBOARD_FAB2_LIB.BASEBOARD_FAB2(SCH_1):PAGE237_I77@MSTR_DISCRETE.CAP(CHIPS)':
 'B': CDS_PINID='B';
NODE_NAME     C2L32 2
 '@BASEBOARD_FAB2_LIB.BASEBOARD_FAB2(SCH_1):PAGE237_I79@MSTR_DISCRETE.CAP(CHIPS)':
 'B': CDS_PINID='B';
NODE_NAME     R2L19 2
 '@BASEBOARD_FAB2_LIB.BASEBOARD_FAB2(SCH_1):PAGE237_I80@MSTR_DISCRETE.RES(CHIPS)':
 'B': CDS_PINID='B';
NODE_NAME     EU8A2 11
 '@BASEBOARD_FAB2_LIB.BASEBOARD_FAB2(SCH_1):PAGE237_I86@MSTR_VREG.RT9059(CHIPS)':
 'GND': CDS_PINID='GND';
NODE_NAME     C9F9 2
 '@BASEBOARD_FAB2_LIB.BASEBOARD_FAB2(SCH_1):PAGE238_I5@MSTR_DISCRETE.CAP(CHIPS)':
 'B': CDS_PINID='B';
NODE_NAME     C9F3 2
 '@BASEBOARD_FAB2_LIB.BASEBOARD_FAB2(SCH_1):PAGE238_I7@MSTR_DISCRETE.CAP(CHIPS)':
 'B': CDS_PINID='B';
NODE_NAME     R9F8 1
 '@BASEBOARD_FAB2_LIB.BASEBOARD_FAB2(SCH_1):PAGE238_I14@MSTR_DISCRETE.RES(CHIPS)':
 'A': CDS_PINID='A';
NODE_NAME     C9F8 2
 '@BASEBOARD_FAB2_LIB.BASEBOARD_FAB2(SCH_1):PAGE238_I19@MSTR_DISCRETE.CAP(CHIPS)':
 'B': CDS_PINID='B';
NODE_NAME     C9E10 2
 '@BASEBOARD_FAB2_LIB.BASEBOARD_FAB2(SCH_1):PAGE238_I23@MSTR_DISCRETE.CAP(CHIPS)':
 'B': CDS_PINID='B';
NODE_NAME     C9F4 2
 '@BASEBOARD_FAB2_LIB.BASEBOARD_FAB2(SCH_1):PAGE238_I30@MSTR_DISCRETE.CAP(CHIPS)':
 'B': CDS_PINID='B';
NODE_NAME     C9E11 2
 '@BASEBOARD_FAB2_LIB.BASEBOARD_FAB2(SCH_1):PAGE238_I39@MSTR_DISCRETE.CAP(CHIPS)':
 'B': CDS_PINID='B';
NODE_NAME     EU9F1 11
 '@BASEBOARD_FAB2_LIB.BASEBOARD_FAB2(SCH_1):PAGE238_I40@MSTR_VREG.RT9059(CHIPS)':
 'GND': CDS_PINID='GND';
NODE_NAME     C9F10 2
 '@BASEBOARD_FAB2_LIB.BASEBOARD_FAB2(SCH_1):PAGE239_I4@MSTR_DISCRETE.CAP(CHIPS)':
 'B': CDS_PINID='B';
NODE_NAME     C9F13 2
 '@BASEBOARD_FAB2_LIB.BASEBOARD_FAB2(SCH_1):PAGE239_I7@MSTR_DISCRETE.CAP(CHIPS)':
 'B': CDS_PINID='B';
NODE_NAME     C1T15 2
 '@BASEBOARD_FAB2_LIB.BASEBOARD_FAB2(SCH_1):PAGE239_I12@MSTR_DISCRETE.CAP(CHIPS)':
 'B': CDS_PINID='B';
NODE_NAME     C1T7 2
 '@BASEBOARD_FAB2_LIB.BASEBOARD_FAB2(SCH_1):PAGE239_I22@MSTR_DISCRETE.CAP(CHIPS)':
 'B': CDS_PINID='B';
NODE_NAME     C9F6 2
 '@BASEBOARD_FAB2_LIB.BASEBOARD_FAB2(SCH_1):PAGE239_I30@MSTR_DISCRETE.CAP(CHIPS)':
 'B': CDS_PINID='B';
NODE_NAME     EU9F2 11
 '@BASEBOARD_FAB2_LIB.BASEBOARD_FAB2(SCH_1):PAGE239_I70@MSTR_VREG.RT9059(CHIPS)':
 'GND': CDS_PINID='GND';
NODE_NAME     C9F5 2
 '@BASEBOARD_FAB2_LIB.BASEBOARD_FAB2(SCH_1):PAGE239_I71@DEV_DISCRETE.CAP_A(CHIPS)':
 'B': CDS_PINID='B';
NODE_NAME     R8F1 2
 '@BASEBOARD_FAB2_LIB.BASEBOARD_FAB2(SCH_1):PAGE240_I111@MSTR_DISCRETE.RES(CHIPS)':
 'B': CDS_PINID='B';
NODE_NAME     C8F2 2
 '@BASEBOARD_FAB2_LIB.BASEBOARD_FAB2(SCH_1):PAGE240_I116@MSTR_DISCRETE.CAP(CHIPS)':
 'B': CDS_PINID='B';
NODE_NAME     C8E10 2
 '@BASEBOARD_FAB2_LIB.BASEBOARD_FAB2(SCH_1):PAGE240_I137@MSTR_DISCRETE.CAP(CHIPS)':
 'B': CDS_PINID='B';
NODE_NAME     C8E14 2
 '@BASEBOARD_FAB2_LIB.BASEBOARD_FAB2(SCH_1):PAGE240_I139@MSTR_DISCRETE.CAP(CHIPS)':
 'B': CDS_PINID='B';
NODE_NAME     R8F11 1
 '@BASEBOARD_FAB2_LIB.BASEBOARD_FAB2(SCH_1):PAGE240_I146@MSTR_DISCRETE.RES(CHIPS)':
 'A': CDS_PINID='A';
NODE_NAME     R8F3 2
 '@BASEBOARD_FAB2_LIB.BASEBOARD_FAB2(SCH_1):PAGE240_I148@MSTR_DISCRETE.RES(CHIPS)':
 'B': CDS_PINID='B';
NODE_NAME     R2T4 2
 '@BASEBOARD_FAB2_LIB.BASEBOARD_FAB2(SCH_1):PAGE240_I152@MSTR_DISCRETE.RES(CHIPS)':
 'B': CDS_PINID='B';
NODE_NAME     C2T7 2
 '@BASEBOARD_FAB2_LIB.BASEBOARD_FAB2(SCH_1):PAGE240_I158@MSTR_DISCRETE.CAP(CHIPS)':
 'B': CDS_PINID='B';
NODE_NAME     C2T6 2
 '@BASEBOARD_FAB2_LIB.BASEBOARD_FAB2(SCH_1):PAGE240_I160@MSTR_DISCRETE.CAP(CHIPS)':
 'B': CDS_PINID='B';
NODE_NAME     EU8E1 3
 '@BASEBOARD_FAB2_LIB.BASEBOARD_FAB2(SCH_1):PAGE240_I170@MSTR_DISCRETE.CSD87384M(CHIPS)':
 'PGND': CDS_PINID='PGND';
NODE_NAME     C2T9 2
 '@BASEBOARD_FAB2_LIB.BASEBOARD_FAB2(SCH_1):PAGE240_I174@MSTR_DISCRETE.CAP(CHIPS)':
 'B': CDS_PINID='B';
NODE_NAME     R8E18 2
 '@BASEBOARD_FAB2_LIB.BASEBOARD_FAB2(SCH_1):PAGE241_I9@MSTR_DISCRETE.RES(CHIPS)':
 'B': CDS_PINID='B';
NODE_NAME     C7E10 2
 '@BASEBOARD_FAB2_LIB.BASEBOARD_FAB2(SCH_1):PAGE241_I14@MSTR_DISCRETE.CAP(CHIPS)':
 'B': CDS_PINID='B';
NODE_NAME     C7E14 2
 '@BASEBOARD_FAB2_LIB.BASEBOARD_FAB2(SCH_1):PAGE241_I30@MSTR_DISCRETE.CAP(CHIPS)':
 'B': CDS_PINID='B';
NODE_NAME     C7E11 2
 '@BASEBOARD_FAB2_LIB.BASEBOARD_FAB2(SCH_1):PAGE241_I39@MSTR_DISCRETE.CAP(CHIPS)':
 'B': CDS_PINID='B';
NODE_NAME     R7E13 1
 '@BASEBOARD_FAB2_LIB.BASEBOARD_FAB2(SCH_1):PAGE241_I58@MSTR_DISCRETE.RES(CHIPS)':
 'A': CDS_PINID='A';
NODE_NAME     EU7E2 2
 '@BASEBOARD_FAB2_LIB.BASEBOARD_FAB2(SCH_1):PAGE241_I83@MSTR_VREG.TPS54821(CHIPS)':
 'GND'<0>: CDS_PINID='GND(0)';
NODE_NAME     EU7E2 3
 '@BASEBOARD_FAB2_LIB.BASEBOARD_FAB2(SCH_1):PAGE241_I83@MSTR_VREG.TPS54821(CHIPS)':
 'GND'<1>: CDS_PINID='GND(1)';
NODE_NAME     EU7E2 15
 '@BASEBOARD_FAB2_LIB.BASEBOARD_FAB2(SCH_1):PAGE241_I83@MSTR_VREG.TPS54821(CHIPS)':
 'THPAD': CDS_PINID='THPAD';
NODE_NAME     C5G41 2
 '@BASEBOARD_FAB2_LIB.BASEBOARD_FAB2(SCH_1):PAGE242_I53@DEV_DISCRETE.CAP_A(CHIPS)':
 'B': CDS_PINID='B';
NODE_NAME     C5G42 2
 '@BASEBOARD_FAB2_LIB.BASEBOARD_FAB2(SCH_1):PAGE242_I54@DEV_DISCRETE.CAP_A(CHIPS)':
 'B': CDS_PINID='B';
NODE_NAME     C5G44 2
 '@BASEBOARD_FAB2_LIB.BASEBOARD_FAB2(SCH_1):PAGE242_I55@DEV_DISCRETE.CAP_A(CHIPS)':
 'B': CDS_PINID='B';
NODE_NAME     C5G43 2
 '@BASEBOARD_FAB2_LIB.BASEBOARD_FAB2(SCH_1):PAGE242_I56@DEV_DISCRETE.CAP_A(CHIPS)':
 'B': CDS_PINID='B';
NODE_NAME     C5G48 2
 '@BASEBOARD_FAB2_LIB.BASEBOARD_FAB2(SCH_1):PAGE242_I57@DEV_DISCRETE.CAP_A(CHIPS)':
 'B': CDS_PINID='B';
NODE_NAME     C5G47 2
 '@BASEBOARD_FAB2_LIB.BASEBOARD_FAB2(SCH_1):PAGE242_I58@DEV_DISCRETE.CAP_A(CHIPS)':
 'B': CDS_PINID='B';
NODE_NAME     C5G46 2
 '@BASEBOARD_FAB2_LIB.BASEBOARD_FAB2(SCH_1):PAGE242_I59@DEV_DISCRETE.CAP_A(CHIPS)':
 'B': CDS_PINID='B';
NODE_NAME     C5G45 2
 '@BASEBOARD_FAB2_LIB.BASEBOARD_FAB2(SCH_1):PAGE242_I60@DEV_DISCRETE.CAP_A(CHIPS)':
 'B': CDS_PINID='B';
NODE_NAME     C5G49 2
 '@BASEBOARD_FAB2_LIB.BASEBOARD_FAB2(SCH_1):PAGE242_I61@DEV_DISCRETE.CAP_A(CHIPS)':
 'B': CDS_PINID='B';
NODE_NAME     C5G54 2
 '@BASEBOARD_FAB2_LIB.BASEBOARD_FAB2(SCH_1):PAGE242_I62@DEV_DISCRETE.CAP_A(CHIPS)':
 'B': CDS_PINID='B';
NODE_NAME     C5G58 2
 '@BASEBOARD_FAB2_LIB.BASEBOARD_FAB2(SCH_1):PAGE242_I63@DEV_DISCRETE.CAP_A(CHIPS)':
 'B': CDS_PINID='B';
NODE_NAME     C5G57 2
 '@BASEBOARD_FAB2_LIB.BASEBOARD_FAB2(SCH_1):PAGE242_I64@DEV_DISCRETE.CAP_A(CHIPS)':
 'B': CDS_PINID='B';
NODE_NAME     C5G56 2
 '@BASEBOARD_FAB2_LIB.BASEBOARD_FAB2(SCH_1):PAGE242_I65@DEV_DISCRETE.CAP_A(CHIPS)':
 'B': CDS_PINID='B';
NODE_NAME     C5G55 2
 '@BASEBOARD_FAB2_LIB.BASEBOARD_FAB2(SCH_1):PAGE242_I66@DEV_DISCRETE.CAP_A(CHIPS)':
 'B': CDS_PINID='B';
NODE_NAME     C5G53 2
 '@BASEBOARD_FAB2_LIB.BASEBOARD_FAB2(SCH_1):PAGE242_I67@DEV_DISCRETE.CAP_A(CHIPS)':
 'B': CDS_PINID='B';
NODE_NAME     C5G52 2
 '@BASEBOARD_FAB2_LIB.BASEBOARD_FAB2(SCH_1):PAGE242_I68@DEV_DISCRETE.CAP_A(CHIPS)':
 'B': CDS_PINID='B';
NODE_NAME     C5G51 2
 '@BASEBOARD_FAB2_LIB.BASEBOARD_FAB2(SCH_1):PAGE242_I69@DEV_DISCRETE.CAP_A(CHIPS)':
 'B': CDS_PINID='B';
NODE_NAME     C5G50 2
 '@BASEBOARD_FAB2_LIB.BASEBOARD_FAB2(SCH_1):PAGE242_I70@DEV_DISCRETE.CAP_A(CHIPS)':
 'B': CDS_PINID='B';
NODE_NAME     C5G67 2
 '@BASEBOARD_FAB2_LIB.BASEBOARD_FAB2(SCH_1):PAGE242_I71@DEV_DISCRETE.CAP_A(CHIPS)':
 'B': CDS_PINID='B';
NODE_NAME     C5G66 2
 '@BASEBOARD_FAB2_LIB.BASEBOARD_FAB2(SCH_1):PAGE242_I72@DEV_DISCRETE.CAP_A(CHIPS)':
 'B': CDS_PINID='B';
NODE_NAME     C5G65 2
 '@BASEBOARD_FAB2_LIB.BASEBOARD_FAB2(SCH_1):PAGE242_I73@DEV_DISCRETE.CAP_A(CHIPS)':
 'B': CDS_PINID='B';
NODE_NAME     C5G64 2
 '@BASEBOARD_FAB2_LIB.BASEBOARD_FAB2(SCH_1):PAGE242_I74@DEV_DISCRETE.CAP_A(CHIPS)':
 'B': CDS_PINID='B';
NODE_NAME     C5G63 2
 '@BASEBOARD_FAB2_LIB.BASEBOARD_FAB2(SCH_1):PAGE242_I75@DEV_DISCRETE.CAP_A(CHIPS)':
 'B': CDS_PINID='B';
NODE_NAME     C5G62 2
 '@BASEBOARD_FAB2_LIB.BASEBOARD_FAB2(SCH_1):PAGE242_I76@DEV_DISCRETE.CAP_A(CHIPS)':
 'B': CDS_PINID='B';
NODE_NAME     C5G61 2
 '@BASEBOARD_FAB2_LIB.BASEBOARD_FAB2(SCH_1):PAGE242_I77@DEV_DISCRETE.CAP_A(CHIPS)':
 'B': CDS_PINID='B';
NODE_NAME     C5G60 2
 '@BASEBOARD_FAB2_LIB.BASEBOARD_FAB2(SCH_1):PAGE242_I78@DEV_DISCRETE.CAP_A(CHIPS)':
 'B': CDS_PINID='B';
NODE_NAME     C5G59 2
 '@BASEBOARD_FAB2_LIB.BASEBOARD_FAB2(SCH_1):PAGE242_I79@DEV_DISCRETE.CAP_A(CHIPS)':
 'B': CDS_PINID='B';
NODE_NAME     C5G76 2
 '@BASEBOARD_FAB2_LIB.BASEBOARD_FAB2(SCH_1):PAGE242_I80@DEV_DISCRETE.CAP_A(CHIPS)':
 'B': CDS_PINID='B';
NODE_NAME     C5G75 2
 '@BASEBOARD_FAB2_LIB.BASEBOARD_FAB2(SCH_1):PAGE242_I81@DEV_DISCRETE.CAP_A(CHIPS)':
 'B': CDS_PINID='B';
NODE_NAME     C5G74 2
 '@BASEBOARD_FAB2_LIB.BASEBOARD_FAB2(SCH_1):PAGE242_I82@DEV_DISCRETE.CAP_A(CHIPS)':
 'B': CDS_PINID='B';
NODE_NAME     C5G73 2
 '@BASEBOARD_FAB2_LIB.BASEBOARD_FAB2(SCH_1):PAGE242_I83@DEV_DISCRETE.CAP_A(CHIPS)':
 'B': CDS_PINID='B';
NODE_NAME     C5G72 2
 '@BASEBOARD_FAB2_LIB.BASEBOARD_FAB2(SCH_1):PAGE242_I84@DEV_DISCRETE.CAP_A(CHIPS)':
 'B': CDS_PINID='B';
NODE_NAME     C5G71 2
 '@BASEBOARD_FAB2_LIB.BASEBOARD_FAB2(SCH_1):PAGE242_I85@DEV_DISCRETE.CAP_A(CHIPS)':
 'B': CDS_PINID='B';
NODE_NAME     C5G70 2
 '@BASEBOARD_FAB2_LIB.BASEBOARD_FAB2(SCH_1):PAGE242_I86@DEV_DISCRETE.CAP_A(CHIPS)':
 'B': CDS_PINID='B';
NODE_NAME     C5G69 2
 '@BASEBOARD_FAB2_LIB.BASEBOARD_FAB2(SCH_1):PAGE242_I87@DEV_DISCRETE.CAP_A(CHIPS)':
 'B': CDS_PINID='B';
NODE_NAME     C5G68 2
 '@BASEBOARD_FAB2_LIB.BASEBOARD_FAB2(SCH_1):PAGE242_I88@DEV_DISCRETE.CAP_A(CHIPS)':
 'B': CDS_PINID='B';
NODE_NAME     C5G79 2
 '@BASEBOARD_FAB2_LIB.BASEBOARD_FAB2(SCH_1):PAGE243_I53@DEV_DISCRETE.CAP_A(CHIPS)':
 'B': CDS_PINID='B';
NODE_NAME     C5G87 2
 '@BASEBOARD_FAB2_LIB.BASEBOARD_FAB2(SCH_1):PAGE243_I54@DEV_DISCRETE.CAP_A(CHIPS)':
 'B': CDS_PINID='B';
NODE_NAME     C5G86 2
 '@BASEBOARD_FAB2_LIB.BASEBOARD_FAB2(SCH_1):PAGE243_I55@DEV_DISCRETE.CAP_A(CHIPS)':
 'B': CDS_PINID='B';
NODE_NAME     C5G85 2
 '@BASEBOARD_FAB2_LIB.BASEBOARD_FAB2(SCH_1):PAGE243_I56@DEV_DISCRETE.CAP_A(CHIPS)':
 'B': CDS_PINID='B';
NODE_NAME     C5G84 2
 '@BASEBOARD_FAB2_LIB.BASEBOARD_FAB2(SCH_1):PAGE243_I57@DEV_DISCRETE.CAP_A(CHIPS)':
 'B': CDS_PINID='B';
NODE_NAME     C5G83 2
 '@BASEBOARD_FAB2_LIB.BASEBOARD_FAB2(SCH_1):PAGE243_I58@DEV_DISCRETE.CAP_A(CHIPS)':
 'B': CDS_PINID='B';
NODE_NAME     C5G82 2
 '@BASEBOARD_FAB2_LIB.BASEBOARD_FAB2(SCH_1):PAGE243_I59@DEV_DISCRETE.CAP_A(CHIPS)':
 'B': CDS_PINID='B';
NODE_NAME     C5G81 2
 '@BASEBOARD_FAB2_LIB.BASEBOARD_FAB2(SCH_1):PAGE243_I60@DEV_DISCRETE.CAP_A(CHIPS)':
 'B': CDS_PINID='B';
NODE_NAME     C5G80 2
 '@BASEBOARD_FAB2_LIB.BASEBOARD_FAB2(SCH_1):PAGE243_I61@DEV_DISCRETE.CAP_A(CHIPS)':
 'B': CDS_PINID='B';
NODE_NAME     C5G96 2
 '@BASEBOARD_FAB2_LIB.BASEBOARD_FAB2(SCH_1):PAGE243_I62@DEV_DISCRETE.CAP_A(CHIPS)':
 'B': CDS_PINID='B';
NODE_NAME     C5G95 2
 '@BASEBOARD_FAB2_LIB.BASEBOARD_FAB2(SCH_1):PAGE243_I63@DEV_DISCRETE.CAP_A(CHIPS)':
 'B': CDS_PINID='B';
NODE_NAME     C5G94 2
 '@BASEBOARD_FAB2_LIB.BASEBOARD_FAB2(SCH_1):PAGE243_I64@DEV_DISCRETE.CAP_A(CHIPS)':
 'B': CDS_PINID='B';
NODE_NAME     C5G93 2
 '@BASEBOARD_FAB2_LIB.BASEBOARD_FAB2(SCH_1):PAGE243_I65@DEV_DISCRETE.CAP_A(CHIPS)':
 'B': CDS_PINID='B';
NODE_NAME     C5G92 2
 '@BASEBOARD_FAB2_LIB.BASEBOARD_FAB2(SCH_1):PAGE243_I66@DEV_DISCRETE.CAP_A(CHIPS)':
 'B': CDS_PINID='B';
NODE_NAME     C5G91 2
 '@BASEBOARD_FAB2_LIB.BASEBOARD_FAB2(SCH_1):PAGE243_I67@DEV_DISCRETE.CAP_A(CHIPS)':
 'B': CDS_PINID='B';
NODE_NAME     C5G90 2
 '@BASEBOARD_FAB2_LIB.BASEBOARD_FAB2(SCH_1):PAGE243_I68@DEV_DISCRETE.CAP_A(CHIPS)':
 'B': CDS_PINID='B';
NODE_NAME     C5G89 2
 '@BASEBOARD_FAB2_LIB.BASEBOARD_FAB2(SCH_1):PAGE243_I69@DEV_DISCRETE.CAP_A(CHIPS)':
 'B': CDS_PINID='B';
NODE_NAME     C5G88 2
 '@BASEBOARD_FAB2_LIB.BASEBOARD_FAB2(SCH_1):PAGE243_I70@DEV_DISCRETE.CAP_A(CHIPS)':
 'B': CDS_PINID='B';
NODE_NAME     C5G103 2
 '@BASEBOARD_FAB2_LIB.BASEBOARD_FAB2(SCH_1):PAGE243_I71@DEV_DISCRETE.CAP_A(CHIPS)':
 'B': CDS_PINID='B';
NODE_NAME     C5G104 2
 '@BASEBOARD_FAB2_LIB.BASEBOARD_FAB2(SCH_1):PAGE243_I72@DEV_DISCRETE.CAP_A(CHIPS)':
 'B': CDS_PINID='B';
NODE_NAME     C5G105 2
 '@BASEBOARD_FAB2_LIB.BASEBOARD_FAB2(SCH_1):PAGE243_I73@DEV_DISCRETE.CAP_A(CHIPS)':
 'B': CDS_PINID='B';
NODE_NAME     C5G102 2
 '@BASEBOARD_FAB2_LIB.BASEBOARD_FAB2(SCH_1):PAGE243_I74@DEV_DISCRETE.CAP_A(CHIPS)':
 'B': CDS_PINID='B';
NODE_NAME     C5G101 2
 '@BASEBOARD_FAB2_LIB.BASEBOARD_FAB2(SCH_1):PAGE243_I75@DEV_DISCRETE.CAP_A(CHIPS)':
 'B': CDS_PINID='B';
NODE_NAME     C5G100 2
 '@BASEBOARD_FAB2_LIB.BASEBOARD_FAB2(SCH_1):PAGE243_I76@DEV_DISCRETE.CAP_A(CHIPS)':
 'B': CDS_PINID='B';
NODE_NAME     C5G99 2
 '@BASEBOARD_FAB2_LIB.BASEBOARD_FAB2(SCH_1):PAGE243_I77@DEV_DISCRETE.CAP_A(CHIPS)':
 'B': CDS_PINID='B';
NODE_NAME     C5G98 2
 '@BASEBOARD_FAB2_LIB.BASEBOARD_FAB2(SCH_1):PAGE243_I78@DEV_DISCRETE.CAP_A(CHIPS)':
 'B': CDS_PINID='B';
NODE_NAME     C5G97 2
 '@BASEBOARD_FAB2_LIB.BASEBOARD_FAB2(SCH_1):PAGE243_I79@DEV_DISCRETE.CAP_A(CHIPS)':
 'B': CDS_PINID='B';
NODE_NAME     C5G114 2
 '@BASEBOARD_FAB2_LIB.BASEBOARD_FAB2(SCH_1):PAGE243_I80@DEV_DISCRETE.CAP_A(CHIPS)':
 'B': CDS_PINID='B';
NODE_NAME     C5G113 2
 '@BASEBOARD_FAB2_LIB.BASEBOARD_FAB2(SCH_1):PAGE243_I81@DEV_DISCRETE.CAP_A(CHIPS)':
 'B': CDS_PINID='B';
NODE_NAME     C5G112 2
 '@BASEBOARD_FAB2_LIB.BASEBOARD_FAB2(SCH_1):PAGE243_I82@DEV_DISCRETE.CAP_A(CHIPS)':
 'B': CDS_PINID='B';
NODE_NAME     C5G111 2
 '@BASEBOARD_FAB2_LIB.BASEBOARD_FAB2(SCH_1):PAGE243_I83@DEV_DISCRETE.CAP_A(CHIPS)':
 'B': CDS_PINID='B';
NODE_NAME     C5G110 2
 '@BASEBOARD_FAB2_LIB.BASEBOARD_FAB2(SCH_1):PAGE243_I84@DEV_DISCRETE.CAP_A(CHIPS)':
 'B': CDS_PINID='B';
NODE_NAME     C5G109 2
 '@BASEBOARD_FAB2_LIB.BASEBOARD_FAB2(SCH_1):PAGE243_I85@DEV_DISCRETE.CAP_A(CHIPS)':
 'B': CDS_PINID='B';
NODE_NAME     C5G108 2
 '@BASEBOARD_FAB2_LIB.BASEBOARD_FAB2(SCH_1):PAGE243_I86@DEV_DISCRETE.CAP_A(CHIPS)':
 'B': CDS_PINID='B';
NODE_NAME     C5G107 2
 '@BASEBOARD_FAB2_LIB.BASEBOARD_FAB2(SCH_1):PAGE243_I87@DEV_DISCRETE.CAP_A(CHIPS)':
 'B': CDS_PINID='B';
NODE_NAME     C5G106 2
 '@BASEBOARD_FAB2_LIB.BASEBOARD_FAB2(SCH_1):PAGE243_I88@DEV_DISCRETE.CAP_A(CHIPS)':
 'B': CDS_PINID='B';
NODE_NAME     CT1 2
 '@BASEBOARD_FAB2_LIB.BASEBOARD_FAB2(SCH_1):PAGE202_I70@DEV_DISCRETE.CAP_A(CHIPS)':
 'B': CDS_PINID='B';
NODE_NAME     CT2 2
 '@BASEBOARD_FAB2_LIB.BASEBOARD_FAB2(SCH_1):PAGE202_I78@MSTR_DISCRETE.CAP(CHIPS)':
 'B': CDS_PINID='B';
NODE_NAME     CT6 2
 '@BASEBOARD_FAB2_LIB.BASEBOARD_FAB2(SCH_1):PAGE202_I81@DEV_DISCRETE.CAP_A(CHIPS)':
 'B': CDS_PINID='B';
NODE_NAME     CT7 2
 '@BASEBOARD_FAB2_LIB.BASEBOARD_FAB2(SCH_1):PAGE227_I109@DEV_DISCRETE.CAP_A(CHIPS)':
 'B': CDS_PINID='B';
NODE_NAME     CT8 2
 '@BASEBOARD_FAB2_LIB.BASEBOARD_FAB2(SCH_1):PAGE227_I114@MSTR_DISCRETE.CAP(CHIPS)':
 'B': CDS_PINID='B';
NODE_NAME     CT10 2
 '@BASEBOARD_FAB2_LIB.BASEBOARD_FAB2(SCH_1):PAGE227_I119@MSTR_DISCRETE.CAP(CHIPS)':
 'B': CDS_PINID='B';
NODE_NAME     CT12 2
 '@BASEBOARD_FAB2_LIB.BASEBOARD_FAB2(SCH_1):PAGE227_I122@DEV_DISCRETE.CAP_A(CHIPS)':
 'B': CDS_PINID='B';
NODE_NAME     CT13 2
 '@BASEBOARD_FAB2_LIB.BASEBOARD_FAB2(SCH_1):PAGE209_I62@DEV_DISCRETE.CAP_A(CHIPS)':
 'B': CDS_PINID='B';
NODE_NAME     CT15 2
 '@BASEBOARD_FAB2_LIB.BASEBOARD_FAB2(SCH_1):PAGE209_I67@MSTR_DISCRETE.CAP(CHIPS)':
 'B': CDS_PINID='B';
NODE_NAME     CT16 2
 '@BASEBOARD_FAB2_LIB.BASEBOARD_FAB2(SCH_1):PAGE208_I80@DEV_DISCRETE.CAP_A(CHIPS)':
 'B': CDS_PINID='B';
NODE_NAME     CTI7 2
 '@BASEBOARD_FAB2_LIB.BASEBOARD_FAB2(SCH_1):PAGE208_I82@MSTR_DISCRETE.CAP(CHIPS)':
 'B': CDS_PINID='B';
NODE_NAME     CT21 2
 '@BASEBOARD_FAB2_LIB.BASEBOARD_FAB2(SCH_1):PAGE208_I87@DEV_DISCRETE.CAP_A(CHIPS)':
 'B': CDS_PINID='B';
NODE_NAME     CT19 2
 '@BASEBOARD_FAB2_LIB.BASEBOARD_FAB2(SCH_1):PAGE208_I90@MSTR_DISCRETE.CAP(CHIPS)':
 'B': CDS_PINID='B';
NODE_NAME     CT24 2
 '@BASEBOARD_FAB2_LIB.BASEBOARD_FAB2(SCH_1):PAGE207_I71@DEV_DISCRETE.CAP_A(CHIPS)':
 'B': CDS_PINID='B';
NODE_NAME     CT22 2
 '@BASEBOARD_FAB2_LIB.BASEBOARD_FAB2(SCH_1):PAGE207_I74@MSTR_DISCRETE.CAP(CHIPS)':
 'B': CDS_PINID='B';
NODE_NAME     CT30 2
 '@BASEBOARD_FAB2_LIB.BASEBOARD_FAB2(SCH_1):PAGE224_I117@DEV_DISCRETE.CAP_A(CHIPS)':
 'B': CDS_PINID='B';
NODE_NAME     CT28 2
 '@BASEBOARD_FAB2_LIB.BASEBOARD_FAB2(SCH_1):PAGE224_I122@MSTR_DISCRETE.CAP(CHIPS)':
 'B': CDS_PINID='B';
NODE_NAME     CT31 2
 '@BASEBOARD_FAB2_LIB.BASEBOARD_FAB2(SCH_1):PAGE224_I124@DEV_DISCRETE.CAP_A(CHIPS)':
 'B': CDS_PINID='B';
NODE_NAME     CT32 2
 '@BASEBOARD_FAB2_LIB.BASEBOARD_FAB2(SCH_1):PAGE224_I130@MSTR_DISCRETE.CAP(CHIPS)':
 'B': CDS_PINID='B';
NODE_NAME     CT36 2
 '@BASEBOARD_FAB2_LIB.BASEBOARD_FAB2(SCH_1):PAGE204_I85@DEV_DISCRETE.CAP_A(CHIPS)':
 'B': CDS_PINID='B';
NODE_NAME     CT34 2
 '@BASEBOARD_FAB2_LIB.BASEBOARD_FAB2(SCH_1):PAGE204_I88@MSTR_DISCRETE.CAP(CHIPS)':
 'B': CDS_PINID='B';
NODE_NAME     CT40 2
 '@BASEBOARD_FAB2_LIB.BASEBOARD_FAB2(SCH_1):PAGE203_I93@DEV_DISCRETE.CAP_A(CHIPS)':
 'B': CDS_PINID='B';
NODE_NAME     CT39 2
 '@BASEBOARD_FAB2_LIB.BASEBOARD_FAB2(SCH_1):PAGE203_I96@DEV_DISCRETE.CAP_A(CHIPS)':
 'B': CDS_PINID='B';
NODE_NAME     CT37 2
 '@BASEBOARD_FAB2_LIB.BASEBOARD_FAB2(SCH_1):PAGE203_I99@MSTR_DISCRETE.CAP(CHIPS)':
 'B': CDS_PINID='B';
NODE_NAME     CT42 2
 '@BASEBOARD_FAB2_LIB.BASEBOARD_FAB2(SCH_1):PAGE203_I108@MSTR_DISCRETE.CAP(CHIPS)':
 'B': CDS_PINID='B';
NODE_NAME     CT46 2
 '@BASEBOARD_FAB2_LIB.BASEBOARD_FAB2(SCH_1):PAGE219_I113@DEV_DISCRETE.CAP_A(CHIPS)':
 'B': CDS_PINID='B';
NODE_NAME     CT45 2
 '@BASEBOARD_FAB2_LIB.BASEBOARD_FAB2(SCH_1):PAGE219_I116@DEV_DISCRETE.CAP_A(CHIPS)':
 'B': CDS_PINID='B';
NODE_NAME     CT48 2
 '@BASEBOARD_FAB2_LIB.BASEBOARD_FAB2(SCH_1):PAGE219_I119@MSTR_DISCRETE.CAP(CHIPS)':
 'B': CDS_PINID='B';
NODE_NAME     CT43 2
 '@BASEBOARD_FAB2_LIB.BASEBOARD_FAB2(SCH_1):PAGE219_I124@MSTR_DISCRETE.CAP(CHIPS)':
 'B': CDS_PINID='B';
NODE_NAME     CT51 2
 '@BASEBOARD_FAB2_LIB.BASEBOARD_FAB2(SCH_1):PAGE216_I108@DEV_DISCRETE.CAP_A(CHIPS)':
 'B': CDS_PINID='B';
NODE_NAME     CT52 2
 '@BASEBOARD_FAB2_LIB.BASEBOARD_FAB2(SCH_1):PAGE216_I111@DEV_DISCRETE.CAP_A(CHIPS)':
 'B': CDS_PINID='B';
NODE_NAME     CT49 2
 '@BASEBOARD_FAB2_LIB.BASEBOARD_FAB2(SCH_1):PAGE216_I118@MSTR_DISCRETE.CAP(CHIPS)':
 'B': CDS_PINID='B';
NODE_NAME     CT54 2
 '@BASEBOARD_FAB2_LIB.BASEBOARD_FAB2(SCH_1):PAGE216_I121@MSTR_DISCRETE.CAP(CHIPS)':
 'B': CDS_PINID='B';
NODE_NAME     CT57 2
 '@BASEBOARD_FAB2_LIB.BASEBOARD_FAB2(SCH_1):PAGE210_I55@DEV_DISCRETE.CAP_A(CHIPS)':
 'B': CDS_PINID='B';
NODE_NAME     CT55 2
 '@BASEBOARD_FAB2_LIB.BASEBOARD_FAB2(SCH_1):PAGE210_I60@MSTR_DISCRETE.CAP(CHIPS)':
 'B': CDS_PINID='B';
NODE_NAME     CT58 2
 '@BASEBOARD_FAB2_LIB.BASEBOARD_FAB2(SCH_1):PAGE205_I65@MSTR_DISCRETE.CAP(CHIPS)':
 'B': CDS_PINID='B';
NODE_NAME     CT60 2
 '@BASEBOARD_FAB2_LIB.BASEBOARD_FAB2(SCH_1):PAGE205_I69@DEV_DISCRETE.CAP_A(CHIPS)':
 'B': CDS_PINID='B';
NODE_NAME     CT61 2
 '@BASEBOARD_FAB2_LIB.BASEBOARD_FAB2(SCH_1):PAGE214_I134@MSTR_DISCRETE.CAP(CHIPS)':
 'B': CDS_PINID='B';
NODE_NAME     CT63 2
 '@BASEBOARD_FAB2_LIB.BASEBOARD_FAB2(SCH_1):PAGE214_I137@DEV_DISCRETE.CAP_A(CHIPS)':
 'B': CDS_PINID='B';
NODE_NAME     CT67 2
 '@BASEBOARD_FAB2_LIB.BASEBOARD_FAB2(SCH_1):PAGE236_I124@DEV_DISCRETE.CAP_A(CHIPS)':
 'B': CDS_PINID='B';
NODE_NAME     CT66 2
 '@BASEBOARD_FAB2_LIB.BASEBOARD_FAB2(SCH_1):PAGE236_I127@DEV_DISCRETE.CAP_A(CHIPS)':
 'B': CDS_PINID='B';
NODE_NAME     CT69 2
 '@BASEBOARD_FAB2_LIB.BASEBOARD_FAB2(SCH_1):PAGE236_I134@MSTR_DISCRETE.CAP(CHIPS)':
 'B': CDS_PINID='B';
NODE_NAME     CT64 2
 '@BASEBOARD_FAB2_LIB.BASEBOARD_FAB2(SCH_1):PAGE236_I136@MSTR_DISCRETE.CAP(CHIPS)':
 'B': CDS_PINID='B';
NODE_NAME     CT70 2
 '@BASEBOARD_FAB2_LIB.BASEBOARD_FAB2(SCH_1):PAGE212_I106@DEV_DISCRETE.CAP_A(CHIPS)':
 'B': CDS_PINID='B';
NODE_NAME     CT71 2
 '@BASEBOARD_FAB2_LIB.BASEBOARD_FAB2(SCH_1):PAGE212_I109@MSTR_DISCRETE.CAP(CHIPS)':
 'B': CDS_PINID='B';
NODE_NAME     CT25 2
 '@BASEBOARD_FAB2_LIB.BASEBOARD_FAB2(SCH_1):PAGE207_I81@DEV_DISCRETE.CAP_A(CHIPS)':
 'B': CDS_PINID='B';
NODE_NAME     CT26 2
 '@BASEBOARD_FAB2_LIB.BASEBOARD_FAB2(SCH_1):PAGE207_I82@MSTR_DISCRETE.CAP(CHIPS)':
 'B': CDS_PINID='B';
NODE_NAME     CT4 2
 '@BASEBOARD_FAB2_LIB.BASEBOARD_FAB2(SCH_1):PAGE202_I87@MSTR_DISCRETE.CAP(CHIPS)':
 'B': CDS_PINID='B';
NODE_NAME     CONX8 1
 '@BASEBOARD_FAB2_LIB.BASEBOARD_FAB2(SCH_1):PAGE245_I48@W_HDL.SMC-CONN60A-22-GP(CHIPS)':
 '1': CDS_PINID='\1\';
NODE_NAME     CONX8 4
 '@BASEBOARD_FAB2_LIB.BASEBOARD_FAB2(SCH_1):PAGE245_I48@W_HDL.SMC-CONN60A-22-GP(CHIPS)':
 '4': CDS_PINID='\4\';
NODE_NAME     CONX8 7
 '@BASEBOARD_FAB2_LIB.BASEBOARD_FAB2(SCH_1):PAGE245_I48@W_HDL.SMC-CONN60A-22-GP(CHIPS)':
 '7': CDS_PINID='\7\';
NODE_NAME     CONX8 10
 '@BASEBOARD_FAB2_LIB.BASEBOARD_FAB2(SCH_1):PAGE245_I48@W_HDL.SMC-CONN60A-22-GP(CHIPS)':
 '10': CDS_PINID='\10\';
NODE_NAME     CONX8 13
 '@BASEBOARD_FAB2_LIB.BASEBOARD_FAB2(SCH_1):PAGE245_I48@W_HDL.SMC-CONN60A-22-GP(CHIPS)':
 '13': CDS_PINID='\13\';
NODE_NAME     CONX8 16
 '@BASEBOARD_FAB2_LIB.BASEBOARD_FAB2(SCH_1):PAGE245_I48@W_HDL.SMC-CONN60A-22-GP(CHIPS)':
 '16': CDS_PINID='\16\';
NODE_NAME     CONX8 19
 '@BASEBOARD_FAB2_LIB.BASEBOARD_FAB2(SCH_1):PAGE245_I48@W_HDL.SMC-CONN60A-22-GP(CHIPS)':
 '19': CDS_PINID='\19\';
NODE_NAME     CONX8 22
 '@BASEBOARD_FAB2_LIB.BASEBOARD_FAB2(SCH_1):PAGE245_I48@W_HDL.SMC-CONN60A-22-GP(CHIPS)':
 '22': CDS_PINID='\22\';
NODE_NAME     CONX8 25
 '@BASEBOARD_FAB2_LIB.BASEBOARD_FAB2(SCH_1):PAGE245_I48@W_HDL.SMC-CONN60A-22-GP(CHIPS)':
 '25': CDS_PINID='\25\';
NODE_NAME     CONX8 28
 '@BASEBOARD_FAB2_LIB.BASEBOARD_FAB2(SCH_1):PAGE245_I48@W_HDL.SMC-CONN60A-22-GP(CHIPS)':
 '28': CDS_PINID='\28\';
NODE_NAME     CONX8 31
 '@BASEBOARD_FAB2_LIB.BASEBOARD_FAB2(SCH_1):PAGE245_I48@W_HDL.SMC-CONN60A-22-GP(CHIPS)':
 '31': CDS_PINID='\31\';
NODE_NAME     CONX8 34
 '@BASEBOARD_FAB2_LIB.BASEBOARD_FAB2(SCH_1):PAGE245_I48@W_HDL.SMC-CONN60A-22-GP(CHIPS)':
 '34': CDS_PINID='\34\';
NODE_NAME     CONX8 37
 '@BASEBOARD_FAB2_LIB.BASEBOARD_FAB2(SCH_1):PAGE245_I48@W_HDL.SMC-CONN60A-22-GP(CHIPS)':
 '37': CDS_PINID='\37\';
NODE_NAME     CONX8 40
 '@BASEBOARD_FAB2_LIB.BASEBOARD_FAB2(SCH_1):PAGE245_I48@W_HDL.SMC-CONN60A-22-GP(CHIPS)':
 '40': CDS_PINID='\40\';
NODE_NAME     CONX8 43
 '@BASEBOARD_FAB2_LIB.BASEBOARD_FAB2(SCH_1):PAGE245_I48@W_HDL.SMC-CONN60A-22-GP(CHIPS)':
 '43': CDS_PINID='\43\';
NODE_NAME     CONX8 46
 '@BASEBOARD_FAB2_LIB.BASEBOARD_FAB2(SCH_1):PAGE245_I48@W_HDL.SMC-CONN60A-22-GP(CHIPS)':
 '46': CDS_PINID='\46\';
NODE_NAME     CONX8 49
 '@BASEBOARD_FAB2_LIB.BASEBOARD_FAB2(SCH_1):PAGE245_I48@W_HDL.SMC-CONN60A-22-GP(CHIPS)':
 '49': CDS_PINID='\49\';
NODE_NAME     CONX8 52
 '@BASEBOARD_FAB2_LIB.BASEBOARD_FAB2(SCH_1):PAGE245_I48@W_HDL.SMC-CONN60A-22-GP(CHIPS)':
 '52': CDS_PINID='\52\';
NODE_NAME     CONX8 55
 '@BASEBOARD_FAB2_LIB.BASEBOARD_FAB2(SCH_1):PAGE245_I48@W_HDL.SMC-CONN60A-22-GP(CHIPS)':
 '55': CDS_PINID='\55\';
NODE_NAME     CONX8 58
 '@BASEBOARD_FAB2_LIB.BASEBOARD_FAB2(SCH_1):PAGE245_I48@W_HDL.SMC-CONN60A-22-GP(CHIPS)':
 '58': CDS_PINID='\58\';
NODE_NAME     CONX8 PTH1
 '@BASEBOARD_FAB2_LIB.BASEBOARD_FAB2(SCH_1):PAGE245_I48@W_HDL.SMC-CONN60A-22-GP(CHIPS)':
 'PTH1': CDS_PINID='PTH1';
NODE_NAME     CONX8 PTH2
 '@BASEBOARD_FAB2_LIB.BASEBOARD_FAB2(SCH_1):PAGE245_I48@W_HDL.SMC-CONN60A-22-GP(CHIPS)':
 'PTH2': CDS_PINID='PTH2';
NODE_NAME     J8G1 101
 '@BASEBOARD_FAB2_LIB.BASEBOARD_FAB2(SCH_1):PAGE109_I78@MSTR_SCONN.SCONN200_H68296001(CHIPS)':
 'IO101': CDS_PINID='IO101';
NODE_NAME     J8G1 104
 '@BASEBOARD_FAB2_LIB.BASEBOARD_FAB2(SCH_1):PAGE109_I78@MSTR_SCONN.SCONN200_H68296001(CHIPS)':
 'IO104': CDS_PINID='IO104';
NODE_NAME     J8G1 107
 '@BASEBOARD_FAB2_LIB.BASEBOARD_FAB2(SCH_1):PAGE109_I78@MSTR_SCONN.SCONN200_H68296001(CHIPS)':
 'IO107': CDS_PINID='IO107';
NODE_NAME     J8G1 110
 '@BASEBOARD_FAB2_LIB.BASEBOARD_FAB2(SCH_1):PAGE109_I78@MSTR_SCONN.SCONN200_H68296001(CHIPS)':
 'IO110': CDS_PINID='IO110';
NODE_NAME     J8G1 113
 '@BASEBOARD_FAB2_LIB.BASEBOARD_FAB2(SCH_1):PAGE109_I78@MSTR_SCONN.SCONN200_H68296001(CHIPS)':
 'IO113': CDS_PINID='IO113';
NODE_NAME     J8G1 116
 '@BASEBOARD_FAB2_LIB.BASEBOARD_FAB2(SCH_1):PAGE109_I78@MSTR_SCONN.SCONN200_H68296001(CHIPS)':
 'IO116': CDS_PINID='IO116';
NODE_NAME     J8G1 119
 '@BASEBOARD_FAB2_LIB.BASEBOARD_FAB2(SCH_1):PAGE109_I78@MSTR_SCONN.SCONN200_H68296001(CHIPS)':
 'IO119': CDS_PINID='IO119';
NODE_NAME     J8G1 122
 '@BASEBOARD_FAB2_LIB.BASEBOARD_FAB2(SCH_1):PAGE109_I78@MSTR_SCONN.SCONN200_H68296001(CHIPS)':
 'IO122': CDS_PINID='IO122';
NODE_NAME     J8G1 125
 '@BASEBOARD_FAB2_LIB.BASEBOARD_FAB2(SCH_1):PAGE109_I78@MSTR_SCONN.SCONN200_H68296001(CHIPS)':
 'IO125': CDS_PINID='IO125';
NODE_NAME     J8G1 128
 '@BASEBOARD_FAB2_LIB.BASEBOARD_FAB2(SCH_1):PAGE109_I78@MSTR_SCONN.SCONN200_H68296001(CHIPS)':
 'IO128': CDS_PINID='IO128';
NODE_NAME     J8G1 131
 '@BASEBOARD_FAB2_LIB.BASEBOARD_FAB2(SCH_1):PAGE109_I78@MSTR_SCONN.SCONN200_H68296001(CHIPS)':
 'IO131': CDS_PINID='IO131';
NODE_NAME     J8G1 134
 '@BASEBOARD_FAB2_LIB.BASEBOARD_FAB2(SCH_1):PAGE109_I78@MSTR_SCONN.SCONN200_H68296001(CHIPS)':
 'IO134': CDS_PINID='IO134';
NODE_NAME     J8G1 137
 '@BASEBOARD_FAB2_LIB.BASEBOARD_FAB2(SCH_1):PAGE109_I78@MSTR_SCONN.SCONN200_H68296001(CHIPS)':
 'IO137': CDS_PINID='IO137';
NODE_NAME     J8G1 140
 '@BASEBOARD_FAB2_LIB.BASEBOARD_FAB2(SCH_1):PAGE109_I78@MSTR_SCONN.SCONN200_H68296001(CHIPS)':
 'IO140': CDS_PINID='IO140';
NODE_NAME     J8G1 143
 '@BASEBOARD_FAB2_LIB.BASEBOARD_FAB2(SCH_1):PAGE109_I78@MSTR_SCONN.SCONN200_H68296001(CHIPS)':
 'IO143': CDS_PINID='IO143';
NODE_NAME     J8G1 146
 '@BASEBOARD_FAB2_LIB.BASEBOARD_FAB2(SCH_1):PAGE109_I78@MSTR_SCONN.SCONN200_H68296001(CHIPS)':
 'IO146': CDS_PINID='IO146';
NODE_NAME     J8G1 149
 '@BASEBOARD_FAB2_LIB.BASEBOARD_FAB2(SCH_1):PAGE109_I78@MSTR_SCONN.SCONN200_H68296001(CHIPS)':
 'IO149': CDS_PINID='IO149';
NODE_NAME     J8G1 152
 '@BASEBOARD_FAB2_LIB.BASEBOARD_FAB2(SCH_1):PAGE109_I78@MSTR_SCONN.SCONN200_H68296001(CHIPS)':
 'IO152': CDS_PINID='IO152';
NODE_NAME     J8G1 155
 '@BASEBOARD_FAB2_LIB.BASEBOARD_FAB2(SCH_1):PAGE109_I78@MSTR_SCONN.SCONN200_H68296001(CHIPS)':
 'IO155': CDS_PINID='IO155';
NODE_NAME     J8G1 158
 '@BASEBOARD_FAB2_LIB.BASEBOARD_FAB2(SCH_1):PAGE109_I78@MSTR_SCONN.SCONN200_H68296001(CHIPS)':
 'IO158': CDS_PINID='IO158';
NODE_NAME     J8G1 161
 '@BASEBOARD_FAB2_LIB.BASEBOARD_FAB2(SCH_1):PAGE109_I78@MSTR_SCONN.SCONN200_H68296001(CHIPS)':
 'IO161': CDS_PINID='IO161';
NODE_NAME     J8G1 164
 '@BASEBOARD_FAB2_LIB.BASEBOARD_FAB2(SCH_1):PAGE109_I78@MSTR_SCONN.SCONN200_H68296001(CHIPS)':
 'IO164': CDS_PINID='IO164';
NODE_NAME     J8G1 167
 '@BASEBOARD_FAB2_LIB.BASEBOARD_FAB2(SCH_1):PAGE109_I78@MSTR_SCONN.SCONN200_H68296001(CHIPS)':
 'IO167': CDS_PINID='IO167';
NODE_NAME     J8G1 170
 '@BASEBOARD_FAB2_LIB.BASEBOARD_FAB2(SCH_1):PAGE109_I78@MSTR_SCONN.SCONN200_H68296001(CHIPS)':
 'IO170': CDS_PINID='IO170';
NODE_NAME     J8G1 173
 '@BASEBOARD_FAB2_LIB.BASEBOARD_FAB2(SCH_1):PAGE109_I78@MSTR_SCONN.SCONN200_H68296001(CHIPS)':
 'IO173': CDS_PINID='IO173';
NODE_NAME     J8G1 176
 '@BASEBOARD_FAB2_LIB.BASEBOARD_FAB2(SCH_1):PAGE109_I78@MSTR_SCONN.SCONN200_H68296001(CHIPS)':
 'IO176': CDS_PINID='IO176';
NODE_NAME     J8G1 179
 '@BASEBOARD_FAB2_LIB.BASEBOARD_FAB2(SCH_1):PAGE109_I78@MSTR_SCONN.SCONN200_H68296001(CHIPS)':
 'IO179': CDS_PINID='IO179';
NODE_NAME     J8G1 182
 '@BASEBOARD_FAB2_LIB.BASEBOARD_FAB2(SCH_1):PAGE109_I78@MSTR_SCONN.SCONN200_H68296001(CHIPS)':
 'IO182': CDS_PINID='IO182';
NODE_NAME     J8G1 185
 '@BASEBOARD_FAB2_LIB.BASEBOARD_FAB2(SCH_1):PAGE109_I78@MSTR_SCONN.SCONN200_H68296001(CHIPS)':
 'IO185': CDS_PINID='IO185';
NODE_NAME     J8G1 188
 '@BASEBOARD_FAB2_LIB.BASEBOARD_FAB2(SCH_1):PAGE109_I78@MSTR_SCONN.SCONN200_H68296001(CHIPS)':
 'IO188': CDS_PINID='IO188';
NODE_NAME     J8G1 191
 '@BASEBOARD_FAB2_LIB.BASEBOARD_FAB2(SCH_1):PAGE109_I78@MSTR_SCONN.SCONN200_H68296001(CHIPS)':
 'IO191': CDS_PINID='IO191';
NODE_NAME     J8G1 194
 '@BASEBOARD_FAB2_LIB.BASEBOARD_FAB2(SCH_1):PAGE109_I78@MSTR_SCONN.SCONN200_H68296001(CHIPS)':
 'IO194': CDS_PINID='IO194';
NODE_NAME     J8G1 197
 '@BASEBOARD_FAB2_LIB.BASEBOARD_FAB2(SCH_1):PAGE109_I78@MSTR_SCONN.SCONN200_H68296001(CHIPS)':
 'IO197': CDS_PINID='IO197';
NODE_NAME     J8G1 200
 '@BASEBOARD_FAB2_LIB.BASEBOARD_FAB2(SCH_1):PAGE109_I78@MSTR_SCONN.SCONN200_H68296001(CHIPS)':
 'IO200': CDS_PINID='IO200';
NODE_NAME     UN8F2 10
 '@BASEBOARD_FAB2_LIB.BASEBOARD_FAB2(SCH_1):PAGE246_I17@MSTR_MEMORY.W25Q256(CHIPS)':
 'GND': CDS_PINID='GND';
NODE_NAME     Q6W1 2
 '@BASEBOARD_FAB2_LIB.BASEBOARD_FAB2(SCH_1):PAGE200_I225@MSTR_DISCRETE.FET_N(CHIPS)':
 'SRC': CDS_PINID='SRC';
NODE_NAME     R3W1 2
 '@BASEBOARD_FAB2_LIB.BASEBOARD_FAB2(SCH_1):PAGE249_I2@MSTR_DISCRETE.RES(CHIPS)':
 'B': CDS_PINID='B';
NODE_NAME     R3W9 2
 '@BASEBOARD_FAB2_LIB.BASEBOARD_FAB2(SCH_1):PAGE249_I7@MSTR_DISCRETE.RES(CHIPS)':
 'B': CDS_PINID='B';
NODE_NAME     Q9W4 2
 '@BASEBOARD_FAB2_LIB.BASEBOARD_FAB2(SCH_1):PAGE249_I15@W_HDL.LMV331IDCKRG4-GP(CHIPS)':
 'GND': CDS_PINID='GND';
NODE_NAME     Q9W2 2
 '@BASEBOARD_FAB2_LIB.BASEBOARD_FAB2(SCH_1):PAGE249_I29@MSTR_DISCRETE.NPN(CHIPS)':
 'E': CDS_PINID='E';
NODE_NAME     EU25F2 11
 '@BASEBOARD_FAB2_LIB.BASEBOARD_FAB2(SCH_1):PAGE239_I73@MSTR_VREG.RT9059(CHIPS)':
 'GND': CDS_PINID='GND';
NODE_NAME     C9W13 2
 '@BASEBOARD_FAB2_LIB.BASEBOARD_FAB2(SCH_1):PAGE239_I81@MSTR_DISCRETE.CAP(CHIPS)':
 'B': CDS_PINID='B';
NODE_NAME     C1W15 2
 '@BASEBOARD_FAB2_LIB.BASEBOARD_FAB2(SCH_1):PAGE239_I83@MSTR_DISCRETE.CAP(CHIPS)':
 'B': CDS_PINID='B';
NODE_NAME     C9W10 2
 '@BASEBOARD_FAB2_LIB.BASEBOARD_FAB2(SCH_1):PAGE239_I84@MSTR_DISCRETE.CAP(CHIPS)':
 'B': CDS_PINID='B';
NODE_NAME     C9W5 2
 '@BASEBOARD_FAB2_LIB.BASEBOARD_FAB2(SCH_1):PAGE239_I90@DEV_DISCRETE.CAP_A(CHIPS)':
 'B': CDS_PINID='B';
NODE_NAME     C9W6 2
 '@BASEBOARD_FAB2_LIB.BASEBOARD_FAB2(SCH_1):PAGE239_I91@MSTR_DISCRETE.CAP(CHIPS)':
 'B': CDS_PINID='B';
NODE_NAME     C1W7 2
 '@BASEBOARD_FAB2_LIB.BASEBOARD_FAB2(SCH_1):PAGE239_I92@MSTR_DISCRETE.CAP(CHIPS)':
 'B': CDS_PINID='B';
NODE_NAME     Q9W1 2
 '@BASEBOARD_FAB2_LIB.BASEBOARD_FAB2(SCH_1):PAGE249_I30@MSTR_DISCRETE.FET_N(CHIPS)':
 'SRC': CDS_PINID='SRC';
NODE_NAME     R1T27 1
 '@BASEBOARD_FAB2_LIB.BASEBOARD_FAB2(SCH_1):PAGE143_I58@MSTR_DISCRETE.RES(CHIPS)':
 'A': CDS_PINID='A';
NODE_NAME     Y9F2 2
 '@BASEBOARD_FAB2_LIB.BASEBOARD_FAB2(SCH_1):PAGE145_I8@MSTR_DISCRETE.OSC_C(CHIPS)':
 'GND': CDS_PINID='GND';
NODE_NAME     C9F23 2
 '@BASEBOARD_FAB2_LIB.BASEBOARD_FAB2(SCH_1):PAGE145_I15@DEV_DISCRETE.CAP_A(CHIPS)':
 'B': CDS_PINID='B';
NODE_NAME     R9F20 2
 '@BASEBOARD_FAB2_LIB.BASEBOARD_FAB2(SCH_1):PAGE145_I22@MSTR_DISCRETE.RES(CHIPS)':
 'B': CDS_PINID='B';
NODE_NAME     R25W61 2
 '@BASEBOARD_FAB2_LIB.BASEBOARD_FAB2(SCH_1):PAGE145_I30@MSTR_DISCRETE.RES(CHIPS)':
 'B': CDS_PINID='B';
NODE_NAME     R25W62 2
 '@BASEBOARD_FAB2_LIB.BASEBOARD_FAB2(SCH_1):PAGE145_I31@MSTR_DISCRETE.RES(CHIPS)':
 'B': CDS_PINID='B';
NODE_NAME     R25W60 2
 '@BASEBOARD_FAB2_LIB.BASEBOARD_FAB2(SCH_1):PAGE145_I34@MSTR_DISCRETE.RES(CHIPS)':
 'B': CDS_PINID='B';
NODE_NAME     R25W64 2
 '@BASEBOARD_FAB2_LIB.BASEBOARD_FAB2(SCH_1):PAGE145_I36@MSTR_DISCRETE.RES(CHIPS)':
 'B': CDS_PINID='B';
NODE_NAME     R25W65 2
 '@BASEBOARD_FAB2_LIB.BASEBOARD_FAB2(SCH_1):PAGE145_I38@MSTR_DISCRETE.RES(CHIPS)':
 'B': CDS_PINID='B';
NODE_NAME     R1T25 2
 '@BASEBOARD_FAB2_LIB.BASEBOARD_FAB2(SCH_1):PAGE146_I35@MSTR_DISCRETE.RES(CHIPS)':
 'B': CDS_PINID='B';
NODE_NAME     R1T26 2
 '@BASEBOARD_FAB2_LIB.BASEBOARD_FAB2(SCH_1):PAGE146_I37@MSTR_DISCRETE.RES(CHIPS)':
 'B': CDS_PINID='B';
NODE_NAME     R1U2 2
 '@BASEBOARD_FAB2_LIB.BASEBOARD_FAB2(SCH_1):PAGE147_I62@MSTR_DISCRETE.RES(CHIPS)':
 'B': CDS_PINID='B';
NODE_NAME     R25W63 2
 '@BASEBOARD_FAB2_LIB.BASEBOARD_FAB2(SCH_1):PAGE146_I65@MSTR_DISCRETE.RES(CHIPS)':
 'B': CDS_PINID='B';
NODE_NAME     R25W66 2
 '@BASEBOARD_FAB2_LIB.BASEBOARD_FAB2(SCH_1):PAGE146_I76@MSTR_DISCRETE.RES(CHIPS)':
 'B': CDS_PINID='B';
NODE_NAME     R1U7 1
 '@BASEBOARD_FAB2_LIB.BASEBOARD_FAB2(SCH_1):PAGE146_I78@MSTR_DISCRETE.RES(CHIPS)':
 'A': CDS_PINID='A';
NODE_NAME     R1U4 2
 '@BASEBOARD_FAB2_LIB.BASEBOARD_FAB2(SCH_1):PAGE147_I65@MSTR_DISCRETE.RES(CHIPS)':
 'B': CDS_PINID='B';
NODE_NAME     R1U5 2
 '@BASEBOARD_FAB2_LIB.BASEBOARD_FAB2(SCH_1):PAGE147_I66@MSTR_DISCRETE.RES(CHIPS)':
 'B': CDS_PINID='B';
NODE_NAME     R1U1 2
 '@BASEBOARD_FAB2_LIB.BASEBOARD_FAB2(SCH_1):PAGE147_I61@MSTR_DISCRETE.RES(CHIPS)':
 'B': CDS_PINID='B';
NODE_NAME     C1T21 2
 '@BASEBOARD_FAB2_LIB.BASEBOARD_FAB2(SCH_1):PAGE148_I20@DEV_DISCRETE.CAP_A(CHIPS)':
 'B': CDS_PINID='B';
NODE_NAME     R2N13 2
 '@BASEBOARD_FAB2_LIB.BASEBOARD_FAB2(SCH_1):PAGE147_I75@MSTR_DISCRETE.RES(CHIPS)':
 'B': CDS_PINID='B';
NODE_NAME     R1T23 2
 '@BASEBOARD_FAB2_LIB.BASEBOARD_FAB2(SCH_1):PAGE145_I101@MSTR_DISCRETE.RES(CHIPS)':
 'B': CDS_PINID='B';
NODE_NAME     C6W3 2
 '@BASEBOARD_FAB2_LIB.BASEBOARD_FAB2(SCH_1):PAGE247_I85@DEV_DISCRETE.CAP_A(CHIPS)':
 'B': CDS_PINID='B';
NODE_NAME     U6W3 2
 '@BASEBOARD_FAB2_LIB.BASEBOARD_FAB2(SCH_1):PAGE247_I89@MSTR_MEMORY.AT24C64(CHIPS)':
 'A1': CDS_PINID='A1';
NODE_NAME     U6W3 3
 '@BASEBOARD_FAB2_LIB.BASEBOARD_FAB2(SCH_1):PAGE247_I89@MSTR_MEMORY.AT24C64(CHIPS)':
 'A2': CDS_PINID='A2';
NODE_NAME     R6W23 2
 '@BASEBOARD_FAB2_LIB.BASEBOARD_FAB2(SCH_1):PAGE247_I92@MSTR_DISCRETE.RES(CHIPS)':
 'B': CDS_PINID='B';
NODE_NAME     U25W4 F2
 '@BASEBOARD_FAB2_LIB.BASEBOARD_FAB2(SCH_1):PAGE147_I106@W_HDL.AST2520A1-GP-GP(CHIPS)':
 'ADC8_GPIX0': CDS_PINID='ADC8_GPIX0';
NODE_NAME     U25W4 G3
 '@BASEBOARD_FAB2_LIB.BASEBOARD_FAB2(SCH_1):PAGE147_I106@W_HDL.AST2520A1-GP-GP(CHIPS)':
 'ADC9_GPIX1': CDS_PINID='ADC9_GPIX1';
NODE_NAME     U25W4 G2
 '@BASEBOARD_FAB2_LIB.BASEBOARD_FAB2(SCH_1):PAGE147_I106@W_HDL.AST2520A1-GP-GP(CHIPS)':
 'ADC10_GPIX2': CDS_PINID='ADC10_GPIX2';
NODE_NAME     U25W4 A1
 '@BASEBOARD_FAB2_LIB.BASEBOARD_FAB2(SCH_1):PAGE148_I28@W_HDL.AST2520A1-GP-GP(CHIPS)':
 'GND0': CDS_PINID='GND0';
NODE_NAME     U25W4 A22
 '@BASEBOARD_FAB2_LIB.BASEBOARD_FAB2(SCH_1):PAGE148_I28@W_HDL.AST2520A1-GP-GP(CHIPS)':
 'GND1': CDS_PINID='GND1';
NODE_NAME     U25W4 AA11
 '@BASEBOARD_FAB2_LIB.BASEBOARD_FAB2(SCH_1):PAGE148_I28@W_HDL.AST2520A1-GP-GP(CHIPS)':
 'GND2': CDS_PINID='GND2';
NODE_NAME     U25W4 AA13
 '@BASEBOARD_FAB2_LIB.BASEBOARD_FAB2(SCH_1):PAGE148_I28@W_HDL.AST2520A1-GP-GP(CHIPS)':
 'GND3': CDS_PINID='GND3';
NODE_NAME     U25W4 AA15
 '@BASEBOARD_FAB2_LIB.BASEBOARD_FAB2(SCH_1):PAGE148_I28@W_HDL.AST2520A1-GP-GP(CHIPS)':
 'GND4': CDS_PINID='GND4';
NODE_NAME     U25W4 AA7
 '@BASEBOARD_FAB2_LIB.BASEBOARD_FAB2(SCH_1):PAGE148_I28@W_HDL.AST2520A1-GP-GP(CHIPS)':
 'GND5': CDS_PINID='GND5';
NODE_NAME     U25W4 AA9
 '@BASEBOARD_FAB2_LIB.BASEBOARD_FAB2(SCH_1):PAGE148_I28@W_HDL.AST2520A1-GP-GP(CHIPS)':
 'GND6': CDS_PINID='GND6';
NODE_NAME     U25W4 AB1
 '@BASEBOARD_FAB2_LIB.BASEBOARD_FAB2(SCH_1):PAGE148_I28@W_HDL.AST2520A1-GP-GP(CHIPS)':
 'GND7': CDS_PINID='GND7';
NODE_NAME     U25W4 AB22
 '@BASEBOARD_FAB2_LIB.BASEBOARD_FAB2(SCH_1):PAGE148_I28@W_HDL.AST2520A1-GP-GP(CHIPS)':
 'GND8': CDS_PINID='GND8';
NODE_NAME     U25W4 C6
 '@BASEBOARD_FAB2_LIB.BASEBOARD_FAB2(SCH_1):PAGE148_I28@W_HDL.AST2520A1-GP-GP(CHIPS)':
 'GND9': CDS_PINID='GND9';
NODE_NAME     U25W4 E8
 '@BASEBOARD_FAB2_LIB.BASEBOARD_FAB2(SCH_1):PAGE148_I28@W_HDL.AST2520A1-GP-GP(CHIPS)':
 'GND10': CDS_PINID='GND10';
NODE_NAME     U25W4 F16
 '@BASEBOARD_FAB2_LIB.BASEBOARD_FAB2(SCH_1):PAGE148_I28@W_HDL.AST2520A1-GP-GP(CHIPS)':
 'GND11': CDS_PINID='GND11';
NODE_NAME     U25W4 G19
 '@BASEBOARD_FAB2_LIB.BASEBOARD_FAB2(SCH_1):PAGE148_I28@W_HDL.AST2520A1-GP-GP(CHIPS)':
 'GND12': CDS_PINID='GND12';
NODE_NAME     U25W4 G6
 '@BASEBOARD_FAB2_LIB.BASEBOARD_FAB2(SCH_1):PAGE148_I28@W_HDL.AST2520A1-GP-GP(CHIPS)':
 'GND13': CDS_PINID='GND13';
NODE_NAME     U25W4 H6
 '@BASEBOARD_FAB2_LIB.BASEBOARD_FAB2(SCH_1):PAGE148_I28@W_HDL.AST2520A1-GP-GP(CHIPS)':
 'GND14': CDS_PINID='GND14';
NODE_NAME     U25W4 J10
 '@BASEBOARD_FAB2_LIB.BASEBOARD_FAB2(SCH_1):PAGE148_I28@W_HDL.AST2520A1-GP-GP(CHIPS)':
 'GND15': CDS_PINID='GND15';
NODE_NAME     U25W4 J11
 '@BASEBOARD_FAB2_LIB.BASEBOARD_FAB2(SCH_1):PAGE148_I28@W_HDL.AST2520A1-GP-GP(CHIPS)':
 'GND16': CDS_PINID='GND16';
NODE_NAME     U25W4 J12
 '@BASEBOARD_FAB2_LIB.BASEBOARD_FAB2(SCH_1):PAGE148_I28@W_HDL.AST2520A1-GP-GP(CHIPS)':
 'GND17': CDS_PINID='GND17';
NODE_NAME     U25W4 J13
 '@BASEBOARD_FAB2_LIB.BASEBOARD_FAB2(SCH_1):PAGE148_I28@W_HDL.AST2520A1-GP-GP(CHIPS)':
 'GND18': CDS_PINID='GND18';
NODE_NAME     U25W4 J14
 '@BASEBOARD_FAB2_LIB.BASEBOARD_FAB2(SCH_1):PAGE148_I28@W_HDL.AST2520A1-GP-GP(CHIPS)':
 'GND19': CDS_PINID='GND19';
NODE_NAME     U25W4 J21
 '@BASEBOARD_FAB2_LIB.BASEBOARD_FAB2(SCH_1):PAGE148_I28@W_HDL.AST2520A1-GP-GP(CHIPS)':
 'GND20': CDS_PINID='GND20';
NODE_NAME     U25W4 J22
 '@BASEBOARD_FAB2_LIB.BASEBOARD_FAB2(SCH_1):PAGE148_I28@W_HDL.AST2520A1-GP-GP(CHIPS)':
 'GND21': CDS_PINID='GND21';
NODE_NAME     U25W4 J5
 '@BASEBOARD_FAB2_LIB.BASEBOARD_FAB2(SCH_1):PAGE148_I28@W_HDL.AST2520A1-GP-GP(CHIPS)':
 'GND22': CDS_PINID='GND22';
NODE_NAME     U25W4 J9
 '@BASEBOARD_FAB2_LIB.BASEBOARD_FAB2(SCH_1):PAGE148_I28@W_HDL.AST2520A1-GP-GP(CHIPS)':
 'GND23': CDS_PINID='GND23';
NODE_NAME     U25W4 K10
 '@BASEBOARD_FAB2_LIB.BASEBOARD_FAB2(SCH_1):PAGE148_I28@W_HDL.AST2520A1-GP-GP(CHIPS)':
 'GND24': CDS_PINID='GND24';
NODE_NAME     U25W4 K11
 '@BASEBOARD_FAB2_LIB.BASEBOARD_FAB2(SCH_1):PAGE148_I28@W_HDL.AST2520A1-GP-GP(CHIPS)':
 'GND25': CDS_PINID='GND25';
NODE_NAME     U25W4 K12
 '@BASEBOARD_FAB2_LIB.BASEBOARD_FAB2(SCH_1):PAGE148_I28@W_HDL.AST2520A1-GP-GP(CHIPS)':
 'GND26': CDS_PINID='GND26';
NODE_NAME     U25W4 K13
 '@BASEBOARD_FAB2_LIB.BASEBOARD_FAB2(SCH_1):PAGE148_I28@W_HDL.AST2520A1-GP-GP(CHIPS)':
 'GND27': CDS_PINID='GND27';
NODE_NAME     U25W4 K14
 '@BASEBOARD_FAB2_LIB.BASEBOARD_FAB2(SCH_1):PAGE148_I28@W_HDL.AST2520A1-GP-GP(CHIPS)':
 'GND28': CDS_PINID='GND28';
NODE_NAME     U25W4 K16
 '@BASEBOARD_FAB2_LIB.BASEBOARD_FAB2(SCH_1):PAGE148_I28@W_HDL.AST2520A1-GP-GP(CHIPS)':
 'GND29': CDS_PINID='GND29';
NODE_NAME     U25W4 K9
 '@BASEBOARD_FAB2_LIB.BASEBOARD_FAB2(SCH_1):PAGE148_I28@W_HDL.AST2520A1-GP-GP(CHIPS)':
 'GND30': CDS_PINID='GND30';
NODE_NAME     U25W4 L10
 '@BASEBOARD_FAB2_LIB.BASEBOARD_FAB2(SCH_1):PAGE148_I28@W_HDL.AST2520A1-GP-GP(CHIPS)':
 'GND31': CDS_PINID='GND31';
NODE_NAME     U25W4 L11
 '@BASEBOARD_FAB2_LIB.BASEBOARD_FAB2(SCH_1):PAGE148_I28@W_HDL.AST2520A1-GP-GP(CHIPS)':
 'GND32': CDS_PINID='GND32';
NODE_NAME     U25W4 L12
 '@BASEBOARD_FAB2_LIB.BASEBOARD_FAB2(SCH_1):PAGE148_I28@W_HDL.AST2520A1-GP-GP(CHIPS)':
 'GND33': CDS_PINID='GND33';
NODE_NAME     U25W4 L13
 '@BASEBOARD_FAB2_LIB.BASEBOARD_FAB2(SCH_1):PAGE148_I28@W_HDL.AST2520A1-GP-GP(CHIPS)':
 'GND34': CDS_PINID='GND34';
NODE_NAME     U25W4 L14
 '@BASEBOARD_FAB2_LIB.BASEBOARD_FAB2(SCH_1):PAGE148_I28@W_HDL.AST2520A1-GP-GP(CHIPS)':
 'GND35': CDS_PINID='GND35';
NODE_NAME     U25W4 L9
 '@BASEBOARD_FAB2_LIB.BASEBOARD_FAB2(SCH_1):PAGE148_I28@W_HDL.AST2520A1-GP-GP(CHIPS)':
 'GND36': CDS_PINID='GND36';
NODE_NAME     U25W4 M1
 '@BASEBOARD_FAB2_LIB.BASEBOARD_FAB2(SCH_1):PAGE148_I28@W_HDL.AST2520A1-GP-GP(CHIPS)':
 'GND37': CDS_PINID='GND37';
NODE_NAME     U25W4 M10
 '@BASEBOARD_FAB2_LIB.BASEBOARD_FAB2(SCH_1):PAGE148_I28@W_HDL.AST2520A1-GP-GP(CHIPS)':
 'GND38': CDS_PINID='GND38';
NODE_NAME     U25W4 M11
 '@BASEBOARD_FAB2_LIB.BASEBOARD_FAB2(SCH_1):PAGE148_I28@W_HDL.AST2520A1-GP-GP(CHIPS)':
 'GND39': CDS_PINID='GND39';
NODE_NAME     U25W4 M12
 '@BASEBOARD_FAB2_LIB.BASEBOARD_FAB2(SCH_1):PAGE148_I28@W_HDL.AST2520A1-GP-GP(CHIPS)':
 'GND40': CDS_PINID='GND40';
NODE_NAME     U25W4 M13
 '@BASEBOARD_FAB2_LIB.BASEBOARD_FAB2(SCH_1):PAGE148_I28@W_HDL.AST2520A1-GP-GP(CHIPS)':
 'GND41': CDS_PINID='GND41';
NODE_NAME     U25W4 M14
 '@BASEBOARD_FAB2_LIB.BASEBOARD_FAB2(SCH_1):PAGE148_I28@W_HDL.AST2520A1-GP-GP(CHIPS)':
 'GND42': CDS_PINID='GND42';
NODE_NAME     U25W4 M16
 '@BASEBOARD_FAB2_LIB.BASEBOARD_FAB2(SCH_1):PAGE148_I28@W_HDL.AST2520A1-GP-GP(CHIPS)':
 'GND43': CDS_PINID='GND43';
NODE_NAME     U25W4 M17
 '@BASEBOARD_FAB2_LIB.BASEBOARD_FAB2(SCH_1):PAGE148_I28@W_HDL.AST2520A1-GP-GP(CHIPS)':
 'GND44': CDS_PINID='GND44';
NODE_NAME     U25W4 M2
 '@BASEBOARD_FAB2_LIB.BASEBOARD_FAB2(SCH_1):PAGE148_I28@W_HDL.AST2520A1-GP-GP(CHIPS)':
 'GND45': CDS_PINID='GND45';
NODE_NAME     U25W4 M3
 '@BASEBOARD_FAB2_LIB.BASEBOARD_FAB2(SCH_1):PAGE148_I28@W_HDL.AST2520A1-GP-GP(CHIPS)':
 'GND46': CDS_PINID='GND46';
NODE_NAME     U25W4 M4
 '@BASEBOARD_FAB2_LIB.BASEBOARD_FAB2(SCH_1):PAGE148_I28@W_HDL.AST2520A1-GP-GP(CHIPS)':
 'GND47': CDS_PINID='GND47';
NODE_NAME     U25W4 M5
 '@BASEBOARD_FAB2_LIB.BASEBOARD_FAB2(SCH_1):PAGE148_I28@W_HDL.AST2520A1-GP-GP(CHIPS)':
 'GND48': CDS_PINID='GND48';
NODE_NAME     U25W4 M6
 '@BASEBOARD_FAB2_LIB.BASEBOARD_FAB2(SCH_1):PAGE148_I28@W_HDL.AST2520A1-GP-GP(CHIPS)':
 'GND49': CDS_PINID='GND49';
NODE_NAME     U25W4 M7
 '@BASEBOARD_FAB2_LIB.BASEBOARD_FAB2(SCH_1):PAGE148_I28@W_HDL.AST2520A1-GP-GP(CHIPS)':
 'GND50': CDS_PINID='GND50';
NODE_NAME     U25W4 M9
 '@BASEBOARD_FAB2_LIB.BASEBOARD_FAB2(SCH_1):PAGE148_I28@W_HDL.AST2520A1-GP-GP(CHIPS)':
 'GND51': CDS_PINID='GND51';
NODE_NAME     U25W4 N10
 '@BASEBOARD_FAB2_LIB.BASEBOARD_FAB2(SCH_1):PAGE148_I28@W_HDL.AST2520A1-GP-GP(CHIPS)':
 'GND52': CDS_PINID='GND52';
NODE_NAME     U25W4 N11
 '@BASEBOARD_FAB2_LIB.BASEBOARD_FAB2(SCH_1):PAGE148_I28@W_HDL.AST2520A1-GP-GP(CHIPS)':
 'GND53': CDS_PINID='GND53';
NODE_NAME     U25W4 N12
 '@BASEBOARD_FAB2_LIB.BASEBOARD_FAB2(SCH_1):PAGE148_I28@W_HDL.AST2520A1-GP-GP(CHIPS)':
 'GND54': CDS_PINID='GND54';
NODE_NAME     U25W4 N13
 '@BASEBOARD_FAB2_LIB.BASEBOARD_FAB2(SCH_1):PAGE148_I28@W_HDL.AST2520A1-GP-GP(CHIPS)':
 'GND55': CDS_PINID='GND55';
NODE_NAME     U25W4 N14
 '@BASEBOARD_FAB2_LIB.BASEBOARD_FAB2(SCH_1):PAGE148_I28@W_HDL.AST2520A1-GP-GP(CHIPS)':
 'GND56': CDS_PINID='GND56';
NODE_NAME     U25W4 N9
 '@BASEBOARD_FAB2_LIB.BASEBOARD_FAB2(SCH_1):PAGE148_I28@W_HDL.AST2520A1-GP-GP(CHIPS)':
 'GND57': CDS_PINID='GND57';
NODE_NAME     U25W4 T16
 '@BASEBOARD_FAB2_LIB.BASEBOARD_FAB2(SCH_1):PAGE148_I28@W_HDL.AST2520A1-GP-GP(CHIPS)':
 'GND58': CDS_PINID='GND58';
NODE_NAME     U25W4 T6
 '@BASEBOARD_FAB2_LIB.BASEBOARD_FAB2(SCH_1):PAGE148_I28@W_HDL.AST2520A1-GP-GP(CHIPS)':
 'GND59': CDS_PINID='GND59';
NODE_NAME     U25W4 T7
 '@BASEBOARD_FAB2_LIB.BASEBOARD_FAB2(SCH_1):PAGE148_I28@W_HDL.AST2520A1-GP-GP(CHIPS)':
 'GND60': CDS_PINID='GND60';
NODE_NAME     U25W4 U11
 '@BASEBOARD_FAB2_LIB.BASEBOARD_FAB2(SCH_1):PAGE148_I28@W_HDL.AST2520A1-GP-GP(CHIPS)':
 'GND61': CDS_PINID='GND61';
NODE_NAME     U25W4 U6
 '@BASEBOARD_FAB2_LIB.BASEBOARD_FAB2(SCH_1):PAGE148_I28@W_HDL.AST2520A1-GP-GP(CHIPS)':
 'GND62': CDS_PINID='GND62';
NODE_NAME     U25W4 V10
 '@BASEBOARD_FAB2_LIB.BASEBOARD_FAB2(SCH_1):PAGE148_I28@W_HDL.AST2520A1-GP-GP(CHIPS)':
 'GND63': CDS_PINID='GND63';
NODE_NAME     U25W4 V12
 '@BASEBOARD_FAB2_LIB.BASEBOARD_FAB2(SCH_1):PAGE148_I28@W_HDL.AST2520A1-GP-GP(CHIPS)':
 'GND64': CDS_PINID='GND64';
NODE_NAME     U25W4 V14
 '@BASEBOARD_FAB2_LIB.BASEBOARD_FAB2(SCH_1):PAGE148_I28@W_HDL.AST2520A1-GP-GP(CHIPS)':
 'GND65': CDS_PINID='GND65';
NODE_NAME     U25W4 V16
 '@BASEBOARD_FAB2_LIB.BASEBOARD_FAB2(SCH_1):PAGE148_I28@W_HDL.AST2520A1-GP-GP(CHIPS)':
 'GND66': CDS_PINID='GND66';
NODE_NAME     U25W4 V8
 '@BASEBOARD_FAB2_LIB.BASEBOARD_FAB2(SCH_1):PAGE148_I28@W_HDL.AST2520A1-GP-GP(CHIPS)':
 'GND67': CDS_PINID='GND67';
NODE_NAME     U25W4 E5
 '@BASEBOARD_FAB2_LIB.BASEBOARD_FAB2(SCH_1):PAGE148_I28@W_HDL.AST2520A1-GP-GP(CHIPS)':
 'GND68': CDS_PINID='GND68';
NODE_NAME     R25W67 2
 '@BASEBOARD_FAB2_LIB.BASEBOARD_FAB2(SCH_1):PAGE145_I118@W_HDL.200R2F-L1-GP(CHIPS)':
 '2': CDS_PINID='\2\';
NODE_NAME     U3T1 10
 '@BASEBOARD_FAB2_LIB.BASEBOARD_FAB2(SCH_1):PAGE153_I185@W_HDL.W25Q256FVFIG-GP(CHIPS)':
 'GND': CDS_PINID='GND';
NODE_NAME     C14W1 2
 '@BASEBOARD_FAB2_LIB.BASEBOARD_FAB2(SCH_1):PAGE248_I13@DEV_DISCRETE.CAP_A(CHIPS)':
 'B': CDS_PINID='B';
NODE_NAME     C14W2 2
 '@BASEBOARD_FAB2_LIB.BASEBOARD_FAB2(SCH_1):PAGE248_I17@DEV_DISCRETE.CAP_A(CHIPS)':
 'B': CDS_PINID='B';
NODE_NAME     S9A2 1
 '@BASEBOARD_FAB2_LIB.BASEBOARD_FAB2(SCH_1):PAGE175_I92@MSTR_MISC.SWITCH_D37771002(CHIPS)':
 'PIN1': CDS_PINID='PIN1';
NODE_NAME     S9A2 2
 '@BASEBOARD_FAB2_LIB.BASEBOARD_FAB2(SCH_1):PAGE175_I92@MSTR_MISC.SWITCH_D37771002(CHIPS)':
 'PIN2': CDS_PINID='PIN2';
NODE_NAME     C25W70 2
 '@BASEBOARD_FAB2_LIB.BASEBOARD_FAB2(SCH_1):PAGE149_I5@MSTR_DISCRETE.CAP(CHIPS)':
 'B': CDS_PINID='B';
NODE_NAME     C25W69 2
 '@BASEBOARD_FAB2_LIB.BASEBOARD_FAB2(SCH_1):PAGE149_I17@MSTR_DISCRETE.CAP(CHIPS)':
 'B': CDS_PINID='B';
NODE_NAME     C25W39 2
 '@BASEBOARD_FAB2_LIB.BASEBOARD_FAB2(SCH_1):PAGE149_I25@MSTR_DISCRETE.CAP(CHIPS)':
 'B': CDS_PINID='B';
NODE_NAME     C25W50 2
 '@BASEBOARD_FAB2_LIB.BASEBOARD_FAB2(SCH_1):PAGE149_I31@MSTR_DISCRETE.CAP(CHIPS)':
 'B': CDS_PINID='B';
NODE_NAME     C25W62 2
 '@BASEBOARD_FAB2_LIB.BASEBOARD_FAB2(SCH_1):PAGE149_I40@MSTR_DISCRETE.CAP(CHIPS)':
 'B': CDS_PINID='B';
NODE_NAME     C25W36 2
 '@BASEBOARD_FAB2_LIB.BASEBOARD_FAB2(SCH_1):PAGE149_I46@MSTR_DISCRETE.CAP(CHIPS)':
 'B': CDS_PINID='B';
NODE_NAME     C25W47 2
 '@BASEBOARD_FAB2_LIB.BASEBOARD_FAB2(SCH_1):PAGE149_I50@MSTR_DISCRETE.CAP(CHIPS)':
 'B': CDS_PINID='B';
NODE_NAME     C25W46 2
 '@BASEBOARD_FAB2_LIB.BASEBOARD_FAB2(SCH_1):PAGE149_I51@MSTR_DISCRETE.CAP(CHIPS)':
 'B': CDS_PINID='B';
NODE_NAME     C25W59 2
 '@BASEBOARD_FAB2_LIB.BASEBOARD_FAB2(SCH_1):PAGE149_I79@MSTR_DISCRETE.CAP(CHIPS)':
 'B': CDS_PINID='B';
NODE_NAME     C25W30 2
 '@BASEBOARD_FAB2_LIB.BASEBOARD_FAB2(SCH_1):PAGE149_I1@MSTR_DISCRETE.CAP(CHIPS)':
 'B': CDS_PINID='B';
NODE_NAME     U25W5 N9
 '@BASEBOARD_FAB2_LIB.BASEBOARD_FAB2(SCH_1):PAGE151_I49@W_HDL.H5AN4G6NAFR-TFC-GP(CHIPS)':
 'TEN': CDS_PINID='TEN';
NODE_NAME     U25W5 B2
 '@BASEBOARD_FAB2_LIB.BASEBOARD_FAB2(SCH_1):PAGE151_I49@W_HDL.H5AN4G6NAFR-TFC-GP(CHIPS)':
 'VSS'<0>: CDS_PINID='VSS(0)';
NODE_NAME     U25W5 E1
 '@BASEBOARD_FAB2_LIB.BASEBOARD_FAB2(SCH_1):PAGE151_I49@W_HDL.H5AN4G6NAFR-TFC-GP(CHIPS)':
 'VSS'<1>: CDS_PINID='VSS(1)';
NODE_NAME     U25W5 E9
 '@BASEBOARD_FAB2_LIB.BASEBOARD_FAB2(SCH_1):PAGE151_I49@W_HDL.H5AN4G6NAFR-TFC-GP(CHIPS)':
 'VSS'<2>: CDS_PINID='VSS(2)';
NODE_NAME     U25W5 G8
 '@BASEBOARD_FAB2_LIB.BASEBOARD_FAB2(SCH_1):PAGE151_I49@W_HDL.H5AN4G6NAFR-TFC-GP(CHIPS)':
 'VSS'<3>: CDS_PINID='VSS(3)';
NODE_NAME     U25W5 K1
 '@BASEBOARD_FAB2_LIB.BASEBOARD_FAB2(SCH_1):PAGE151_I49@W_HDL.H5AN4G6NAFR-TFC-GP(CHIPS)':
 'VSS'<4>: CDS_PINID='VSS(4)';
NODE_NAME     U25W5 K9
 '@BASEBOARD_FAB2_LIB.BASEBOARD_FAB2(SCH_1):PAGE151_I49@W_HDL.H5AN4G6NAFR-TFC-GP(CHIPS)':
 'VSS'<5>: CDS_PINID='VSS(5)';
NODE_NAME     U25W5 M9
 '@BASEBOARD_FAB2_LIB.BASEBOARD_FAB2(SCH_1):PAGE151_I49@W_HDL.H5AN4G6NAFR-TFC-GP(CHIPS)':
 'VSS'<6>: CDS_PINID='VSS(6)';
NODE_NAME     U25W5 N1
 '@BASEBOARD_FAB2_LIB.BASEBOARD_FAB2(SCH_1):PAGE151_I49@W_HDL.H5AN4G6NAFR-TFC-GP(CHIPS)':
 'VSS'<7>: CDS_PINID='VSS(7)';
NODE_NAME     U25W5 T1
 '@BASEBOARD_FAB2_LIB.BASEBOARD_FAB2(SCH_1):PAGE151_I49@W_HDL.H5AN4G6NAFR-TFC-GP(CHIPS)':
 'VSS'<8>: CDS_PINID='VSS(8)';
NODE_NAME     U25W5 A2
 '@BASEBOARD_FAB2_LIB.BASEBOARD_FAB2(SCH_1):PAGE151_I49@W_HDL.H5AN4G6NAFR-TFC-GP(CHIPS)':
 'VSSQ'<0>: CDS_PINID='VSSQ(0)';
NODE_NAME     U25W5 A8
 '@BASEBOARD_FAB2_LIB.BASEBOARD_FAB2(SCH_1):PAGE151_I49@W_HDL.H5AN4G6NAFR-TFC-GP(CHIPS)':
 'VSSQ'<1>: CDS_PINID='VSSQ(1)';
NODE_NAME     U25W5 C9
 '@BASEBOARD_FAB2_LIB.BASEBOARD_FAB2(SCH_1):PAGE151_I49@W_HDL.H5AN4G6NAFR-TFC-GP(CHIPS)':
 'VSSQ'<2>: CDS_PINID='VSSQ(2)';
NODE_NAME     U25W5 D2
 '@BASEBOARD_FAB2_LIB.BASEBOARD_FAB2(SCH_1):PAGE151_I49@W_HDL.H5AN4G6NAFR-TFC-GP(CHIPS)':
 'VSSQ'<3>: CDS_PINID='VSSQ(3)';
NODE_NAME     U25W5 D8
 '@BASEBOARD_FAB2_LIB.BASEBOARD_FAB2(SCH_1):PAGE151_I49@W_HDL.H5AN4G6NAFR-TFC-GP(CHIPS)':
 'VSSQ'<4>: CDS_PINID='VSSQ(4)';
NODE_NAME     U25W5 E3
 '@BASEBOARD_FAB2_LIB.BASEBOARD_FAB2(SCH_1):PAGE151_I49@W_HDL.H5AN4G6NAFR-TFC-GP(CHIPS)':
 'VSSQ'<5>: CDS_PINID='VSSQ(5)';
NODE_NAME     U25W5 E8
 '@BASEBOARD_FAB2_LIB.BASEBOARD_FAB2(SCH_1):PAGE151_I49@W_HDL.H5AN4G6NAFR-TFC-GP(CHIPS)':
 'VSSQ'<6>: CDS_PINID='VSSQ(6)';
NODE_NAME     U25W5 F1
 '@BASEBOARD_FAB2_LIB.BASEBOARD_FAB2(SCH_1):PAGE151_I49@W_HDL.H5AN4G6NAFR-TFC-GP(CHIPS)':
 'VSSQ'<7>: CDS_PINID='VSSQ(7)';
NODE_NAME     U25W5 H1
 '@BASEBOARD_FAB2_LIB.BASEBOARD_FAB2(SCH_1):PAGE151_I49@W_HDL.H5AN4G6NAFR-TFC-GP(CHIPS)':
 'VSSQ'<8>: CDS_PINID='VSSQ(8)';
NODE_NAME     U25W5 H9
 '@BASEBOARD_FAB2_LIB.BASEBOARD_FAB2(SCH_1):PAGE151_I49@W_HDL.H5AN4G6NAFR-TFC-GP(CHIPS)':
 'VSSQ'<9>: CDS_PINID='VSSQ(9)';
NODE_NAME     C25W16 2
 '@BASEBOARD_FAB2_LIB.BASEBOARD_FAB2(SCH_1):PAGE151_I58@MSTR_DISCRETE.CAP(CHIPS)':
 'B': CDS_PINID='B';
NODE_NAME     R25W117 2
 '@BASEBOARD_FAB2_LIB.BASEBOARD_FAB2(SCH_1):PAGE151_I101@MSTR_DISCRETE.RES(CHIPS)':
 'B': CDS_PINID='B';
NODE_NAME     C25W17 2
 '@BASEBOARD_FAB2_LIB.BASEBOARD_FAB2(SCH_1):PAGE151_I120@W_HDL.SC1U16V3KX-2GP(CHIPS)':
 '2': CDS_PINID='\2\';
NODE_NAME     C25W18 2
 '@BASEBOARD_FAB2_LIB.BASEBOARD_FAB2(SCH_1):PAGE151_I121@W_HDL.SC1U16V3KX-2GP(CHIPS)':
 '2': CDS_PINID='\2\';
NODE_NAME     C25W19 2
 '@BASEBOARD_FAB2_LIB.BASEBOARD_FAB2(SCH_1):PAGE151_I123@MSTR_DISCRETE.CAP(CHIPS)':
 'B': CDS_PINID='B';
NODE_NAME     C25W1 2
 '@BASEBOARD_FAB2_LIB.BASEBOARD_FAB2(SCH_1):PAGE151_I125@MSTR_DISCRETE.CAP(CHIPS)':
 'B': CDS_PINID='B';
NODE_NAME     C25W2 2
 '@BASEBOARD_FAB2_LIB.BASEBOARD_FAB2(SCH_1):PAGE151_I139@MSTR_DISCRETE.CAP(CHIPS)':
 'B': CDS_PINID='B';
NODE_NAME     C25W3 2
 '@BASEBOARD_FAB2_LIB.BASEBOARD_FAB2(SCH_1):PAGE151_I140@MSTR_DISCRETE.CAP(CHIPS)':
 'B': CDS_PINID='B';
NODE_NAME     C25W4 2
 '@BASEBOARD_FAB2_LIB.BASEBOARD_FAB2(SCH_1):PAGE151_I141@MSTR_DISCRETE.CAP(CHIPS)':
 'B': CDS_PINID='B';
NODE_NAME     C25W5 2
 '@BASEBOARD_FAB2_LIB.BASEBOARD_FAB2(SCH_1):PAGE151_I142@MSTR_DISCRETE.CAP(CHIPS)':
 'B': CDS_PINID='B';
NODE_NAME     C25W6 2
 '@BASEBOARD_FAB2_LIB.BASEBOARD_FAB2(SCH_1):PAGE151_I143@MSTR_DISCRETE.CAP(CHIPS)':
 'B': CDS_PINID='B';
NODE_NAME     Q9E1 4
 '@BASEBOARD_FAB2_LIB.BASEBOARD_FAB2(SCH_1):PAGE151_I145@MSTR_DISCRETE.FET_N_DUAL(CHIPS)':
 'SOURCE'<0>: CDS_PINID='SOURCE(0)';
NODE_NAME     Q9E1 1
 '@BASEBOARD_FAB2_LIB.BASEBOARD_FAB2(SCH_1):PAGE151_I198@MSTR_DISCRETE.FET_N_DUAL(CHIPS)':
 'SOURCE'<0>: CDS_PINID='SOURCE(0)';
NODE_NAME     R1T29 2
 '@BASEBOARD_FAB2_LIB.BASEBOARD_FAB2(SCH_1):PAGE151_I202@MSTR_DISCRETE.RES(CHIPS)':
 'B': CDS_PINID='B';
NODE_NAME     C6W4 2
 '@BASEBOARD_FAB2_LIB.BASEBOARD_FAB2(SCH_1):PAGE247_I105@DEV_DISCRETE.CAP_A(CHIPS)':
 'B': CDS_PINID='B';
NODE_NAME     C6W2 2
 '@BASEBOARD_FAB2_LIB.BASEBOARD_FAB2(SCH_1):PAGE247_I107@DEV_DISCRETE.CAP_A(CHIPS)':
 'B': CDS_PINID='B';
NODE_NAME     C9W8 2
 '@BASEBOARD_FAB2_LIB.BASEBOARD_FAB2(SCH_1):PAGE248_I30@DEV_DISCRETE.CAP_A(CHIPS)':
 'B': CDS_PINID='B';
NODE_NAME     C9W7 2
 '@BASEBOARD_FAB2_LIB.BASEBOARD_FAB2(SCH_1):PAGE248_I32@DEV_DISCRETE.CAP_A(CHIPS)':
 'B': CDS_PINID='B';
NODE_NAME     R1U16 2
 '@BASEBOARD_FAB2_LIB.BASEBOARD_FAB2(SCH_1):PAGE164_I37@MSTR_DISCRETE.RES(CHIPS)':
 'B': CDS_PINID='B';
NODE_NAME     RN8F6 2
 '@BASEBOARD_FAB2_LIB.BASEBOARD_FAB2(SCH_1):PAGE246_I19@W_HDL.82KR2F-1-GP(CHIPS)':
 '2': CDS_PINID='\2\';
NODE_NAME     Q1P2 2
 '@BASEBOARD_FAB2_LIB.BASEBOARD_FAB2(SCH_1):PAGE196_I129@MSTR_DISCRETE.FET_N(CHIPS)':
 'SRC': CDS_PINID='SRC';
NODE_NAME     Q7D1 2
 '@BASEBOARD_FAB2_LIB.BASEBOARD_FAB2(SCH_1):PAGE134_I14@MSTR_DISCRETE.FET_N(CHIPS)':
 'SRC': CDS_PINID='SRC';
NODE_NAME     Q7E4 2
 '@BASEBOARD_FAB2_LIB.BASEBOARD_FAB2(SCH_1):PAGE95_I122@MSTR_DISCRETE.FET_N(CHIPS)':
 'SRC': CDS_PINID='SRC';
NODE_NAME     Q7E8 2
 '@BASEBOARD_FAB2_LIB.BASEBOARD_FAB2(SCH_1):PAGE95_I123@MSTR_DISCRETE.FET_N(CHIPS)':
 'SRC': CDS_PINID='SRC';
NODE_NAME     Q1W4 1
 '@BASEBOARD_FAB2_LIB.BASEBOARD_FAB2(SCH_1):PAGE250_I3@MSTR_DISCRETE.FET_N_DUAL(CHIPS)':
 'SOURCE'<0>: CDS_PINID='SOURCE(0)';
NODE_NAME     Q1W4 4
 '@BASEBOARD_FAB2_LIB.BASEBOARD_FAB2(SCH_1):PAGE250_I8@MSTR_DISCRETE.FET_N_DUAL(CHIPS)':
 'SOURCE'<0>: CDS_PINID='SOURCE(0)';
NODE_NAME     R1U28 2
 '@BASEBOARD_FAB2_LIB.BASEBOARD_FAB2(SCH_1):PAGE169_I169@W_HDL.1K82R2F-1-GP(CHIPS)':
 '2': CDS_PINID='\2\';
NODE_NAME     R1U44 2
 '@BASEBOARD_FAB2_LIB.BASEBOARD_FAB2(SCH_1):PAGE169_I170@W_HDL.1K82R2F-1-GP(CHIPS)':
 '2': CDS_PINID='\2\';
NODE_NAME     R1U33 2
 '@BASEBOARD_FAB2_LIB.BASEBOARD_FAB2(SCH_1):PAGE169_I171@W_HDL.649R2F-GP(CHIPS)':
 '2': CDS_PINID='\2\';
NODE_NAME     R1U38 2
 '@BASEBOARD_FAB2_LIB.BASEBOARD_FAB2(SCH_1):PAGE169_I172@MSTR_DISCRETE.RES(CHIPS)':
 'B': CDS_PINID='B';
NODE_NAME     R1U27 2
 '@BASEBOARD_FAB2_LIB.BASEBOARD_FAB2(SCH_1):PAGE169_I173@MSTR_DISCRETE.RES(CHIPS)':
 'B': CDS_PINID='B';
NODE_NAME     C5G77 2
 '@BASEBOARD_FAB2_LIB.BASEBOARD_FAB2(SCH_1):PAGE242_I89@MSTR_DISCRETE.CAP(CHIPS)':
 'B': CDS_PINID='B';
NODE_NAME     C5G22 2
 '@BASEBOARD_FAB2_LIB.BASEBOARD_FAB2(SCH_1):PAGE242_I90@MSTR_DISCRETE.CAP(CHIPS)':
 'B': CDS_PINID='B';
NODE_NAME     C5G78 2
 '@BASEBOARD_FAB2_LIB.BASEBOARD_FAB2(SCH_1):PAGE242_I91@MSTR_DISCRETE.CAP(CHIPS)':
 'B': CDS_PINID='B';
NODE_NAME     C5G21 2
 '@BASEBOARD_FAB2_LIB.BASEBOARD_FAB2(SCH_1):PAGE242_I92@MSTR_DISCRETE.CAP(CHIPS)':
 'B': CDS_PINID='B';
NODE_NAME     C5G115 2
 '@BASEBOARD_FAB2_LIB.BASEBOARD_FAB2(SCH_1):PAGE243_I89@MSTR_DISCRETE.CAP(CHIPS)':
 'B': CDS_PINID='B';
NODE_NAME     C5G116 2
 '@BASEBOARD_FAB2_LIB.BASEBOARD_FAB2(SCH_1):PAGE243_I90@MSTR_DISCRETE.CAP(CHIPS)':
 'B': CDS_PINID='B';
NODE_NAME     C5G118 2
 '@BASEBOARD_FAB2_LIB.BASEBOARD_FAB2(SCH_1):PAGE243_I91@MSTR_DISCRETE.CAP(CHIPS)':
 'B': CDS_PINID='B';
NODE_NAME     C5G117 2
 '@BASEBOARD_FAB2_LIB.BASEBOARD_FAB2(SCH_1):PAGE243_I92@MSTR_DISCRETE.CAP(CHIPS)':
 'B': CDS_PINID='B';
NODE_NAME     R25W57 2
 '@BASEBOARD_FAB2_LIB.BASEBOARD_FAB2(SCH_1):PAGE147_I151@MSTR_DISCRETE.RES(CHIPS)':
 'B': CDS_PINID='B';
NODE_NAME     C25W53 2
 '@BASEBOARD_FAB2_LIB.BASEBOARD_FAB2(SCH_1):PAGE149_I92@MSTR_DISCRETE.CAP(CHIPS)':
 'B': CDS_PINID='B';
NODE_NAME     C25W56 2
 '@BASEBOARD_FAB2_LIB.BASEBOARD_FAB2(SCH_1):PAGE149_I93@MSTR_DISCRETE.CAP(CHIPS)':
 'B': CDS_PINID='B';
NODE_NAME     C25W54 2
 '@BASEBOARD_FAB2_LIB.BASEBOARD_FAB2(SCH_1):PAGE149_I95@MSTR_DISCRETE.CAP(CHIPS)':
 'B': CDS_PINID='B';
NODE_NAME     C25W40 2
 '@BASEBOARD_FAB2_LIB.BASEBOARD_FAB2(SCH_1):PAGE149_I96@MSTR_DISCRETE.CAP(CHIPS)':
 'B': CDS_PINID='B';
NODE_NAME     C25W41 2
 '@BASEBOARD_FAB2_LIB.BASEBOARD_FAB2(SCH_1):PAGE149_I97@MSTR_DISCRETE.CAP(CHIPS)':
 'B': CDS_PINID='B';
NODE_NAME     C25W42 2
 '@BASEBOARD_FAB2_LIB.BASEBOARD_FAB2(SCH_1):PAGE149_I98@MSTR_DISCRETE.CAP(CHIPS)':
 'B': CDS_PINID='B';
NODE_NAME     C25W32 2
 '@BASEBOARD_FAB2_LIB.BASEBOARD_FAB2(SCH_1):PAGE149_I99@MSTR_DISCRETE.CAP(CHIPS)':
 'B': CDS_PINID='B';
NODE_NAME     C25W43 2
 '@BASEBOARD_FAB2_LIB.BASEBOARD_FAB2(SCH_1):PAGE149_I100@MSTR_DISCRETE.CAP(CHIPS)':
 'B': CDS_PINID='B';
NODE_NAME     C25W44 2
 '@BASEBOARD_FAB2_LIB.BASEBOARD_FAB2(SCH_1):PAGE149_I101@MSTR_DISCRETE.CAP(CHIPS)':
 'B': CDS_PINID='B';
NODE_NAME     C25W33 2
 '@BASEBOARD_FAB2_LIB.BASEBOARD_FAB2(SCH_1):PAGE149_I102@MSTR_DISCRETE.CAP(CHIPS)':
 'B': CDS_PINID='B';
NODE_NAME     C25W23 2
 '@BASEBOARD_FAB2_LIB.BASEBOARD_FAB2(SCH_1):PAGE149_I103@MSTR_DISCRETE.CAP(CHIPS)':
 'B': CDS_PINID='B';
NODE_NAME     C25W24 2
 '@BASEBOARD_FAB2_LIB.BASEBOARD_FAB2(SCH_1):PAGE149_I104@MSTR_DISCRETE.CAP(CHIPS)':
 'B': CDS_PINID='B';
NODE_NAME     C25W25 2
 '@BASEBOARD_FAB2_LIB.BASEBOARD_FAB2(SCH_1):PAGE149_I105@MSTR_DISCRETE.CAP(CHIPS)':
 'B': CDS_PINID='B';
NODE_NAME     C25W26 2
 '@BASEBOARD_FAB2_LIB.BASEBOARD_FAB2(SCH_1):PAGE149_I106@MSTR_DISCRETE.CAP(CHIPS)':
 'B': CDS_PINID='B';
NODE_NAME     C25W27 2
 '@BASEBOARD_FAB2_LIB.BASEBOARD_FAB2(SCH_1):PAGE149_I107@MSTR_DISCRETE.CAP(CHIPS)':
 'B': CDS_PINID='B';
NODE_NAME     C25W28 2
 '@BASEBOARD_FAB2_LIB.BASEBOARD_FAB2(SCH_1):PAGE149_I108@MSTR_DISCRETE.CAP(CHIPS)':
 'B': CDS_PINID='B';
NODE_NAME     C25W60 2
 '@BASEBOARD_FAB2_LIB.BASEBOARD_FAB2(SCH_1):PAGE149_I109@MSTR_DISCRETE.CAP(CHIPS)':
 'B': CDS_PINID='B';
NODE_NAME     C25W35 2
 '@BASEBOARD_FAB2_LIB.BASEBOARD_FAB2(SCH_1):PAGE149_I110@MSTR_DISCRETE.CAP(CHIPS)':
 'B': CDS_PINID='B';
NODE_NAME     C25W48 2
 '@BASEBOARD_FAB2_LIB.BASEBOARD_FAB2(SCH_1):PAGE149_I112@MSTR_DISCRETE.CAP(CHIPS)':
 'B': CDS_PINID='B';
NODE_NAME     C25W37 2
 '@BASEBOARD_FAB2_LIB.BASEBOARD_FAB2(SCH_1):PAGE149_I113@MSTR_DISCRETE.CAP(CHIPS)':
 'B': CDS_PINID='B';
NODE_NAME     C25W51 2
 '@BASEBOARD_FAB2_LIB.BASEBOARD_FAB2(SCH_1):PAGE149_I114@MSTR_DISCRETE.CAP(CHIPS)':
 'B': CDS_PINID='B';
NODE_NAME     C25W71 2
 '@BASEBOARD_FAB2_LIB.BASEBOARD_FAB2(SCH_1):PAGE149_I115@MSTR_DISCRETE.CAP(CHIPS)':
 'B': CDS_PINID='B';
NODE_NAME     C25W66 2
 '@BASEBOARD_FAB2_LIB.BASEBOARD_FAB2(SCH_1):PAGE149_I116@MSTR_DISCRETE.CAP(CHIPS)':
 'B': CDS_PINID='B';
NODE_NAME     C25W67 2
 '@BASEBOARD_FAB2_LIB.BASEBOARD_FAB2(SCH_1):PAGE149_I117@MSTR_DISCRETE.CAP(CHIPS)':
 'B': CDS_PINID='B';
NODE_NAME     C25W52 2
 '@BASEBOARD_FAB2_LIB.BASEBOARD_FAB2(SCH_1):PAGE149_I118@MSTR_DISCRETE.CAP(CHIPS)':
 'B': CDS_PINID='B';
NODE_NAME     U2R1 2
 '@BASEBOARD_FAB2_LIB.BASEBOARD_FAB2(SCH_1):PAGE157_I390@W_HDL.TC7PZ14FU-GP(CHIPS)':
 'GND': CDS_PINID='GND';
NODE_NAME     U9A3 2
 '@BASEBOARD_FAB2_LIB.BASEBOARD_FAB2(SCH_1):PAGE175_I93@W_HDL.TC7PZ14FU-GP(CHIPS)':
 'GND': CDS_PINID='GND';
NODE_NAME     U9A4 2
 '@BASEBOARD_FAB2_LIB.BASEBOARD_FAB2(SCH_1):PAGE175_I97@W_HDL.TC7PZ14FU-GP(CHIPS)':
 'GND': CDS_PINID='GND';
NODE_NAME     R1U18 2
 '@BASEBOARD_FAB2_LIB.BASEBOARD_FAB2(SCH_1):PAGE164_I40@MSTR_DISCRETE.RES(CHIPS)':
 'B': CDS_PINID='B';
NODE_NAME     U8F3 2
 '@BASEBOARD_FAB2_LIB.BASEBOARD_FAB2(SCH_1):PAGE156_I340@W_HDL.SN74LVC2G07DCKR-GP(CHIPS)':
 'GND': CDS_PINID='GND';
NODE_NAME     U8G1 2
 '@BASEBOARD_FAB2_LIB.BASEBOARD_FAB2(SCH_1):PAGE156_I342@W_HDL.SN74LVC2G07DCKR-GP(CHIPS)':
 'GND': CDS_PINID='GND';
NODE_NAME     C10W2 2
 '@BASEBOARD_FAB2_LIB.BASEBOARD_FAB2(SCH_1):PAGE251_I1@DEV_DISCRETE.CAP_A(CHIPS)':
 'B': CDS_PINID='B';
NODE_NAME     C10W1 2
 '@BASEBOARD_FAB2_LIB.BASEBOARD_FAB2(SCH_1):PAGE251_I3@MSTR_DISCRETE.CAP(CHIPS)':
 'B': CDS_PINID='B';
NODE_NAME     C10W3 2
 '@BASEBOARD_FAB2_LIB.BASEBOARD_FAB2(SCH_1):PAGE251_I16@DEV_DISCRETE.CAP_A(CHIPS)':
 'B': CDS_PINID='B';
NODE_NAME     C10W4 2
 '@BASEBOARD_FAB2_LIB.BASEBOARD_FAB2(SCH_1):PAGE251_I21@DEV_DISCRETE.CAP_A(CHIPS)':
 'B': CDS_PINID='B';
NODE_NAME     Q1W2 4
 '@BASEBOARD_FAB2_LIB.BASEBOARD_FAB2(SCH_1):PAGE250_I12@MSTR_DISCRETE.FET_N_DUAL(CHIPS)':
 'SOURCE'<0>: CDS_PINID='SOURCE(0)';
NODE_NAME     Q1W2 1
 '@BASEBOARD_FAB2_LIB.BASEBOARD_FAB2(SCH_1):PAGE250_I24@MSTR_DISCRETE.FET_N_DUAL(CHIPS)':
 'SOURCE'<0>: CDS_PINID='SOURCE(0)';
NODE_NAME     R25W123 2
 '@BASEBOARD_FAB2_LIB.BASEBOARD_FAB2(SCH_1):PAGE144_I139@MSTR_DISCRETE.RES(CHIPS)':
 'B': CDS_PINID='B';
NODE_NAME     R25W124 2
 '@BASEBOARD_FAB2_LIB.BASEBOARD_FAB2(SCH_1):PAGE144_I140@MSTR_DISCRETE.RES(CHIPS)':
 'B': CDS_PINID='B';
NODE_NAME     R25W125 2
 '@BASEBOARD_FAB2_LIB.BASEBOARD_FAB2(SCH_1):PAGE144_I141@MSTR_DISCRETE.RES(CHIPS)':
 'B': CDS_PINID='B';
NODE_NAME     C25W72 2
 '@BASEBOARD_FAB2_LIB.BASEBOARD_FAB2(SCH_1):PAGE255_I7@MSTR_DISCRETE.CAP(CHIPS)':
 'B': CDS_PINID='B';
NODE_NAME     C25W73 2
 '@BASEBOARD_FAB2_LIB.BASEBOARD_FAB2(SCH_1):PAGE255_I11@MSTR_DISCRETE.CAP(CHIPS)':
 'B': CDS_PINID='B';
NODE_NAME     C25W74 2
 '@BASEBOARD_FAB2_LIB.BASEBOARD_FAB2(SCH_1):PAGE255_I12@MSTR_DISCRETE.CAP(CHIPS)':
 'B': CDS_PINID='B';
NODE_NAME     C25W77 2
 '@BASEBOARD_FAB2_LIB.BASEBOARD_FAB2(SCH_1):PAGE255_I16@MSTR_DISCRETE.CAP(CHIPS)':
 'B': CDS_PINID='B';
NODE_NAME     C25W76 2
 '@BASEBOARD_FAB2_LIB.BASEBOARD_FAB2(SCH_1):PAGE255_I18@MSTR_DISCRETE.CAP(CHIPS)':
 'B': CDS_PINID='B';
NODE_NAME     C25W75 2
 '@BASEBOARD_FAB2_LIB.BASEBOARD_FAB2(SCH_1):PAGE255_I21@MSTR_DISCRETE.CAP(CHIPS)':
 'B': CDS_PINID='B';
NODE_NAME     R25W128 2
 '@BASEBOARD_FAB2_LIB.BASEBOARD_FAB2(SCH_1):PAGE255_I22@MSTR_DISCRETE.RES(CHIPS)':
 'B': CDS_PINID='B';
NODE_NAME     R25W127 2
 '@BASEBOARD_FAB2_LIB.BASEBOARD_FAB2(SCH_1):PAGE255_I24@MSTR_DISCRETE.RES(CHIPS)':
 'B': CDS_PINID='B';
NODE_NAME     R25W126 2
 '@BASEBOARD_FAB2_LIB.BASEBOARD_FAB2(SCH_1):PAGE255_I26@MSTR_DISCRETE.RES(CHIPS)':
 'B': CDS_PINID='B';
NODE_NAME     C25W78 2
 '@BASEBOARD_FAB2_LIB.BASEBOARD_FAB2(SCH_1):PAGE255_I35@MSTR_DISCRETE.CAP(CHIPS)':
 'B': CDS_PINID='B';
NODE_NAME     C25W79 2
 '@BASEBOARD_FAB2_LIB.BASEBOARD_FAB2(SCH_1):PAGE255_I39@MSTR_DISCRETE.CAP(CHIPS)':
 'B': CDS_PINID='B';
NODE_NAME     R25W116 1
 '@BASEBOARD_FAB2_LIB.BASEBOARD_FAB2(SCH_1):PAGE150_I189@MSTR_DISCRETE.RES(CHIPS)':
 'A': CDS_PINID='A';
NODE_NAME     C25W81 2
 '@BASEBOARD_FAB2_LIB.BASEBOARD_FAB2(SCH_1):PAGE255_I60@MSTR_DISCRETE.CAP(CHIPS)':
 'B': CDS_PINID='B';
NODE_NAME     C25W82 2
 '@BASEBOARD_FAB2_LIB.BASEBOARD_FAB2(SCH_1):PAGE255_I62@MSTR_DISCRETE.CAP(CHIPS)':
 'B': CDS_PINID='B';
NODE_NAME     C25P83 2
 '@BASEBOARD_FAB2_LIB.BASEBOARD_FAB2(SCH_1):PAGE255_I74@DEV_DISCRETE.CAP_A(CHIPS)':
 'B': CDS_PINID='B';
NODE_NAME     U1B2 4
 '@BASEBOARD_FAB2_LIB.BASEBOARD_FAB2(SCH_1):PAGE163_I28@W_HDL.TCA9517DGKR-GP(CHIPS)':
 'GND': CDS_PINID='GND';
NODE_NAME     U6W2 4
 '@BASEBOARD_FAB2_LIB.BASEBOARD_FAB2(SCH_1):PAGE247_I118@W_HDL.TCA9517DGKR-GP(CHIPS)':
 'GND': CDS_PINID='GND';
NODE_NAME     U1W2 4
 '@BASEBOARD_FAB2_LIB.BASEBOARD_FAB2(SCH_1):PAGE248_I49@W_HDL.TCA9517DGKR-GP(CHIPS)':
 'GND': CDS_PINID='GND';
NODE_NAME     R7D1 2
 '@BASEBOARD_FAB2_LIB.BASEBOARD_FAB2(SCH_1):PAGE125_I86@MSTR_DISCRETE.RES(CHIPS)':
 'B': CDS_PINID='B';
NODE_NAME     C22W1 2
 '@BASEBOARD_FAB2_LIB.BASEBOARD_FAB2(SCH_1):PAGE225_I246@W_HDL.SC22U16V5MX-4-GP(CHIPS)':
 '2': CDS_PINID='\2\';
NODE_NAME     C22W2 2
 '@BASEBOARD_FAB2_LIB.BASEBOARD_FAB2(SCH_1):PAGE225_I247@W_HDL.SC22U16V5MX-4-GP(CHIPS)':
 '2': CDS_PINID='\2\';
NODE_NAME     C22W3 2
 '@BASEBOARD_FAB2_LIB.BASEBOARD_FAB2(SCH_1):PAGE225_I249@W_HDL.SC22U16V5MX-4-GP(CHIPS)':
 '2': CDS_PINID='\2\';
NODE_NAME     C1G2 2
 '@BASEBOARD_FAB2_LIB.BASEBOARD_FAB2(SCH_1):PAGE225_I250@W_HDL.SC22U16V5MX-4-GP(CHIPS)':
 '2': CDS_PINID='\2\';
NODE_NAME     C22W4 2
 '@BASEBOARD_FAB2_LIB.BASEBOARD_FAB2(SCH_1):PAGE225_I251@W_HDL.SC22U16V5MX-4-GP(CHIPS)':
 '2': CDS_PINID='\2\';
NODE_NAME     C22W5 2
 '@BASEBOARD_FAB2_LIB.BASEBOARD_FAB2(SCH_1):PAGE234_I222@W_HDL.SC22U16V5MX-4-GP(CHIPS)':
 '2': CDS_PINID='\2\';
NODE_NAME     C4B1 2
 '@BASEBOARD_FAB2_LIB.BASEBOARD_FAB2(SCH_1):PAGE234_I223@W_HDL.SC22U16V5MX-4-GP(CHIPS)':
 '2': CDS_PINID='\2\';
NODE_NAME     C22W6 2
 '@BASEBOARD_FAB2_LIB.BASEBOARD_FAB2(SCH_1):PAGE233_I278@W_HDL.SC22U16V5MX-4-GP(CHIPS)':
 '2': CDS_PINID='\2\';
NODE_NAME     C4G5 2
 '@BASEBOARD_FAB2_LIB.BASEBOARD_FAB2(SCH_1):PAGE233_I280@W_HDL.SC22U16V5MX-4-GP(CHIPS)':
 '2': CDS_PINID='\2\';
NODE_NAME     C7B8 2
 '@BASEBOARD_FAB2_LIB.BASEBOARD_FAB2(SCH_1):PAGE232_I309@W_HDL.SC22U16V5MX-4-GP(CHIPS)':
 '2': CDS_PINID='\2\';
NODE_NAME     C22W7 2
 '@BASEBOARD_FAB2_LIB.BASEBOARD_FAB2(SCH_1):PAGE232_I311@W_HDL.SC22U16V5MX-4-GP(CHIPS)':
 '2': CDS_PINID='\2\';
NODE_NAME     C7E13 2
 '@BASEBOARD_FAB2_LIB.BASEBOARD_FAB2(SCH_1):PAGE241_I92@W_HDL.SC22U16V5MX-4-GP(CHIPS)':
 '2': CDS_PINID='\2\';
NODE_NAME     C22W9 2
 '@BASEBOARD_FAB2_LIB.BASEBOARD_FAB2(SCH_1):PAGE241_I95@W_HDL.SC22U16V5MX-4-GP(CHIPS)':
 '2': CDS_PINID='\2\';
NODE_NAME     C22W8 2
 '@BASEBOARD_FAB2_LIB.BASEBOARD_FAB2(SCH_1):PAGE241_I96@W_HDL.SC22U16V5MX-4-GP(CHIPS)':
 '2': CDS_PINID='\2\';
NODE_NAME     C7E12 2
 '@BASEBOARD_FAB2_LIB.BASEBOARD_FAB2(SCH_1):PAGE241_I98@W_HDL.SC22U16V5MX-4-GP(CHIPS)':
 '2': CDS_PINID='\2\';
NODE_NAME     C22W10 2
 '@BASEBOARD_FAB2_LIB.BASEBOARD_FAB2(SCH_1):PAGE231_I225@W_HDL.SC22U16V5MX-4-GP(CHIPS)':
 '2': CDS_PINID='\2\';
NODE_NAME     C7F7 2
 '@BASEBOARD_FAB2_LIB.BASEBOARD_FAB2(SCH_1):PAGE231_I226@W_HDL.SC22U16V5MX-4-GP(CHIPS)':
 '2': CDS_PINID='\2\';
NODE_NAME     C9F1 2
 '@BASEBOARD_FAB2_LIB.BASEBOARD_FAB2(SCH_1):PAGE240_I181@W_HDL.SC22U16V5MX-4-GP(CHIPS)':
 '2': CDS_PINID='\2\';
NODE_NAME     C22W11 2
 '@BASEBOARD_FAB2_LIB.BASEBOARD_FAB2(SCH_1):PAGE240_I182@W_HDL.SC22U16V5MX-4-GP(CHIPS)':
 '2': CDS_PINID='\2\';
NODE_NAME     C8E11 2
 '@BASEBOARD_FAB2_LIB.BASEBOARD_FAB2(SCH_1):PAGE240_I183@W_HDL.SC22U16V5MX-4-GP(CHIPS)':
 '2': CDS_PINID='\2\';
NODE_NAME     C22W12 2
 '@BASEBOARD_FAB2_LIB.BASEBOARD_FAB2(SCH_1):PAGE240_I186@W_HDL.SC22U16V5MX-4-GP(CHIPS)':
 '2': CDS_PINID='\2\';
NODE_NAME     C4E14 2
 '@BASEBOARD_FAB2_LIB.BASEBOARD_FAB2(SCH_1):PAGE214_I148@W_HDL.SC22U16V5MX-4-GP(CHIPS)':
 '2': CDS_PINID='\2\';
NODE_NAME     C22W13 2
 '@BASEBOARD_FAB2_LIB.BASEBOARD_FAB2(SCH_1):PAGE214_I149@W_HDL.SC22U16V5MX-4-GP(CHIPS)':
 '2': CDS_PINID='\2\';
NODE_NAME     C22W14 2
 '@BASEBOARD_FAB2_LIB.BASEBOARD_FAB2(SCH_1):PAGE214_I152@W_HDL.SC22U16V5MX-4-GP(CHIPS)':
 '2': CDS_PINID='\2\';
NODE_NAME     C22W15 2
 '@BASEBOARD_FAB2_LIB.BASEBOARD_FAB2(SCH_1):PAGE214_I154@W_HDL.SC22U16V5MX-4-GP(CHIPS)':
 '2': CDS_PINID='\2\';
NODE_NAME     C22W18 2
 '@BASEBOARD_FAB2_LIB.BASEBOARD_FAB2(SCH_1):PAGE214_I156@W_HDL.SC22U16V5MX-4-GP(CHIPS)':
 '2': CDS_PINID='\2\';
NODE_NAME     C22W17 2
 '@BASEBOARD_FAB2_LIB.BASEBOARD_FAB2(SCH_1):PAGE214_I158@W_HDL.SC22U16V5MX-4-GP(CHIPS)':
 '2': CDS_PINID='\2\';
NODE_NAME     C22W16 2
 '@BASEBOARD_FAB2_LIB.BASEBOARD_FAB2(SCH_1):PAGE214_I160@W_HDL.SC22U16V5MX-4-GP(CHIPS)':
 '2': CDS_PINID='\2\';
NODE_NAME     C4E8 2
 '@BASEBOARD_FAB2_LIB.BASEBOARD_FAB2(SCH_1):PAGE214_I161@W_HDL.SC22U16V5MX-4-GP(CHIPS)':
 '2': CDS_PINID='\2\';
NODE_NAME     C4E9 2
 '@BASEBOARD_FAB2_LIB.BASEBOARD_FAB2(SCH_1):PAGE214_I164@W_HDL.SC22U16V5MX-4-GP(CHIPS)':
 '2': CDS_PINID='\2\';
NODE_NAME     C22W21 2
 '@BASEBOARD_FAB2_LIB.BASEBOARD_FAB2(SCH_1):PAGE214_I166@W_HDL.SC22U16V5MX-4-GP(CHIPS)':
 '2': CDS_PINID='\2\';
NODE_NAME     C22W20 2
 '@BASEBOARD_FAB2_LIB.BASEBOARD_FAB2(SCH_1):PAGE214_I168@W_HDL.SC22U16V5MX-4-GP(CHIPS)':
 '2': CDS_PINID='\2\';
NODE_NAME     C22W19 2
 '@BASEBOARD_FAB2_LIB.BASEBOARD_FAB2(SCH_1):PAGE214_I169@W_HDL.SC22U16V5MX-4-GP(CHIPS)':
 '2': CDS_PINID='\2\';
NODE_NAME     C22W23 2
 '@BASEBOARD_FAB2_LIB.BASEBOARD_FAB2(SCH_1):PAGE236_I159@W_HDL.SC22U16V5MX-4-GP(CHIPS)':
 '2': CDS_PINID='\2\';
NODE_NAME     C22W24 2
 '@BASEBOARD_FAB2_LIB.BASEBOARD_FAB2(SCH_1):PAGE236_I160@W_HDL.SC22U16V5MX-4-GP(CHIPS)':
 '2': CDS_PINID='\2\';
NODE_NAME     C7A13 2
 '@BASEBOARD_FAB2_LIB.BASEBOARD_FAB2(SCH_1):PAGE236_I161@W_HDL.SC22U16V5MX-4-GP(CHIPS)':
 '2': CDS_PINID='\2\';
NODE_NAME     C22W25 2
 '@BASEBOARD_FAB2_LIB.BASEBOARD_FAB2(SCH_1):PAGE236_I162@W_HDL.SC22U16V5MX-4-GP(CHIPS)':
 '2': CDS_PINID='\2\';
NODE_NAME     C22W27 2
 '@BASEBOARD_FAB2_LIB.BASEBOARD_FAB2(SCH_1):PAGE236_I163@W_HDL.SC22U16V5MX-4-GP(CHIPS)':
 '2': CDS_PINID='\2\';
NODE_NAME     C22W26 2
 '@BASEBOARD_FAB2_LIB.BASEBOARD_FAB2(SCH_1):PAGE236_I165@W_HDL.SC22U16V5MX-4-GP(CHIPS)':
 '2': CDS_PINID='\2\';
NODE_NAME     C22W22 2
 '@BASEBOARD_FAB2_LIB.BASEBOARD_FAB2(SCH_1):PAGE236_I171@W_HDL.SC22U16V5MX-4-GP(CHIPS)':
 '2': CDS_PINID='\2\';
NODE_NAME     C7A14 2
 '@BASEBOARD_FAB2_LIB.BASEBOARD_FAB2(SCH_1):PAGE236_I172@W_HDL.SC22U16V5MX-4-GP(CHIPS)':
 '2': CDS_PINID='\2\';
NODE_NAME     C22W33 2
 '@BASEBOARD_FAB2_LIB.BASEBOARD_FAB2(SCH_1):PAGE212_I124@W_HDL.SC22U16V5MX-4-GP(CHIPS)':
 '2': CDS_PINID='\2\';
NODE_NAME     C22W32 2
 '@BASEBOARD_FAB2_LIB.BASEBOARD_FAB2(SCH_1):PAGE212_I126@W_HDL.SC22U16V5MX-4-GP(CHIPS)':
 '2': CDS_PINID='\2\';
NODE_NAME     C22W31 2
 '@BASEBOARD_FAB2_LIB.BASEBOARD_FAB2(SCH_1):PAGE212_I129@W_HDL.SC22U16V5MX-4-GP(CHIPS)':
 '2': CDS_PINID='\2\';
NODE_NAME     C7C8 2
 '@BASEBOARD_FAB2_LIB.BASEBOARD_FAB2(SCH_1):PAGE212_I130@W_HDL.SC22U16V5MX-4-GP(CHIPS)':
 '2': CDS_PINID='\2\';
NODE_NAME     C22W30 2
 '@BASEBOARD_FAB2_LIB.BASEBOARD_FAB2(SCH_1):PAGE212_I132@W_HDL.SC22U16V5MX-4-GP(CHIPS)':
 '2': CDS_PINID='\2\';
NODE_NAME     C22W29 2
 '@BASEBOARD_FAB2_LIB.BASEBOARD_FAB2(SCH_1):PAGE212_I134@W_HDL.SC22U16V5MX-4-GP(CHIPS)':
 '2': CDS_PINID='\2\';
NODE_NAME     C22W28 2
 '@BASEBOARD_FAB2_LIB.BASEBOARD_FAB2(SCH_1):PAGE212_I136@W_HDL.SC22U16V5MX-4-GP(CHIPS)':
 '2': CDS_PINID='\2\';
NODE_NAME     C7C7 2
 '@BASEBOARD_FAB2_LIB.BASEBOARD_FAB2(SCH_1):PAGE212_I138@W_HDL.SC22U16V5MX-4-GP(CHIPS)':
 '2': CDS_PINID='\2\';
NODE_NAME     C22W34 2
 '@BASEBOARD_FAB2_LIB.BASEBOARD_FAB2(SCH_1):PAGE139_I244@W_HDL.SC22U16V5MX-4-GP(CHIPS)':
 '2': CDS_PINID='\2\';
NODE_NAME     C9F2 2
 '@BASEBOARD_FAB2_LIB.BASEBOARD_FAB2(SCH_1):PAGE139_I245@W_HDL.SC22U16V5MX-4-GP(CHIPS)':
 '2': CDS_PINID='\2\';
NODE_NAME     C22W35 2
 '@BASEBOARD_FAB2_LIB.BASEBOARD_FAB2(SCH_1):PAGE139_I246@W_HDL.SC22U16V5MX-4-GP(CHIPS)':
 '2': CDS_PINID='\2\';
NODE_NAME     C9E6 2
 '@BASEBOARD_FAB2_LIB.BASEBOARD_FAB2(SCH_1):PAGE139_I248@W_HDL.SC22U16V5MX-4-GP(CHIPS)':
 '2': CDS_PINID='\2\';
NODE_NAME     Q1W1 2
 '@BASEBOARD_FAB2_LIB.BASEBOARD_FAB2(SCH_1):PAGE250_I29@MSTR_DISCRETE.FET_N(CHIPS)':
 'SRC': CDS_PINID='SRC';
NODE_NAME     Q1W5 2
 '@BASEBOARD_FAB2_LIB.BASEBOARD_FAB2(SCH_1):PAGE199_I130@MSTR_DISCRETE.FET_N(CHIPS)':
 'SRC': CDS_PINID='SRC';
NODE_NAME     U6W1 12
 '@BASEBOARD_FAB2_LIB.BASEBOARD_FAB2(SCH_1):PAGE247_I120@W_HDL.TCA9555PWR-GP(CHIPS)':
 'GND': CDS_PINID='GND';
NODE_NAME     CR30W1 3
 '@BASEBOARD_FAB2_LIB.BASEBOARD_FAB2(SCH_1):PAGE253_I5@MSTR_DISCRETE.DIODEAC_DUAL_ARRAY(CHIPS)':
 'GND'<0>: CDS_PINID='GND(0)';
NODE_NAME     U25W7 3
 '@BASEBOARD_FAB2_LIB.BASEBOARD_FAB2(SCH_1):PAGE255_I111@W_HDL.U74AHCT1G125G-AL5-R-GP-U(CHIPS)':
 'GND': CDS_PINID='GND';
NODE_NAME     U25W7 1
 '@BASEBOARD_FAB2_LIB.BASEBOARD_FAB2(SCH_1):PAGE255_I111@W_HDL.U74AHCT1G125G-AL5-R-GP-U(CHIPS)':
 'OE#': CDS_PINID='\oe#\';
NODE_NAME     U25W8 3
 '@BASEBOARD_FAB2_LIB.BASEBOARD_FAB2(SCH_1):PAGE255_I112@W_HDL.U74AHCT1G125G-AL5-R-GP-U(CHIPS)':
 'GND': CDS_PINID='GND';
NODE_NAME     U25W8 1
 '@BASEBOARD_FAB2_LIB.BASEBOARD_FAB2(SCH_1):PAGE255_I112@W_HDL.U74AHCT1G125G-AL5-R-GP-U(CHIPS)':
 'OE#': CDS_PINID='\oe#\';
NODE_NAME     C25W90 2
 '@BASEBOARD_FAB2_LIB.BASEBOARD_FAB2(SCH_1):PAGE255_I118@DEV_DISCRETE.CAP_A(CHIPS)':
 'B': CDS_PINID='B';
NODE_NAME     CR25W1 3
 '@BASEBOARD_FAB2_LIB.BASEBOARD_FAB2(SCH_1):PAGE255_I129@MSTR_DISCRETE.DIODEAC_DUAL_ARRAY(CHIPS)':
 'GND'<0>: CDS_PINID='GND(0)';
NODE_NAME     CR25W2 3
 '@BASEBOARD_FAB2_LIB.BASEBOARD_FAB2(SCH_1):PAGE255_I131@MSTR_DISCRETE.DIODEAC_DUAL_ARRAY(CHIPS)':
 'GND'<0>: CDS_PINID='GND(0)';
NODE_NAME     C25P80 2
 '@BASEBOARD_FAB2_LIB.BASEBOARD_FAB2(SCH_1):PAGE255_I134@DEV_DISCRETE.CAP_A(CHIPS)':
 'B': CDS_PINID='B';
NODE_NAME     C1W16 2
 '@BASEBOARD_FAB2_LIB.BASEBOARD_FAB2(SCH_1):PAGE199_I132@MSTR_DISCRETE.CAP(CHIPS)':
 'B': CDS_PINID='B';
NODE_NAME     R1W21 1
 '@BASEBOARD_FAB2_LIB.BASEBOARD_FAB2(SCH_1):PAGE199_I135@MSTR_DISCRETE.RES(CHIPS)':
 'A': CDS_PINID='A';
NODE_NAME     R25W142 2
 '@BASEBOARD_FAB2_LIB.BASEBOARD_FAB2(SCH_1):PAGE147_I156@MSTR_DISCRETE.RES(CHIPS)':
 'B': CDS_PINID='B';
NODE_NAME     J2W1 H1
 '@BASEBOARD_FAB2_LIB.BASEBOARD_FAB2(SCH_1):PAGE172_I67@W_HDL.SKT-SATA7P-6P-165-GP-U1(CHIPS)':
 'H1': CDS_PINID='H1';
NODE_NAME     J2W1 H2
 '@BASEBOARD_FAB2_LIB.BASEBOARD_FAB2(SCH_1):PAGE172_I67@W_HDL.SKT-SATA7P-6P-165-GP-U1(CHIPS)':
 'H2': CDS_PINID='H2';
NODE_NAME     J2W1 P3
 '@BASEBOARD_FAB2_LIB.BASEBOARD_FAB2(SCH_1):PAGE172_I67@W_HDL.SKT-SATA7P-6P-165-GP-U1(CHIPS)':
 'P3': CDS_PINID='P3';
NODE_NAME     J2W1 P4
 '@BASEBOARD_FAB2_LIB.BASEBOARD_FAB2(SCH_1):PAGE172_I67@W_HDL.SKT-SATA7P-6P-165-GP-U1(CHIPS)':
 'P4': CDS_PINID='P4';
NODE_NAME     J2W1 S1
 '@BASEBOARD_FAB2_LIB.BASEBOARD_FAB2(SCH_1):PAGE172_I67@W_HDL.SKT-SATA7P-6P-165-GP-U1(CHIPS)':
 'S1': CDS_PINID='S1';
NODE_NAME     J2W1 S4
 '@BASEBOARD_FAB2_LIB.BASEBOARD_FAB2(SCH_1):PAGE172_I67@W_HDL.SKT-SATA7P-6P-165-GP-U1(CHIPS)':
 'S4': CDS_PINID='S4';
NODE_NAME     J2W1 S7
 '@BASEBOARD_FAB2_LIB.BASEBOARD_FAB2(SCH_1):PAGE172_I67@W_HDL.SKT-SATA7P-6P-165-GP-U1(CHIPS)':
 'S7': CDS_PINID='S7';
NODE_NAME     J2W2 H1
 '@BASEBOARD_FAB2_LIB.BASEBOARD_FAB2(SCH_1):PAGE172_I68@W_HDL.SKT-SATA7P-6P-165-GP-U1(CHIPS)':
 'H1': CDS_PINID='H1';
NODE_NAME     J2W2 H2
 '@BASEBOARD_FAB2_LIB.BASEBOARD_FAB2(SCH_1):PAGE172_I68@W_HDL.SKT-SATA7P-6P-165-GP-U1(CHIPS)':
 'H2': CDS_PINID='H2';
NODE_NAME     J2W2 P3
 '@BASEBOARD_FAB2_LIB.BASEBOARD_FAB2(SCH_1):PAGE172_I68@W_HDL.SKT-SATA7P-6P-165-GP-U1(CHIPS)':
 'P3': CDS_PINID='P3';
NODE_NAME     J2W2 P4
 '@BASEBOARD_FAB2_LIB.BASEBOARD_FAB2(SCH_1):PAGE172_I68@W_HDL.SKT-SATA7P-6P-165-GP-U1(CHIPS)':
 'P4': CDS_PINID='P4';
NODE_NAME     J2W2 S1
 '@BASEBOARD_FAB2_LIB.BASEBOARD_FAB2(SCH_1):PAGE172_I68@W_HDL.SKT-SATA7P-6P-165-GP-U1(CHIPS)':
 'S1': CDS_PINID='S1';
NODE_NAME     J2W2 S4
 '@BASEBOARD_FAB2_LIB.BASEBOARD_FAB2(SCH_1):PAGE172_I68@W_HDL.SKT-SATA7P-6P-165-GP-U1(CHIPS)':
 'S4': CDS_PINID='S4';
NODE_NAME     J2W2 S7
 '@BASEBOARD_FAB2_LIB.BASEBOARD_FAB2(SCH_1):PAGE172_I68@W_HDL.SKT-SATA7P-6P-165-GP-U1(CHIPS)':
 'S7': CDS_PINID='S7';
NODE_NAME     JA9G1 1
 '@BASEBOARD_FAB2_LIB.BASEBOARD_FAB2(SCH_1):PAGE141_I129@W_HDL.SKT-RJ45-LED-XFOR-1-GP(CHIPS)':
 '1': CDS_PINID='\1\';
NODE_NAME     JA9G1 2
 '@BASEBOARD_FAB2_LIB.BASEBOARD_FAB2(SCH_1):PAGE141_I129@W_HDL.SKT-RJ45-LED-XFOR-1-GP(CHIPS)':
 '2': CDS_PINID='\2\';
NODE_NAME     JA9G1 R6
 '@BASEBOARD_FAB2_LIB.BASEBOARD_FAB2(SCH_1):PAGE141_I129@W_HDL.SKT-RJ45-LED-XFOR-1-GP(CHIPS)':
 'R6': CDS_PINID='R6';
NODE_NAME     C9G3 2
 '@BASEBOARD_FAB2_LIB.BASEBOARD_FAB2(SCH_1):PAGE141_I138@MSTR_DISCRETE.CAP(CHIPS)':
 'B': CDS_PINID='B';
NODE_NAME     C9G1 2
 '@BASEBOARD_FAB2_LIB.BASEBOARD_FAB2(SCH_1):PAGE141_I140@MSTR_DISCRETE.CAP(CHIPS)':
 'B': CDS_PINID='B';
NODE_NAME     C9G2 2
 '@BASEBOARD_FAB2_LIB.BASEBOARD_FAB2(SCH_1):PAGE141_I152@MSTR_DISCRETE.CAP(CHIPS)':
 'B': CDS_PINID='B';
NODE_NAME     C9F22 2
 '@BASEBOARD_FAB2_LIB.BASEBOARD_FAB2(SCH_1):PAGE141_I159@MSTR_DISCRETE.CAP(CHIPS)':
 'B': CDS_PINID='B';
NODE_NAME     C3W1 2
 '@BASEBOARD_FAB2_LIB.BASEBOARD_FAB2(SCH_1):PAGE114_I193@MSTR_DISCRETE.CAP(CHIPS)':
 'B': CDS_PINID='B';
NODE_NAME     J25W1 2
 '@BASEBOARD_FAB2_LIB.BASEBOARD_FAB2(SCH_1):PAGE255_I136@W_HDL.SMC-CON13-GP(CHIPS)':
 '2': CDS_PINID='\2\';
NODE_NAME     J25W1 4
 '@BASEBOARD_FAB2_LIB.BASEBOARD_FAB2(SCH_1):PAGE255_I136@W_HDL.SMC-CON13-GP(CHIPS)':
 '4': CDS_PINID='\4\';
NODE_NAME     J25W1 6
 '@BASEBOARD_FAB2_LIB.BASEBOARD_FAB2(SCH_1):PAGE255_I136@W_HDL.SMC-CON13-GP(CHIPS)':
 '6': CDS_PINID='\6\';
NODE_NAME     J25W1 8
 '@BASEBOARD_FAB2_LIB.BASEBOARD_FAB2(SCH_1):PAGE255_I136@W_HDL.SMC-CON13-GP(CHIPS)':
 '8': CDS_PINID='\8\';
NODE_NAME     J25W1 10
 '@BASEBOARD_FAB2_LIB.BASEBOARD_FAB2(SCH_1):PAGE255_I136@W_HDL.SMC-CON13-GP(CHIPS)':
 '10': CDS_PINID='\10\';
NODE_NAME     J25W1 PTH1
 '@BASEBOARD_FAB2_LIB.BASEBOARD_FAB2(SCH_1):PAGE255_I136@W_HDL.SMC-CON13-GP(CHIPS)':
 'PTH1': CDS_PINID='PTH1';
NODE_NAME     J25W1 PTH2
 '@BASEBOARD_FAB2_LIB.BASEBOARD_FAB2(SCH_1):PAGE255_I136@W_HDL.SMC-CON13-GP(CHIPS)':
 'PTH2': CDS_PINID='PTH2';
NODE_NAME     C8F14 2
 '@BASEBOARD_FAB2_LIB.BASEBOARD_FAB2(SCH_1):PAGE240_I189@W_HDL.ST470U6D3VDM-7-GP(CHIPS)':
 '2': CDS_PINID='\2\';
NODE_NAME     C8F8 2
 '@BASEBOARD_FAB2_LIB.BASEBOARD_FAB2(SCH_1):PAGE240_I190@W_HDL.ST470U6D3VDM-7-GP(CHIPS)':
 '2': CDS_PINID='\2\';
NODE_NAME     J8F1 1
 '@BASEBOARD_FAB2_LIB.BASEBOARD_FAB2(SCH_1):PAGE185_I143@W_HDL.SKT-MINI67P-41-GP(CHIPS)':
 '1': CDS_PINID='\1\';
NODE_NAME     J8F1 3
 '@BASEBOARD_FAB2_LIB.BASEBOARD_FAB2(SCH_1):PAGE185_I143@W_HDL.SKT-MINI67P-41-GP(CHIPS)':
 '3': CDS_PINID='\3\';
NODE_NAME     J8F1 9
 '@BASEBOARD_FAB2_LIB.BASEBOARD_FAB2(SCH_1):PAGE185_I143@W_HDL.SKT-MINI67P-41-GP(CHIPS)':
 '9': CDS_PINID='\9\';
NODE_NAME     J8F1 15
 '@BASEBOARD_FAB2_LIB.BASEBOARD_FAB2(SCH_1):PAGE185_I143@W_HDL.SKT-MINI67P-41-GP(CHIPS)':
 '15': CDS_PINID='\15\';
NODE_NAME     J8F1 21
 '@BASEBOARD_FAB2_LIB.BASEBOARD_FAB2(SCH_1):PAGE185_I143@W_HDL.SKT-MINI67P-41-GP(CHIPS)':
 '21': CDS_PINID='\21\';
NODE_NAME     J8F1 27
 '@BASEBOARD_FAB2_LIB.BASEBOARD_FAB2(SCH_1):PAGE185_I143@W_HDL.SKT-MINI67P-41-GP(CHIPS)':
 '27': CDS_PINID='\27\';
NODE_NAME     J8F1 33
 '@BASEBOARD_FAB2_LIB.BASEBOARD_FAB2(SCH_1):PAGE185_I143@W_HDL.SKT-MINI67P-41-GP(CHIPS)':
 '33': CDS_PINID='\33\';
NODE_NAME     J8F1 39
 '@BASEBOARD_FAB2_LIB.BASEBOARD_FAB2(SCH_1):PAGE185_I143@W_HDL.SKT-MINI67P-41-GP(CHIPS)':
 '39': CDS_PINID='\39\';
NODE_NAME     J8F1 45
 '@BASEBOARD_FAB2_LIB.BASEBOARD_FAB2(SCH_1):PAGE185_I143@W_HDL.SKT-MINI67P-41-GP(CHIPS)':
 '45': CDS_PINID='\45\';
NODE_NAME     J8F1 51
 '@BASEBOARD_FAB2_LIB.BASEBOARD_FAB2(SCH_1):PAGE185_I143@W_HDL.SKT-MINI67P-41-GP(CHIPS)':
 '51': CDS_PINID='\51\';
NODE_NAME     J8F1 57
 '@BASEBOARD_FAB2_LIB.BASEBOARD_FAB2(SCH_1):PAGE185_I143@W_HDL.SKT-MINI67P-41-GP(CHIPS)':
 '57': CDS_PINID='\57\';
NODE_NAME     J8F1 71
 '@BASEBOARD_FAB2_LIB.BASEBOARD_FAB2(SCH_1):PAGE185_I143@W_HDL.SKT-MINI67P-41-GP(CHIPS)':
 '71': CDS_PINID='\71\';
NODE_NAME     J8F1 73
 '@BASEBOARD_FAB2_LIB.BASEBOARD_FAB2(SCH_1):PAGE185_I143@W_HDL.SKT-MINI67P-41-GP(CHIPS)':
 '73': CDS_PINID='\73\';
NODE_NAME     J8F1 75
 '@BASEBOARD_FAB2_LIB.BASEBOARD_FAB2(SCH_1):PAGE185_I143@W_HDL.SKT-MINI67P-41-GP(CHIPS)':
 '75': CDS_PINID='\75\';
NODE_NAME     J8F1 76
 '@BASEBOARD_FAB2_LIB.BASEBOARD_FAB2(SCH_1):PAGE185_I143@W_HDL.SKT-MINI67P-41-GP(CHIPS)':
 '76': CDS_PINID='\76\';
NODE_NAME     J8F1 77
 '@BASEBOARD_FAB2_LIB.BASEBOARD_FAB2(SCH_1):PAGE185_I143@W_HDL.SKT-MINI67P-41-GP(CHIPS)':
 '77': CDS_PINID='\77\';
NODE_NAME     C1W17 2
 '@BASEBOARD_FAB2_LIB.BASEBOARD_FAB2(SCH_1):PAGE101_I139@MSTR_DISCRETE.CAP(CHIPS)':
 'B': CDS_PINID='B';
NODE_NAME     R1W25 2
 '@BASEBOARD_FAB2_LIB.BASEBOARD_FAB2(SCH_1):PAGE101_I140@MSTR_DISCRETE.RES(CHIPS)':
 'B': CDS_PINID='B';
NODE_NAME     R1W26 2
 '@BASEBOARD_FAB2_LIB.BASEBOARD_FAB2(SCH_1):PAGE190_I349@MSTR_DISCRETE.RES(CHIPS)':
 'B': CDS_PINID='B';
NODE_NAME     C4W1 2
 '@BASEBOARD_FAB2_LIB.BASEBOARD_FAB2(SCH_1):PAGE211_I97@MSTR_DISCRETE.CAP(CHIPS)':
 'B': CDS_PINID='B';
NODE_NAME     C4W2 2
 '@BASEBOARD_FAB2_LIB.BASEBOARD_FAB2(SCH_1):PAGE213_I101@MSTR_DISCRETE.CAP(CHIPS)':
 'B': CDS_PINID='B';
NODE_NAME     C4W3 2
 '@BASEBOARD_FAB2_LIB.BASEBOARD_FAB2(SCH_1):PAGE235_I244@MSTR_DISCRETE.CAP(CHIPS)':
 'B': CDS_PINID='B';
NODE_NAME     C4W4 2
 '@BASEBOARD_FAB2_LIB.BASEBOARD_FAB2(SCH_1):PAGE235_I246@MSTR_DISCRETE.CAP(CHIPS)':
 'B': CDS_PINID='B';
NODE_NAME     R25W146 1
 '@BASEBOARD_FAB2_LIB.BASEBOARD_FAB2(SCH_1):PAGE150_I199@MSTR_DISCRETE.RES(CHIPS)':
 'A': CDS_PINID='A';
NODE_NAME     R25W148 1
 '@BASEBOARD_FAB2_LIB.BASEBOARD_FAB2(SCH_1):PAGE150_I216@MSTR_DISCRETE.RES(CHIPS)':
 'A': CDS_PINID='A';
NODE_NAME     R25W151 1
 '@BASEBOARD_FAB2_LIB.BASEBOARD_FAB2(SCH_1):PAGE150_I232@MSTR_DISCRETE.RES(CHIPS)':
 'A': CDS_PINID='A';
NODE_NAME     R25W149 1
 '@BASEBOARD_FAB2_LIB.BASEBOARD_FAB2(SCH_1):PAGE150_I219@MSTR_DISCRETE.RES(CHIPS)':
 'A': CDS_PINID='A';
NODE_NAME     R25W150 1
 '@BASEBOARD_FAB2_LIB.BASEBOARD_FAB2(SCH_1):PAGE150_I229@MSTR_DISCRETE.RES(CHIPS)':
 'A': CDS_PINID='A';
NODE_NAME     R25W152 1
 '@BASEBOARD_FAB2_LIB.BASEBOARD_FAB2(SCH_1):PAGE150_I234@MSTR_DISCRETE.RES(CHIPS)':
 'A': CDS_PINID='A';
NODE_NAME     R25W118 2
 '@BASEBOARD_FAB2_LIB.BASEBOARD_FAB2(SCH_1):PAGE151_I211@MSTR_DISCRETE.RES(CHIPS)':
 'B': CDS_PINID='B';
NODE_NAME     J1E1 3_1
 '@BASEBOARD_FAB2_LIB.BASEBOARD_FAB2(SCH_1):PAGE195_I114@W_HDL.FCI-CONN12-2R-GP(CHIPS)':
 '3_1': CDS_PINID='\3_1\';
NODE_NAME     J1E1 3_2
 '@BASEBOARD_FAB2_LIB.BASEBOARD_FAB2(SCH_1):PAGE195_I114@W_HDL.FCI-CONN12-2R-GP(CHIPS)':
 '3_2': CDS_PINID='\3_2\';
NODE_NAME     J1E1 3_3
 '@BASEBOARD_FAB2_LIB.BASEBOARD_FAB2(SCH_1):PAGE195_I114@W_HDL.FCI-CONN12-2R-GP(CHIPS)':
 '3_3': CDS_PINID='\3_3\';
NODE_NAME     J1E1 4_1
 '@BASEBOARD_FAB2_LIB.BASEBOARD_FAB2(SCH_1):PAGE195_I114@W_HDL.FCI-CONN12-2R-GP(CHIPS)':
 '4_1': CDS_PINID='\4_1\';
NODE_NAME     J1E1 4_2
 '@BASEBOARD_FAB2_LIB.BASEBOARD_FAB2(SCH_1):PAGE195_I114@W_HDL.FCI-CONN12-2R-GP(CHIPS)':
 '4_2': CDS_PINID='\4_2\';
NODE_NAME     J1E1 4_3
 '@BASEBOARD_FAB2_LIB.BASEBOARD_FAB2(SCH_1):PAGE195_I114@W_HDL.FCI-CONN12-2R-GP(CHIPS)':
 '4_3': CDS_PINID='\4_3\';
NODE_NAME     J1D1 3_1
 '@BASEBOARD_FAB2_LIB.BASEBOARD_FAB2(SCH_1):PAGE195_I115@W_HDL.FCI-CONN12-2R-GP(CHIPS)':
 '3_1': CDS_PINID='\3_1\';
NODE_NAME     J1D1 3_2
 '@BASEBOARD_FAB2_LIB.BASEBOARD_FAB2(SCH_1):PAGE195_I115@W_HDL.FCI-CONN12-2R-GP(CHIPS)':
 '3_2': CDS_PINID='\3_2\';
NODE_NAME     J1D1 3_3
 '@BASEBOARD_FAB2_LIB.BASEBOARD_FAB2(SCH_1):PAGE195_I115@W_HDL.FCI-CONN12-2R-GP(CHIPS)':
 '3_3': CDS_PINID='\3_3\';
NODE_NAME     J1D1 4_1
 '@BASEBOARD_FAB2_LIB.BASEBOARD_FAB2(SCH_1):PAGE195_I115@W_HDL.FCI-CONN12-2R-GP(CHIPS)':
 '4_1': CDS_PINID='\4_1\';
NODE_NAME     J1D1 4_2
 '@BASEBOARD_FAB2_LIB.BASEBOARD_FAB2(SCH_1):PAGE195_I115@W_HDL.FCI-CONN12-2R-GP(CHIPS)':
 '4_2': CDS_PINID='\4_2\';
NODE_NAME     J1D1 4_3
 '@BASEBOARD_FAB2_LIB.BASEBOARD_FAB2(SCH_1):PAGE195_I115@W_HDL.FCI-CONN12-2R-GP(CHIPS)':
 '4_3': CDS_PINID='\4_3\';
NODE_NAME     J30W1 A1
 '@BASEBOARD_FAB2_LIB.BASEBOARD_FAB2(SCH_1):PAGE253_I26@W_HDL.SKT-USB32-8-GP(CHIPS)':
 'GND'<0>: CDS_PINID='GND(0)';
NODE_NAME     J30W1 A12
 '@BASEBOARD_FAB2_LIB.BASEBOARD_FAB2(SCH_1):PAGE253_I26@W_HDL.SKT-USB32-8-GP(CHIPS)':
 'GND'<1>: CDS_PINID='GND(1)';
NODE_NAME     J30W1 B1
 '@BASEBOARD_FAB2_LIB.BASEBOARD_FAB2(SCH_1):PAGE253_I26@W_HDL.SKT-USB32-8-GP(CHIPS)':
 'GND'<2>: CDS_PINID='GND(2)';
NODE_NAME     J30W1 B12
 '@BASEBOARD_FAB2_LIB.BASEBOARD_FAB2(SCH_1):PAGE253_I26@W_HDL.SKT-USB32-8-GP(CHIPS)':
 'GND'<3>: CDS_PINID='GND(3)';
NODE_NAME     J30W1 PTH1
 '@BASEBOARD_FAB2_LIB.BASEBOARD_FAB2(SCH_1):PAGE253_I26@W_HDL.SKT-USB32-8-GP(CHIPS)':
 'PTH1': CDS_PINID='PTH1';
NODE_NAME     J30W1 PTH2
 '@BASEBOARD_FAB2_LIB.BASEBOARD_FAB2(SCH_1):PAGE253_I26@W_HDL.SKT-USB32-8-GP(CHIPS)':
 'PTH2': CDS_PINID='PTH2';
NODE_NAME     J30W1 PTH3
 '@BASEBOARD_FAB2_LIB.BASEBOARD_FAB2(SCH_1):PAGE253_I26@W_HDL.SKT-USB32-8-GP(CHIPS)':
 'PTH3': CDS_PINID='PTH3';
NODE_NAME     J30W1 PTH4
 '@BASEBOARD_FAB2_LIB.BASEBOARD_FAB2(SCH_1):PAGE253_I26@W_HDL.SKT-USB32-8-GP(CHIPS)':
 'PTH4': CDS_PINID='PTH4';
NODE_NAME     J30W1 PTH5
 '@BASEBOARD_FAB2_LIB.BASEBOARD_FAB2(SCH_1):PAGE253_I26@W_HDL.SKT-USB32-8-GP(CHIPS)':
 'PTH5': CDS_PINID='PTH5';
NODE_NAME     J30W1 PTH6
 '@BASEBOARD_FAB2_LIB.BASEBOARD_FAB2(SCH_1):PAGE253_I26@W_HDL.SKT-USB32-8-GP(CHIPS)':
 'PTH6': CDS_PINID='PTH6';
NODE_NAME     J30W1 PTH7
 '@BASEBOARD_FAB2_LIB.BASEBOARD_FAB2(SCH_1):PAGE253_I26@W_HDL.SKT-USB32-8-GP(CHIPS)':
 'PTH7': CDS_PINID='PTH7';
NODE_NAME     J30W1 PTH8
 '@BASEBOARD_FAB2_LIB.BASEBOARD_FAB2(SCH_1):PAGE253_I26@W_HDL.SKT-USB32-8-GP(CHIPS)':
 'PTH8': CDS_PINID='PTH8';
NODE_NAME     R25W94 1
 '@BASEBOARD_FAB2_LIB.BASEBOARD_FAB2(SCH_1):PAGE137_I140@MSTR_DISCRETE.RES(CHIPS)':
 'A': CDS_PINID='A';
NODE_NAME     R6W2 2
 '@BASEBOARD_FAB2_LIB.BASEBOARD_FAB2(SCH_1):PAGE137_I144@MSTR_DISCRETE.RES(CHIPS)':
 'B': CDS_PINID='B';
NODE_NAME     C7G3 2
 '@BASEBOARD_FAB2_LIB.BASEBOARD_FAB2(SCH_1):PAGE215_I22@MSTR_DISCRETE.CAP(CHIPS)':
 'B': CDS_PINID='B';
NODE_NAME     C7F17 2
 '@BASEBOARD_FAB2_LIB.BASEBOARD_FAB2(SCH_1):PAGE215_I34@DEV_DISCRETE.CAP_A(CHIPS)':
 'B': CDS_PINID='B';
NODE_NAME     C7F18 2
 '@BASEBOARD_FAB2_LIB.BASEBOARD_FAB2(SCH_1):PAGE215_I35@DEV_DISCRETE.CAP_A(CHIPS)':
 'B': CDS_PINID='B';
NODE_NAME     C7F15 2
 '@BASEBOARD_FAB2_LIB.BASEBOARD_FAB2(SCH_1):PAGE215_I38@DEV_DISCRETE.CAP_A(CHIPS)':
 'B': CDS_PINID='B';
NODE_NAME     C7F16 2
 '@BASEBOARD_FAB2_LIB.BASEBOARD_FAB2(SCH_1):PAGE215_I40@DEV_DISCRETE.CAP_A(CHIPS)':
 'B': CDS_PINID='B';
NODE_NAME     C7F14 2
 '@BASEBOARD_FAB2_LIB.BASEBOARD_FAB2(SCH_1):PAGE215_I44@MSTR_DISCRETE.CAP(CHIPS)':
 'B': CDS_PINID='B';
NODE_NAME     EU7G1 32
 '@BASEBOARD_FAB2_LIB.BASEBOARD_FAB2(SCH_1):PAGE215_I69@MSTR_CONTROLLER.PXM1310B(CHIPS)':
 'BISEN1': CDS_PINID='BISEN1';
NODE_NAME     EU7G1 27
 '@BASEBOARD_FAB2_LIB.BASEBOARD_FAB2(SCH_1):PAGE215_I69@MSTR_CONTROLLER.PXM1310B(CHIPS)':
 'GND': CDS_PINID='GND';
NODE_NAME     EU7G1 41
 '@BASEBOARD_FAB2_LIB.BASEBOARD_FAB2(SCH_1):PAGE215_I69@MSTR_CONTROLLER.PXM1310B(CHIPS)':
 'THPAD': CDS_PINID='THPAD';
NODE_NAME     C4G23 2
 '@BASEBOARD_FAB2_LIB.BASEBOARD_FAB2(SCH_1):PAGE221_I2@MSTR_DISCRETE.CAP(CHIPS)':
 'B': CDS_PINID='B';
NODE_NAME     C6U12 2
 '@BASEBOARD_FAB2_LIB.BASEBOARD_FAB2(SCH_1):PAGE221_I11@MSTR_DISCRETE.CAP(CHIPS)':
 'B': CDS_PINID='B';
NODE_NAME     C4G15 2
 '@BASEBOARD_FAB2_LIB.BASEBOARD_FAB2(SCH_1):PAGE221_I13@MSTR_DISCRETE.CAP(CHIPS)':
 'B': CDS_PINID='B';
NODE_NAME     C6U15 2
 '@BASEBOARD_FAB2_LIB.BASEBOARD_FAB2(SCH_1):PAGE221_I18@MSTR_DISCRETE.CAP(CHIPS)':
 'B': CDS_PINID='B';
NODE_NAME     C6U16 2
 '@BASEBOARD_FAB2_LIB.BASEBOARD_FAB2(SCH_1):PAGE221_I19@MSTR_DISCRETE.CAP(CHIPS)':
 'B': CDS_PINID='B';
NODE_NAME     C4G14 2
 '@BASEBOARD_FAB2_LIB.BASEBOARD_FAB2(SCH_1):PAGE221_I30@MSTR_DISCRETE.CAP(CHIPS)':
 'B': CDS_PINID='B';
NODE_NAME     EU4G3 3
 '@BASEBOARD_FAB2_LIB.BASEBOARD_FAB2(SCH_1):PAGE221_I15@MSTR_VREG.MIC5166(CHIPS)':
 'AGND': CDS_PINID='AGND';
NODE_NAME     EU4G3 8
 '@BASEBOARD_FAB2_LIB.BASEBOARD_FAB2(SCH_1):PAGE221_I15@MSTR_VREG.MIC5166(CHIPS)':
 'PGND': CDS_PINID='PGND';
NODE_NAME     EU4G3 11
 '@BASEBOARD_FAB2_LIB.BASEBOARD_FAB2(SCH_1):PAGE221_I15@MSTR_VREG.MIC5166(CHIPS)':
 'THPAD': CDS_PINID='THPAD';
NODE_NAME     C7B2 2
 '@BASEBOARD_FAB2_LIB.BASEBOARD_FAB2(SCH_1):PAGE218_I28@DEV_DISCRETE.CAP_A(CHIPS)':
 'B': CDS_PINID='B';
NODE_NAME     C7B1 2
 '@BASEBOARD_FAB2_LIB.BASEBOARD_FAB2(SCH_1):PAGE218_I30@DEV_DISCRETE.CAP_A(CHIPS)':
 'B': CDS_PINID='B';
NODE_NAME     C7A38 2
 '@BASEBOARD_FAB2_LIB.BASEBOARD_FAB2(SCH_1):PAGE218_I38@DEV_DISCRETE.CAP_A(CHIPS)':
 'B': CDS_PINID='B';
NODE_NAME     C7B3 2
 '@BASEBOARD_FAB2_LIB.BASEBOARD_FAB2(SCH_1):PAGE218_I41@MSTR_DISCRETE.CAP(CHIPS)':
 'B': CDS_PINID='B';
NODE_NAME     EU7A5 32
 '@BASEBOARD_FAB2_LIB.BASEBOARD_FAB2(SCH_1):PAGE218_I69@MSTR_CONTROLLER.PXM1310B(CHIPS)':
 'BISEN1': CDS_PINID='BISEN1';
NODE_NAME     EU7A5 27
 '@BASEBOARD_FAB2_LIB.BASEBOARD_FAB2(SCH_1):PAGE218_I69@MSTR_CONTROLLER.PXM1310B(CHIPS)':
 'GND': CDS_PINID='GND';
NODE_NAME     EU7A5 41
 '@BASEBOARD_FAB2_LIB.BASEBOARD_FAB2(SCH_1):PAGE218_I69@MSTR_CONTROLLER.PXM1310B(CHIPS)':
 'THPAD': CDS_PINID='THPAD';
NODE_NAME     C7A29 2
 '@BASEBOARD_FAB2_LIB.BASEBOARD_FAB2(SCH_1):PAGE218_I16@MSTR_DISCRETE.CAP(CHIPS)':
 'B': CDS_PINID='B';
NODE_NAME     C7A37 2
 '@BASEBOARD_FAB2_LIB.BASEBOARD_FAB2(SCH_1):PAGE218_I40@DEV_DISCRETE.CAP_A(CHIPS)':
 'B': CDS_PINID='B';
NODE_NAME     C4A2 2
 '@BASEBOARD_FAB2_LIB.BASEBOARD_FAB2(SCH_1):PAGE222_I2@MSTR_DISCRETE.CAP(CHIPS)':
 'B': CDS_PINID='B';
NODE_NAME     C4A11 2
 '@BASEBOARD_FAB2_LIB.BASEBOARD_FAB2(SCH_1):PAGE222_I9@MSTR_DISCRETE.CAP(CHIPS)':
 'B': CDS_PINID='B';
NODE_NAME     EU4A1 3
 '@BASEBOARD_FAB2_LIB.BASEBOARD_FAB2(SCH_1):PAGE222_I13@MSTR_VREG.MIC5166(CHIPS)':
 'AGND': CDS_PINID='AGND';
NODE_NAME     EU4A1 8
 '@BASEBOARD_FAB2_LIB.BASEBOARD_FAB2(SCH_1):PAGE222_I13@MSTR_VREG.MIC5166(CHIPS)':
 'PGND': CDS_PINID='PGND';
NODE_NAME     EU4A1 11
 '@BASEBOARD_FAB2_LIB.BASEBOARD_FAB2(SCH_1):PAGE222_I13@MSTR_VREG.MIC5166(CHIPS)':
 'THPAD': CDS_PINID='THPAD';
NODE_NAME     C6L4 2
 '@BASEBOARD_FAB2_LIB.BASEBOARD_FAB2(SCH_1):PAGE222_I15@MSTR_DISCRETE.CAP(CHIPS)':
 'B': CDS_PINID='B';
NODE_NAME     C6L3 2
 '@BASEBOARD_FAB2_LIB.BASEBOARD_FAB2(SCH_1):PAGE222_I17@MSTR_DISCRETE.CAP(CHIPS)':
 'B': CDS_PINID='B';
NODE_NAME     C4A9 2
 '@BASEBOARD_FAB2_LIB.BASEBOARD_FAB2(SCH_1):PAGE222_I20@MSTR_DISCRETE.CAP(CHIPS)':
 'B': CDS_PINID='B';
NODE_NAME     C4A12 2
 '@BASEBOARD_FAB2_LIB.BASEBOARD_FAB2(SCH_1):PAGE222_I22@MSTR_DISCRETE.CAP(CHIPS)':
 'B': CDS_PINID='B';
NODE_NAME     C1G25 2
 '@BASEBOARD_FAB2_LIB.BASEBOARD_FAB2(SCH_1):PAGE223_I35@DEV_DISCRETE.CAP_A(CHIPS)':
 'B': CDS_PINID='B';
NODE_NAME     C1G21 2
 '@BASEBOARD_FAB2_LIB.BASEBOARD_FAB2(SCH_1):PAGE223_I40@MSTR_DISCRETE.CAP(CHIPS)':
 'B': CDS_PINID='B';
NODE_NAME     C1G22 2
 '@BASEBOARD_FAB2_LIB.BASEBOARD_FAB2(SCH_1):PAGE223_I43@DEV_DISCRETE.CAP_A(CHIPS)':
 'B': CDS_PINID='B';
NODE_NAME     EU1G2 32
 '@BASEBOARD_FAB2_LIB.BASEBOARD_FAB2(SCH_1):PAGE223_I69@MSTR_CONTROLLER.PXM1310B(CHIPS)':
 'BISEN1': CDS_PINID='BISEN1';
NODE_NAME     EU1G2 27
 '@BASEBOARD_FAB2_LIB.BASEBOARD_FAB2(SCH_1):PAGE223_I69@MSTR_CONTROLLER.PXM1310B(CHIPS)':
 'GND': CDS_PINID='GND';
NODE_NAME     EU1G2 41
 '@BASEBOARD_FAB2_LIB.BASEBOARD_FAB2(SCH_1):PAGE223_I69@MSTR_CONTROLLER.PXM1310B(CHIPS)':
 'THPAD': CDS_PINID='THPAD';
NODE_NAME     C1G24 2
 '@BASEBOARD_FAB2_LIB.BASEBOARD_FAB2(SCH_1):PAGE223_I27@MSTR_DISCRETE.CAP(CHIPS)':
 'B': CDS_PINID='B';
NODE_NAME     C1G27 2
 '@BASEBOARD_FAB2_LIB.BASEBOARD_FAB2(SCH_1):PAGE223_I36@DEV_DISCRETE.CAP_A(CHIPS)':
 'B': CDS_PINID='B';
NODE_NAME     C4G12 2
 '@BASEBOARD_FAB2_LIB.BASEBOARD_FAB2(SCH_1):PAGE229_I2@MSTR_DISCRETE.CAP(CHIPS)':
 'B': CDS_PINID='B';
NODE_NAME     C6U13 2
 '@BASEBOARD_FAB2_LIB.BASEBOARD_FAB2(SCH_1):PAGE229_I11@MSTR_DISCRETE.CAP(CHIPS)':
 'B': CDS_PINID='B';
NODE_NAME     C4G18 2
 '@BASEBOARD_FAB2_LIB.BASEBOARD_FAB2(SCH_1):PAGE229_I16@MSTR_DISCRETE.CAP(CHIPS)':
 'B': CDS_PINID='B';
NODE_NAME     C6U14 2
 '@BASEBOARD_FAB2_LIB.BASEBOARD_FAB2(SCH_1):PAGE229_I18@MSTR_DISCRETE.CAP(CHIPS)':
 'B': CDS_PINID='B';
NODE_NAME     C4G20 2
 '@BASEBOARD_FAB2_LIB.BASEBOARD_FAB2(SCH_1):PAGE229_I23@MSTR_DISCRETE.CAP(CHIPS)':
 'B': CDS_PINID='B';
NODE_NAME     C4G13 2
 '@BASEBOARD_FAB2_LIB.BASEBOARD_FAB2(SCH_1):PAGE229_I26@MSTR_DISCRETE.CAP(CHIPS)':
 'B': CDS_PINID='B';
NODE_NAME     C2F2 2
 '@BASEBOARD_FAB2_LIB.BASEBOARD_FAB2(SCH_1):PAGE229_I28@DEV_DISCRETE.CAP_A(CHIPS)':
 'B': CDS_PINID='B';
NODE_NAME     EU4G2 3
 '@BASEBOARD_FAB2_LIB.BASEBOARD_FAB2(SCH_1):PAGE229_I37@MSTR_VREG.MIC5166(CHIPS)':
 'AGND': CDS_PINID='AGND';
NODE_NAME     EU4G2 8
 '@BASEBOARD_FAB2_LIB.BASEBOARD_FAB2(SCH_1):PAGE229_I37@MSTR_VREG.MIC5166(CHIPS)':
 'PGND': CDS_PINID='PGND';
NODE_NAME     EU4G2 11
 '@BASEBOARD_FAB2_LIB.BASEBOARD_FAB2(SCH_1):PAGE229_I37@MSTR_VREG.MIC5166(CHIPS)':
 'THPAD': CDS_PINID='THPAD';
NODE_NAME     C6U11 2
 '@BASEBOARD_FAB2_LIB.BASEBOARD_FAB2(SCH_1):PAGE229_I14@MSTR_DISCRETE.CAP(CHIPS)':
 'B': CDS_PINID='B';
NODE_NAME     C1B6 2
 '@BASEBOARD_FAB2_LIB.BASEBOARD_FAB2(SCH_1):PAGE226_I38@DEV_DISCRETE.CAP_A(CHIPS)':
 'B': CDS_PINID='B';
NODE_NAME     C1B4 2
 '@BASEBOARD_FAB2_LIB.BASEBOARD_FAB2(SCH_1):PAGE226_I40@MSTR_DISCRETE.CAP(CHIPS)':
 'B': CDS_PINID='B';
NODE_NAME     C1B3 2
 '@BASEBOARD_FAB2_LIB.BASEBOARD_FAB2(SCH_1):PAGE226_I45@DEV_DISCRETE.CAP_A(CHIPS)':
 'B': CDS_PINID='B';
NODE_NAME     EU1B1 32
 '@BASEBOARD_FAB2_LIB.BASEBOARD_FAB2(SCH_1):PAGE226_I69@MSTR_CONTROLLER.PXM1310B(CHIPS)':
 'BISEN1': CDS_PINID='BISEN1';
NODE_NAME     EU1B1 27
 '@BASEBOARD_FAB2_LIB.BASEBOARD_FAB2(SCH_1):PAGE226_I69@MSTR_CONTROLLER.PXM1310B(CHIPS)':
 'GND': CDS_PINID='GND';
NODE_NAME     EU1B1 41
 '@BASEBOARD_FAB2_LIB.BASEBOARD_FAB2(SCH_1):PAGE226_I69@MSTR_CONTROLLER.PXM1310B(CHIPS)':
 'THPAD': CDS_PINID='THPAD';
NODE_NAME     C1B11 2
 '@BASEBOARD_FAB2_LIB.BASEBOARD_FAB2(SCH_1):PAGE226_I23@MSTR_DISCRETE.CAP(CHIPS)':
 'B': CDS_PINID='B';
NODE_NAME     C1B5 2
 '@BASEBOARD_FAB2_LIB.BASEBOARD_FAB2(SCH_1):PAGE226_I32@DEV_DISCRETE.CAP_A(CHIPS)':
 'B': CDS_PINID='B';
NODE_NAME     Q12W2 5
 '@BASEBOARD_FAB2_LIB.BASEBOARD_FAB2(SCH_1):PAGE197_I19@W_HDL.BSL308C-H6327-GP(CHIPS)':
 'SOURCE#5': CDS_PINID='\source#5\';
NODE_NAME     Q12W4 5
 '@BASEBOARD_FAB2_LIB.BASEBOARD_FAB2(SCH_1):PAGE197_I35@W_HDL.BSL308C-H6327-GP(CHIPS)':
 'SOURCE#5': CDS_PINID='\source#5\';
NODE_NAME     Q12W1 5
 '@BASEBOARD_FAB2_LIB.BASEBOARD_FAB2(SCH_1):PAGE197_I43@W_HDL.BSL308C-H6327-GP(CHIPS)':
 'SOURCE#5': CDS_PINID='\source#5\';
NODE_NAME     C9T8 2
 '@BASEBOARD_FAB2_LIB.BASEBOARD_FAB2(SCH_1):PAGE197_I56@MSTR_DISCRETE.CAP(CHIPS)':
 'B': CDS_PINID='B';
NODE_NAME     C1A4 2
 '@BASEBOARD_FAB2_LIB.BASEBOARD_FAB2(SCH_1):PAGE197_I60@MSTR_DISCRETE.CAP(CHIPS)':
 'B': CDS_PINID='B';
NODE_NAME     C9U11 2
 '@BASEBOARD_FAB2_LIB.BASEBOARD_FAB2(SCH_1):PAGE197_I63@MSTR_DISCRETE.CAP(CHIPS)':
 'B': CDS_PINID='B';
NODE_NAME     C9U8 2
 '@BASEBOARD_FAB2_LIB.BASEBOARD_FAB2(SCH_1):PAGE197_I66@MSTR_DISCRETE.CAP(CHIPS)':
 'B': CDS_PINID='B';
NODE_NAME     C6U18 2
 '@BASEBOARD_FAB2_LIB.BASEBOARD_FAB2(SCH_1):PAGE197_I69@MSTR_DISCRETE.CAP(CHIPS)':
 'B': CDS_PINID='B';
NODE_NAME     C6T2 2
 '@BASEBOARD_FAB2_LIB.BASEBOARD_FAB2(SCH_1):PAGE197_I71@MSTR_DISCRETE.CAP(CHIPS)':
 'B': CDS_PINID='B';
NODE_NAME     C1B7 2
 '@BASEBOARD_FAB2_LIB.BASEBOARD_FAB2(SCH_1):PAGE197_I72@MSTR_DISCRETE.CAP(CHIPS)':
 'B': CDS_PINID='B';
NODE_NAME     C1A16 2
 '@BASEBOARD_FAB2_LIB.BASEBOARD_FAB2(SCH_1):PAGE197_I75@MSTR_DISCRETE.CAP(CHIPS)':
 'B': CDS_PINID='B';
NODE_NAME     C4B11 2
 '@BASEBOARD_FAB2_LIB.BASEBOARD_FAB2(SCH_1):PAGE197_I78@MSTR_DISCRETE.CAP(CHIPS)':
 'B': CDS_PINID='B';
NODE_NAME     C4A4 2
 '@BASEBOARD_FAB2_LIB.BASEBOARD_FAB2(SCH_1):PAGE197_I81@MSTR_DISCRETE.CAP(CHIPS)':
 'B': CDS_PINID='B';
NODE_NAME     C6U10 2
 '@BASEBOARD_FAB2_LIB.BASEBOARD_FAB2(SCH_1):PAGE197_I84@MSTR_DISCRETE.CAP(CHIPS)':
 'B': CDS_PINID='B';
NODE_NAME     C4A17 2
 '@BASEBOARD_FAB2_LIB.BASEBOARD_FAB2(SCH_1):PAGE197_I88@MSTR_DISCRETE.CAP(CHIPS)':
 'B': CDS_PINID='B';
NODE_NAME     Q12W3 5
 '@BASEBOARD_FAB2_LIB.BASEBOARD_FAB2(SCH_1):PAGE197_I91@W_HDL.BSL308C-H6327-GP(CHIPS)':
 'SOURCE#5': CDS_PINID='\source#5\';
NODE_NAME     C4A6 2
 '@BASEBOARD_FAB2_LIB.BASEBOARD_FAB2(SCH_1):PAGE230_I2@MSTR_DISCRETE.CAP(CHIPS)':
 'B': CDS_PINID='B';
NODE_NAME     C4A7 2
 '@BASEBOARD_FAB2_LIB.BASEBOARD_FAB2(SCH_1):PAGE230_I10@MSTR_DISCRETE.CAP(CHIPS)':
 'B': CDS_PINID='B';
NODE_NAME     C4A8 2
 '@BASEBOARD_FAB2_LIB.BASEBOARD_FAB2(SCH_1):PAGE230_I12@MSTR_DISCRETE.CAP(CHIPS)':
 'B': CDS_PINID='B';
NODE_NAME     C4A13 2
 '@BASEBOARD_FAB2_LIB.BASEBOARD_FAB2(SCH_1):PAGE230_I20@MSTR_DISCRETE.CAP(CHIPS)':
 'B': CDS_PINID='B';
NODE_NAME     C4A3 2
 '@BASEBOARD_FAB2_LIB.BASEBOARD_FAB2(SCH_1):PAGE230_I23@MSTR_DISCRETE.CAP(CHIPS)':
 'B': CDS_PINID='B';
NODE_NAME     C8M12 2
 '@BASEBOARD_FAB2_LIB.BASEBOARD_FAB2(SCH_1):PAGE230_I24@DEV_DISCRETE.CAP_A(CHIPS)':
 'B': CDS_PINID='B';
NODE_NAME     C6L5 2
 '@BASEBOARD_FAB2_LIB.BASEBOARD_FAB2(SCH_1):PAGE230_I35@MSTR_DISCRETE.CAP(CHIPS)':
 'B': CDS_PINID='B';
NODE_NAME     C4A14 2
 '@BASEBOARD_FAB2_LIB.BASEBOARD_FAB2(SCH_1):PAGE230_I36@MSTR_DISCRETE.CAP(CHIPS)':
 'B': CDS_PINID='B';
NODE_NAME     C4A15 2
 '@BASEBOARD_FAB2_LIB.BASEBOARD_FAB2(SCH_1):PAGE230_I17@MSTR_DISCRETE.CAP(CHIPS)':
 'B': CDS_PINID='B';
NODE_NAME     EU4A2 3
 '@BASEBOARD_FAB2_LIB.BASEBOARD_FAB2(SCH_1):PAGE230_I37@MSTR_VREG.MIC5166(CHIPS)':
 'AGND': CDS_PINID='AGND';
NODE_NAME     EU4A2 8
 '@BASEBOARD_FAB2_LIB.BASEBOARD_FAB2(SCH_1):PAGE230_I37@MSTR_VREG.MIC5166(CHIPS)':
 'PGND': CDS_PINID='PGND';
NODE_NAME     EU4A2 11
 '@BASEBOARD_FAB2_LIB.BASEBOARD_FAB2(SCH_1):PAGE230_I37@MSTR_VREG.MIC5166(CHIPS)':
 'THPAD': CDS_PINID='THPAD';
NODE_NAME     C8E1 2
 '@BASEBOARD_FAB2_LIB.BASEBOARD_FAB2(SCH_1):PAGE181_I34@DEV_DISCRETE.CAP_A(CHIPS)':
 'B': CDS_PINID='B';
NODE_NAME     C2R6 2
 '@BASEBOARD_FAB2_LIB.BASEBOARD_FAB2(SCH_1):PAGE181_I40@MSTR_DISCRETE.CAP(CHIPS)':
 'B': CDS_PINID='B';
NODE_NAME     Q9T1 2
 '@BASEBOARD_FAB2_LIB.BASEBOARD_FAB2(SCH_1):PAGE181_I42@MSTR_DISCRETE.NPN(CHIPS)':
 'E': CDS_PINID='E';
NODE_NAME     R9T3 2
 '@BASEBOARD_FAB2_LIB.BASEBOARD_FAB2(SCH_1):PAGE181_I64@MSTR_DISCRETE.RES(CHIPS)':
 'B': CDS_PINID='B';
NODE_NAME     J1F3 8
 '@BASEBOARD_FAB2_LIB.BASEBOARD_FAB2(SCH_1):PAGE181_I106@MSTR_CONN.CONN8_H62179001(CHIPS)':
 'IO8': CDS_PINID='IO8';
NODE_NAME     C8E4 2
 '@BASEBOARD_FAB2_LIB.BASEBOARD_FAB2(SCH_1):PAGE241_I100@W_HDL.ST220U10VDM-LGP(CHIPS)':
 '2': CDS_PINID='\2\';
NODE_NAME     C9B9 2
 '@BASEBOARD_FAB2_LIB.BASEBOARD_FAB2(SCH_1):PAGE186_I357@W_HDL.SC1U10V2KX-4-GP(CHIPS)':
 '2': CDS_PINID='\2\';
NODE_NAME     C1C18 2
 '@BASEBOARD_FAB2_LIB.BASEBOARD_FAB2(SCH_1):PAGE209_I89@W_HDL.SC1U10V2KX-4-GP(CHIPS)':
 '2': CDS_PINID='\2\';
NODE_NAME     C1A11 2
 '@BASEBOARD_FAB2_LIB.BASEBOARD_FAB2(SCH_1):PAGE227_I147@W_HDL.SC1U10V2KX-4-GP(CHIPS)':
 '2': CDS_PINID='\2\';
NODE_NAME     C1A2 2
 '@BASEBOARD_FAB2_LIB.BASEBOARD_FAB2(SCH_1):PAGE227_I148@W_HDL.SC1U10V2KX-4-GP(CHIPS)':
 '2': CDS_PINID='\2\';
NODE_NAME     C1C3 2
 '@BASEBOARD_FAB2_LIB.BASEBOARD_FAB2(SCH_1):PAGE210_I73@W_HDL.SC1U10V2KX-4-GP(CHIPS)':
 '2': CDS_PINID='\2\';
NODE_NAME     C1D15 2
 '@BASEBOARD_FAB2_LIB.BASEBOARD_FAB2(SCH_1):PAGE208_I118@W_HDL.SC1U10V2KX-4-GP(CHIPS)':
 '2': CDS_PINID='\2\';
NODE_NAME     C1D5 2
 '@BASEBOARD_FAB2_LIB.BASEBOARD_FAB2(SCH_1):PAGE208_I119@W_HDL.SC1U10V2KX-4-GP(CHIPS)':
 '2': CDS_PINID='\2\';
NODE_NAME     C1E23 2
 '@BASEBOARD_FAB2_LIB.BASEBOARD_FAB2(SCH_1):PAGE207_I109@W_HDL.SC1U10V2KX-4-GP(CHIPS)':
 '2': CDS_PINID='\2\';
NODE_NAME     C1E6 2
 '@BASEBOARD_FAB2_LIB.BASEBOARD_FAB2(SCH_1):PAGE207_I110@W_HDL.SC1U10V2KX-4-GP(CHIPS)':
 '2': CDS_PINID='\2\';
NODE_NAME     C1F21 2
 '@BASEBOARD_FAB2_LIB.BASEBOARD_FAB2(SCH_1):PAGE224_I154@W_HDL.SC1U10V2KX-4-GP(CHIPS)':
 '2': CDS_PINID='\2\';
NODE_NAME     C1G4 2
 '@BASEBOARD_FAB2_LIB.BASEBOARD_FAB2(SCH_1):PAGE224_I155@W_HDL.SC1U10V2KX-4-GP(CHIPS)':
 '2': CDS_PINID='\2\';
NODE_NAME     C3L1 2
 '@BASEBOARD_FAB2_LIB.BASEBOARD_FAB2(SCH_1):PAGE236_I180@W_HDL.SC1U10V2KX-4-GP(CHIPS)':
 '2': CDS_PINID='\2\';
NODE_NAME     C3L29 2
 '@BASEBOARD_FAB2_LIB.BASEBOARD_FAB2(SCH_1):PAGE236_I181@W_HDL.SC1U10V2KX-4-GP(CHIPS)':
 '2': CDS_PINID='\2\';
NODE_NAME     C4C4 2
 '@BASEBOARD_FAB2_LIB.BASEBOARD_FAB2(SCH_1):PAGE205_I83@W_HDL.SC1U10V2KX-4-GP(CHIPS)':
 '2': CDS_PINID='\2\';
NODE_NAME     C4C14 2
 '@BASEBOARD_FAB2_LIB.BASEBOARD_FAB2(SCH_1):PAGE204_I113@W_HDL.SC1U10V2KX-4-GP(CHIPS)':
 '2': CDS_PINID='\2\';
NODE_NAME     C4D14 2
 '@BASEBOARD_FAB2_LIB.BASEBOARD_FAB2(SCH_1):PAGE203_I132@W_HDL.SC1U10V2KX-4-GP(CHIPS)':
 '2': CDS_PINID='\2\';
NODE_NAME     C4D6 2
 '@BASEBOARD_FAB2_LIB.BASEBOARD_FAB2(SCH_1):PAGE203_I133@W_HDL.SC1U10V2KX-4-GP(CHIPS)':
 '2': CDS_PINID='\2\';
NODE_NAME     C4E25 2
 '@BASEBOARD_FAB2_LIB.BASEBOARD_FAB2(SCH_1):PAGE202_I111@W_HDL.SC1U10V2KX-4-GP(CHIPS)':
 '2': CDS_PINID='\2\';
NODE_NAME     C4E6 2
 '@BASEBOARD_FAB2_LIB.BASEBOARD_FAB2(SCH_1):PAGE202_I112@W_HDL.SC1U10V2KX-4-GP(CHIPS)':
 '2': CDS_PINID='\2\';
NODE_NAME     C4E28 2
 '@BASEBOARD_FAB2_LIB.BASEBOARD_FAB2(SCH_1):PAGE214_I175@W_HDL.SC1U10V2KX-4-GP(CHIPS)':
 '2': CDS_PINID='\2\';
NODE_NAME     C7A18 2
 '@BASEBOARD_FAB2_LIB.BASEBOARD_FAB2(SCH_1):PAGE219_I151@W_HDL.SC1U10V2KX-4-GP(CHIPS)':
 '2': CDS_PINID='\2\';
NODE_NAME     C7A26 2
 '@BASEBOARD_FAB2_LIB.BASEBOARD_FAB2(SCH_1):PAGE219_I152@W_HDL.SC1U10V2KX-4-GP(CHIPS)':
 '2': CDS_PINID='\2\';
NODE_NAME     C7C20 2
 '@BASEBOARD_FAB2_LIB.BASEBOARD_FAB2(SCH_1):PAGE212_I143@W_HDL.SC1U10V2KX-4-GP(CHIPS)':
 '2': CDS_PINID='\2\';
NODE_NAME     C7G35 2
 '@BASEBOARD_FAB2_LIB.BASEBOARD_FAB2(SCH_1):PAGE216_I149@W_HDL.SC1U10V2KX-4-GP(CHIPS)':
 '2': CDS_PINID='\2\';
NODE_NAME     C7G42 2
 '@BASEBOARD_FAB2_LIB.BASEBOARD_FAB2(SCH_1):PAGE216_I150@W_HDL.SC1U10V2KX-4-GP(CHIPS)':
 '2': CDS_PINID='\2\';
NODE_NAME     J1F1 A2
 '@BASEBOARD_FAB2_LIB.BASEBOARD_FAB2(SCH_1):PAGE181_I134@W_HDL.DM-FCI-CONN76-8R-GP-U-01(CHIPS)':
 'GND1': CDS_PINID='GND1';
NODE_NAME     J1F1 A8
 '@BASEBOARD_FAB2_LIB.BASEBOARD_FAB2(SCH_1):PAGE181_I134@W_HDL.DM-FCI-CONN76-8R-GP-U-01(CHIPS)':
 'GND2': CDS_PINID='GND2';
NODE_NAME     J1F1 C1
 '@BASEBOARD_FAB2_LIB.BASEBOARD_FAB2(SCH_1):PAGE181_I134@W_HDL.DM-FCI-CONN76-8R-GP-U-01(CHIPS)':
 'GND3': CDS_PINID='GND3';
NODE_NAME     J1F1 C3
 '@BASEBOARD_FAB2_LIB.BASEBOARD_FAB2(SCH_1):PAGE181_I134@W_HDL.DM-FCI-CONN76-8R-GP-U-01(CHIPS)':
 'GND4': CDS_PINID='GND4';
NODE_NAME     J1F1 C5
 '@BASEBOARD_FAB2_LIB.BASEBOARD_FAB2(SCH_1):PAGE181_I134@W_HDL.DM-FCI-CONN76-8R-GP-U-01(CHIPS)':
 'GND5': CDS_PINID='GND5';
NODE_NAME     J1F1 C7
 '@BASEBOARD_FAB2_LIB.BASEBOARD_FAB2(SCH_1):PAGE181_I134@W_HDL.DM-FCI-CONN76-8R-GP-U-01(CHIPS)':
 'GND6': CDS_PINID='GND6';
NODE_NAME     J1F1 D2
 '@BASEBOARD_FAB2_LIB.BASEBOARD_FAB2(SCH_1):PAGE181_I134@W_HDL.DM-FCI-CONN76-8R-GP-U-01(CHIPS)':
 'GND7': CDS_PINID='GND7';
NODE_NAME     J1F1 D6
 '@BASEBOARD_FAB2_LIB.BASEBOARD_FAB2(SCH_1):PAGE181_I134@W_HDL.DM-FCI-CONN76-8R-GP-U-01(CHIPS)':
 'GND8': CDS_PINID='GND8';
NODE_NAME     J1F1 D8
 '@BASEBOARD_FAB2_LIB.BASEBOARD_FAB2(SCH_1):PAGE181_I134@W_HDL.DM-FCI-CONN76-8R-GP-U-01(CHIPS)':
 'GND9': CDS_PINID='GND9';
NODE_NAME     J1F1 F1
 '@BASEBOARD_FAB2_LIB.BASEBOARD_FAB2(SCH_1):PAGE181_I134@W_HDL.DM-FCI-CONN76-8R-GP-U-01(CHIPS)':
 'GND10': CDS_PINID='GND10';
NODE_NAME     J1F1 F3
 '@BASEBOARD_FAB2_LIB.BASEBOARD_FAB2(SCH_1):PAGE181_I134@W_HDL.DM-FCI-CONN76-8R-GP-U-01(CHIPS)':
 'GND11': CDS_PINID='GND11';
NODE_NAME     J1F1 F7
 '@BASEBOARD_FAB2_LIB.BASEBOARD_FAB2(SCH_1):PAGE181_I134@W_HDL.DM-FCI-CONN76-8R-GP-U-01(CHIPS)':
 'GND12': CDS_PINID='GND12';
NODE_NAME     J1F1 G2
 '@BASEBOARD_FAB2_LIB.BASEBOARD_FAB2(SCH_1):PAGE181_I134@W_HDL.DM-FCI-CONN76-8R-GP-U-01(CHIPS)':
 'GND13': CDS_PINID='GND13';
NODE_NAME     J1F1 G4
 '@BASEBOARD_FAB2_LIB.BASEBOARD_FAB2(SCH_1):PAGE181_I134@W_HDL.DM-FCI-CONN76-8R-GP-U-01(CHIPS)':
 'GND14': CDS_PINID='GND14';
NODE_NAME     J1F1 G6
 '@BASEBOARD_FAB2_LIB.BASEBOARD_FAB2(SCH_1):PAGE181_I134@W_HDL.DM-FCI-CONN76-8R-GP-U-01(CHIPS)':
 'GND15': CDS_PINID='GND15';
NODE_NAME     J1F1 G8
 '@BASEBOARD_FAB2_LIB.BASEBOARD_FAB2(SCH_1):PAGE181_I134@W_HDL.DM-FCI-CONN76-8R-GP-U-01(CHIPS)':
 'GND16': CDS_PINID='GND16';
NODE_NAME     J1F1 I1
 '@BASEBOARD_FAB2_LIB.BASEBOARD_FAB2(SCH_1):PAGE181_I134@W_HDL.DM-FCI-CONN76-8R-GP-U-01(CHIPS)':
 'GND17': CDS_PINID='GND17';
NODE_NAME     J1F1 I7
 '@BASEBOARD_FAB2_LIB.BASEBOARD_FAB2(SCH_1):PAGE181_I134@W_HDL.DM-FCI-CONN76-8R-GP-U-01(CHIPS)':
 'GND18': CDS_PINID='GND18';
NODE_NAME     J1F1 J2
 '@BASEBOARD_FAB2_LIB.BASEBOARD_FAB2(SCH_1):PAGE181_I134@W_HDL.DM-FCI-CONN76-8R-GP-U-01(CHIPS)':
 'J2': CDS_PINID='J2';
NODE_NAME     J1F1 J4
 '@BASEBOARD_FAB2_LIB.BASEBOARD_FAB2(SCH_1):PAGE181_I134@W_HDL.DM-FCI-CONN76-8R-GP-U-01(CHIPS)':
 'J4': CDS_PINID='J4';
NODE_NAME     J1F1 J6
 '@BASEBOARD_FAB2_LIB.BASEBOARD_FAB2(SCH_1):PAGE181_I134@W_HDL.DM-FCI-CONN76-8R-GP-U-01(CHIPS)':
 'J6': CDS_PINID='J6';
NODE_NAME     J1F1 J8
 '@BASEBOARD_FAB2_LIB.BASEBOARD_FAB2(SCH_1):PAGE181_I134@W_HDL.DM-FCI-CONN76-8R-GP-U-01(CHIPS)':
 'J8': CDS_PINID='J8';
NODE_NAME     J1C1 D4
 '@BASEBOARD_FAB2_LIB.BASEBOARD_FAB2(SCH_1):PAGE182_I79@W_HDL.DM-FCI-CONN76-8R-GP-U-01(CHIPS)':
 'FAN_TACH0': CDS_PINID='FAN_TACH0';
NODE_NAME     J1C1 A4
 '@BASEBOARD_FAB2_LIB.BASEBOARD_FAB2(SCH_1):PAGE182_I79@W_HDL.DM-FCI-CONN76-8R-GP-U-01(CHIPS)':
 'FAN_TACH3': CDS_PINID='FAN_TACH3';
NODE_NAME     J1C1 A2
 '@BASEBOARD_FAB2_LIB.BASEBOARD_FAB2(SCH_1):PAGE182_I79@W_HDL.DM-FCI-CONN76-8R-GP-U-01(CHIPS)':
 'GND1': CDS_PINID='GND1';
NODE_NAME     J1C1 A8
 '@BASEBOARD_FAB2_LIB.BASEBOARD_FAB2(SCH_1):PAGE182_I79@W_HDL.DM-FCI-CONN76-8R-GP-U-01(CHIPS)':
 'GND2': CDS_PINID='GND2';
NODE_NAME     J1C1 C1
 '@BASEBOARD_FAB2_LIB.BASEBOARD_FAB2(SCH_1):PAGE182_I79@W_HDL.DM-FCI-CONN76-8R-GP-U-01(CHIPS)':
 'GND3': CDS_PINID='GND3';
NODE_NAME     J1C1 C3
 '@BASEBOARD_FAB2_LIB.BASEBOARD_FAB2(SCH_1):PAGE182_I79@W_HDL.DM-FCI-CONN76-8R-GP-U-01(CHIPS)':
 'GND4': CDS_PINID='GND4';
NODE_NAME     J1C1 C5
 '@BASEBOARD_FAB2_LIB.BASEBOARD_FAB2(SCH_1):PAGE182_I79@W_HDL.DM-FCI-CONN76-8R-GP-U-01(CHIPS)':
 'GND5': CDS_PINID='GND5';
NODE_NAME     J1C1 C7
 '@BASEBOARD_FAB2_LIB.BASEBOARD_FAB2(SCH_1):PAGE182_I79@W_HDL.DM-FCI-CONN76-8R-GP-U-01(CHIPS)':
 'GND6': CDS_PINID='GND6';
NODE_NAME     J1C1 D2
 '@BASEBOARD_FAB2_LIB.BASEBOARD_FAB2(SCH_1):PAGE182_I79@W_HDL.DM-FCI-CONN76-8R-GP-U-01(CHIPS)':
 'GND7': CDS_PINID='GND7';
NODE_NAME     J1C1 D6
 '@BASEBOARD_FAB2_LIB.BASEBOARD_FAB2(SCH_1):PAGE182_I79@W_HDL.DM-FCI-CONN76-8R-GP-U-01(CHIPS)':
 'GND8': CDS_PINID='GND8';
NODE_NAME     J1C1 D8
 '@BASEBOARD_FAB2_LIB.BASEBOARD_FAB2(SCH_1):PAGE182_I79@W_HDL.DM-FCI-CONN76-8R-GP-U-01(CHIPS)':
 'GND9': CDS_PINID='GND9';
NODE_NAME     J1C1 F1
 '@BASEBOARD_FAB2_LIB.BASEBOARD_FAB2(SCH_1):PAGE182_I79@W_HDL.DM-FCI-CONN76-8R-GP-U-01(CHIPS)':
 'GND10': CDS_PINID='GND10';
NODE_NAME     J1C1 F3
 '@BASEBOARD_FAB2_LIB.BASEBOARD_FAB2(SCH_1):PAGE182_I79@W_HDL.DM-FCI-CONN76-8R-GP-U-01(CHIPS)':
 'GND11': CDS_PINID='GND11';
NODE_NAME     J1C1 F7
 '@BASEBOARD_FAB2_LIB.BASEBOARD_FAB2(SCH_1):PAGE182_I79@W_HDL.DM-FCI-CONN76-8R-GP-U-01(CHIPS)':
 'GND12': CDS_PINID='GND12';
NODE_NAME     J1C1 G2
 '@BASEBOARD_FAB2_LIB.BASEBOARD_FAB2(SCH_1):PAGE182_I79@W_HDL.DM-FCI-CONN76-8R-GP-U-01(CHIPS)':
 'GND13': CDS_PINID='GND13';
NODE_NAME     J1C1 G4
 '@BASEBOARD_FAB2_LIB.BASEBOARD_FAB2(SCH_1):PAGE182_I79@W_HDL.DM-FCI-CONN76-8R-GP-U-01(CHIPS)':
 'GND14': CDS_PINID='GND14';
NODE_NAME     J1C1 G6
 '@BASEBOARD_FAB2_LIB.BASEBOARD_FAB2(SCH_1):PAGE182_I79@W_HDL.DM-FCI-CONN76-8R-GP-U-01(CHIPS)':
 'GND15': CDS_PINID='GND15';
NODE_NAME     J1C1 G8
 '@BASEBOARD_FAB2_LIB.BASEBOARD_FAB2(SCH_1):PAGE182_I79@W_HDL.DM-FCI-CONN76-8R-GP-U-01(CHIPS)':
 'GND16': CDS_PINID='GND16';
NODE_NAME     J1C1 I1
 '@BASEBOARD_FAB2_LIB.BASEBOARD_FAB2(SCH_1):PAGE182_I79@W_HDL.DM-FCI-CONN76-8R-GP-U-01(CHIPS)':
 'GND17': CDS_PINID='GND17';
NODE_NAME     J1C1 I7
 '@BASEBOARD_FAB2_LIB.BASEBOARD_FAB2(SCH_1):PAGE182_I79@W_HDL.DM-FCI-CONN76-8R-GP-U-01(CHIPS)':
 'GND18': CDS_PINID='GND18';
NODE_NAME     J1C1 J2
 '@BASEBOARD_FAB2_LIB.BASEBOARD_FAB2(SCH_1):PAGE182_I79@W_HDL.DM-FCI-CONN76-8R-GP-U-01(CHIPS)':
 'J2': CDS_PINID='J2';
NODE_NAME     J1C1 J4
 '@BASEBOARD_FAB2_LIB.BASEBOARD_FAB2(SCH_1):PAGE182_I79@W_HDL.DM-FCI-CONN76-8R-GP-U-01(CHIPS)':
 'J4': CDS_PINID='J4';
NODE_NAME     J1C1 J6
 '@BASEBOARD_FAB2_LIB.BASEBOARD_FAB2(SCH_1):PAGE182_I79@W_HDL.DM-FCI-CONN76-8R-GP-U-01(CHIPS)':
 'J6': CDS_PINID='J6';
NODE_NAME     J1C1 J8
 '@BASEBOARD_FAB2_LIB.BASEBOARD_FAB2(SCH_1):PAGE182_I79@W_HDL.DM-FCI-CONN76-8R-GP-U-01(CHIPS)':
 'J8': CDS_PINID='J8';
NODE_NAME     J1C1 I3
 '@BASEBOARD_FAB2_LIB.BASEBOARD_FAB2(SCH_1):PAGE182_I79@W_HDL.DM-FCI-CONN76-8R-GP-U-01(CHIPS)':
 'MB_ON#': CDS_PINID='\mb_on#\';
NODE_NAME     J1C1 F5
 '@BASEBOARD_FAB2_LIB.BASEBOARD_FAB2(SCH_1):PAGE182_I79@W_HDL.DM-FCI-CONN76-8R-GP-U-01(CHIPS)':
 'MB_SLOT_ID0': CDS_PINID='MB_SLOT_ID0';
NODE_NAME     J1C1 I5
 '@BASEBOARD_FAB2_LIB.BASEBOARD_FAB2(SCH_1):PAGE182_I79@W_HDL.DM-FCI-CONN76-8R-GP-U-01(CHIPS)':
 'PCIE_PERST#': CDS_PINID='\pcie_perst#\';
NODE_NAME     J1C1 A6
 '@BASEBOARD_FAB2_LIB.BASEBOARD_FAB2(SCH_1):PAGE182_I79@W_HDL.DM-FCI-CONN76-8R-GP-U-01(CHIPS)':
 'PMBUS_ALERT#': CDS_PINID='\pmbus_alert#\';
NODE_NAME     CN8F1 2
 '@BASEBOARD_FAB2_LIB.BASEBOARD_FAB2(SCH_1):PAGE246_I21@DEV_DISCRETE.CAP_A(CHIPS)':
 'B': CDS_PINID='B';
NODE_NAME     C25W12 2
 '@BASEBOARD_FAB2_LIB.BASEBOARD_FAB2(SCH_1):PAGE151_I212@DEV_DISCRETE.CAP_A(CHIPS)':
 'B': CDS_PINID='B';
NODE_NAME     CN8F2 2
 '@BASEBOARD_FAB2_LIB.BASEBOARD_FAB2(SCH_1):PAGE246_I22@DEV_DISCRETE.CAP_A(CHIPS)':
 'B': CDS_PINID='B';
NODE_NAME     C25W11 2
 '@BASEBOARD_FAB2_LIB.BASEBOARD_FAB2(SCH_1):PAGE151_I214@DEV_DISCRETE.CAP_A(CHIPS)':
 'B': CDS_PINID='B';
NODE_NAME     C25W14 2
 '@BASEBOARD_FAB2_LIB.BASEBOARD_FAB2(SCH_1):PAGE151_I215@DEV_DISCRETE.CAP_A(CHIPS)':
 'B': CDS_PINID='B';
NODE_NAME     C25W15 2
 '@BASEBOARD_FAB2_LIB.BASEBOARD_FAB2(SCH_1):PAGE151_I216@DEV_DISCRETE.CAP_A(CHIPS)':
 'B': CDS_PINID='B';
NODE_NAME     C25W31 2
 '@BASEBOARD_FAB2_LIB.BASEBOARD_FAB2(SCH_1):PAGE149_I119@DEV_DISCRETE.CAP_A(CHIPS)':
 'B': CDS_PINID='B';
NODE_NAME     C25W34 2
 '@BASEBOARD_FAB2_LIB.BASEBOARD_FAB2(SCH_1):PAGE149_I120@DEV_DISCRETE.CAP_A(CHIPS)':
 'B': CDS_PINID='B';
NODE_NAME     C25W38 2
 '@BASEBOARD_FAB2_LIB.BASEBOARD_FAB2(SCH_1):PAGE149_I121@DEV_DISCRETE.CAP_A(CHIPS)':
 'B': CDS_PINID='B';
NODE_NAME     C25W45 2
 '@BASEBOARD_FAB2_LIB.BASEBOARD_FAB2(SCH_1):PAGE149_I122@DEV_DISCRETE.CAP_A(CHIPS)':
 'B': CDS_PINID='B';
NODE_NAME     C25W49 2
 '@BASEBOARD_FAB2_LIB.BASEBOARD_FAB2(SCH_1):PAGE149_I123@DEV_DISCRETE.CAP_A(CHIPS)':
 'B': CDS_PINID='B';
NODE_NAME     C25W55 2
 '@BASEBOARD_FAB2_LIB.BASEBOARD_FAB2(SCH_1):PAGE149_I124@DEV_DISCRETE.CAP_A(CHIPS)':
 'B': CDS_PINID='B';
NODE_NAME     C25W58 2
 '@BASEBOARD_FAB2_LIB.BASEBOARD_FAB2(SCH_1):PAGE149_I125@DEV_DISCRETE.CAP_A(CHIPS)':
 'B': CDS_PINID='B';
NODE_NAME     C25W61 2
 '@BASEBOARD_FAB2_LIB.BASEBOARD_FAB2(SCH_1):PAGE149_I126@DEV_DISCRETE.CAP_A(CHIPS)':
 'B': CDS_PINID='B';
NODE_NAME     C25W22 2
 '@BASEBOARD_FAB2_LIB.BASEBOARD_FAB2(SCH_1):PAGE143_I67@DEV_DISCRETE.CAP_A(CHIPS)':
 'B': CDS_PINID='B';
NODE_NAME     C25W68 2
 '@BASEBOARD_FAB2_LIB.BASEBOARD_FAB2(SCH_1):PAGE149_I128@DEV_DISCRETE.CAP_A(CHIPS)':
 'B': CDS_PINID='B';
NODE_NAME     C6W1 2
 '@BASEBOARD_FAB2_LIB.BASEBOARD_FAB2(SCH_1):PAGE247_I151@DEV_DISCRETE.CAP_A(CHIPS)':
 'B': CDS_PINID='B';
NODE_NAME     C6W10 2
 '@BASEBOARD_FAB2_LIB.BASEBOARD_FAB2(SCH_1):PAGE176_I139@DEV_DISCRETE.CAP_A(CHIPS)':
 'B': CDS_PINID='B';
NODE_NAME     C8W2 2
 '@BASEBOARD_FAB2_LIB.BASEBOARD_FAB2(SCH_1):PAGE249_I37@DEV_DISCRETE.CAP_A(CHIPS)':
 'B': CDS_PINID='B';
NODE_NAME     C25W13 2
 '@BASEBOARD_FAB2_LIB.BASEBOARD_FAB2(SCH_1):PAGE151_I217@DEV_DISCRETE.CAP_A(CHIPS)':
 'B': CDS_PINID='B';
NODE_NAME     U7W1 2
 '@BASEBOARD_FAB2_LIB.BASEBOARD_FAB2(SCH_1):PAGE166_I34@W_HDL.PI5A3157BC6E-GP(CHIPS)':
 'GND': CDS_PINID='GND';
NODE_NAME     C7W1 2
 '@BASEBOARD_FAB2_LIB.BASEBOARD_FAB2(SCH_1):PAGE166_I36@DEV_DISCRETE.CAP_A(CHIPS)':
 'B': CDS_PINID='B';
NODE_NAME     R7W2 2
 '@BASEBOARD_FAB2_LIB.BASEBOARD_FAB2(SCH_1):PAGE166_I42@MSTR_DISCRETE.RES(CHIPS)':
 'B': CDS_PINID='B';
NODE_NAME     C5D58 2
 '@BASEBOARD_FAB2_LIB.BASEBOARD_FAB2(SCH_1):PAGE217_I269@DEV_DISCRETE.CAP_A(CHIPS)':
 'B': CDS_PINID='B';
NODE_NAME     C5D61 2
 '@BASEBOARD_FAB2_LIB.BASEBOARD_FAB2(SCH_1):PAGE217_I270@DEV_DISCRETE.CAP_A(CHIPS)':
 'B': CDS_PINID='B';
NODE_NAME     C5D59 2
 '@BASEBOARD_FAB2_LIB.BASEBOARD_FAB2(SCH_1):PAGE217_I271@DEV_DISCRETE.CAP_A(CHIPS)':
 'B': CDS_PINID='B';
NODE_NAME     C5D60 2
 '@BASEBOARD_FAB2_LIB.BASEBOARD_FAB2(SCH_1):PAGE217_I272@DEV_DISCRETE.CAP_A(CHIPS)':
 'B': CDS_PINID='B';
NODE_NAME     C5D4 2
 '@BASEBOARD_FAB2_LIB.BASEBOARD_FAB2(SCH_1):PAGE220_I249@DEV_DISCRETE.CAP_A(CHIPS)':
 'B': CDS_PINID='B';
NODE_NAME     C5D3 2
 '@BASEBOARD_FAB2_LIB.BASEBOARD_FAB2(SCH_1):PAGE220_I250@DEV_DISCRETE.CAP_A(CHIPS)':
 'B': CDS_PINID='B';
NODE_NAME     C5D2 2
 '@BASEBOARD_FAB2_LIB.BASEBOARD_FAB2(SCH_1):PAGE220_I251@DEV_DISCRETE.CAP_A(CHIPS)':
 'B': CDS_PINID='B';
NODE_NAME     C5D1 2
 '@BASEBOARD_FAB2_LIB.BASEBOARD_FAB2(SCH_1):PAGE220_I252@DEV_DISCRETE.CAP_A(CHIPS)':
 'B': CDS_PINID='B';
NODE_NAME     C2D45 2
 '@BASEBOARD_FAB2_LIB.BASEBOARD_FAB2(SCH_1):PAGE225_I261@DEV_DISCRETE.CAP_A(CHIPS)':
 'B': CDS_PINID='B';
NODE_NAME     C3D25 2
 '@BASEBOARD_FAB2_LIB.BASEBOARD_FAB2(SCH_1):PAGE225_I262@DEV_DISCRETE.CAP_A(CHIPS)':
 'B': CDS_PINID='B';
NODE_NAME     C2D47 2
 '@BASEBOARD_FAB2_LIB.BASEBOARD_FAB2(SCH_1):PAGE225_I263@DEV_DISCRETE.CAP_A(CHIPS)':
 'B': CDS_PINID='B';
NODE_NAME     C2D46 2
 '@BASEBOARD_FAB2_LIB.BASEBOARD_FAB2(SCH_1):PAGE225_I264@DEV_DISCRETE.CAP_A(CHIPS)':
 'B': CDS_PINID='B';
NODE_NAME     C3D1 2
 '@BASEBOARD_FAB2_LIB.BASEBOARD_FAB2(SCH_1):PAGE228_I255@DEV_DISCRETE.CAP_A(CHIPS)':
 'B': CDS_PINID='B';
NODE_NAME     C2D3 2
 '@BASEBOARD_FAB2_LIB.BASEBOARD_FAB2(SCH_1):PAGE228_I256@DEV_DISCRETE.CAP_A(CHIPS)':
 'B': CDS_PINID='B';
NODE_NAME     C2D2 2
 '@BASEBOARD_FAB2_LIB.BASEBOARD_FAB2(SCH_1):PAGE228_I257@DEV_DISCRETE.CAP_A(CHIPS)':
 'B': CDS_PINID='B';
NODE_NAME     C2D1 2
 '@BASEBOARD_FAB2_LIB.BASEBOARD_FAB2(SCH_1):PAGE228_I258@DEV_DISCRETE.CAP_A(CHIPS)':
 'B': CDS_PINID='B';
NODE_NAME     C8W3 2
 '@BASEBOARD_FAB2_LIB.BASEBOARD_FAB2(SCH_1):PAGE42_I211@MSTR_DISCRETE.CAP(CHIPS)':
 'B': CDS_PINID='B';
NODE_NAME     RM1G1 1
 '@BASEBOARD_FAB2_LIB.BASEBOARD_FAB2(SCH_1):PAGE195_I117@W_HDL.STFT363B238R224H453-GP(CHIPS)':
 '1': CDS_PINID='\1\';
NODE_NAME     Q4W2 2
 '@BASEBOARD_FAB2_LIB.BASEBOARD_FAB2(SCH_1):PAGE102_I112@MSTR_DISCRETE.FET_N(CHIPS)':
 'SRC': CDS_PINID='SRC';
NODE_NAME     C5D54 2
 '@BASEBOARD_FAB2_LIB.BASEBOARD_FAB2(SCH_1):PAGE217_I279@DEV_DISCRETE.CAP_A(CHIPS)':
 'B': CDS_PINID='B';
NODE_NAME     C5D55 2
 '@BASEBOARD_FAB2_LIB.BASEBOARD_FAB2(SCH_1):PAGE217_I280@DEV_DISCRETE.CAP_A(CHIPS)':
 'B': CDS_PINID='B';
NODE_NAME     C5D56 2
 '@BASEBOARD_FAB2_LIB.BASEBOARD_FAB2(SCH_1):PAGE217_I281@DEV_DISCRETE.CAP_A(CHIPS)':
 'B': CDS_PINID='B';
NODE_NAME     C5D57 2
 '@BASEBOARD_FAB2_LIB.BASEBOARD_FAB2(SCH_1):PAGE217_I282@DEV_DISCRETE.CAP_A(CHIPS)':
 'B': CDS_PINID='B';
NODE_NAME     C5U2 2
 '@BASEBOARD_FAB2_LIB.BASEBOARD_FAB2(SCH_1):PAGE217_I283@DEV_DISCRETE.CAP_A(CHIPS)':
 'B': CDS_PINID='B';
NODE_NAME     C5U3 2
 '@BASEBOARD_FAB2_LIB.BASEBOARD_FAB2(SCH_1):PAGE217_I284@DEV_DISCRETE.CAP_A(CHIPS)':
 'B': CDS_PINID='B';
NODE_NAME     C5U4 2
 '@BASEBOARD_FAB2_LIB.BASEBOARD_FAB2(SCH_1):PAGE217_I285@DEV_DISCRETE.CAP_A(CHIPS)':
 'B': CDS_PINID='B';
NODE_NAME     C5U5 2
 '@BASEBOARD_FAB2_LIB.BASEBOARD_FAB2(SCH_1):PAGE217_I286@DEV_DISCRETE.CAP_A(CHIPS)':
 'B': CDS_PINID='B';
NODE_NAME     C5U6 2
 '@BASEBOARD_FAB2_LIB.BASEBOARD_FAB2(SCH_1):PAGE217_I287@DEV_DISCRETE.CAP_A(CHIPS)':
 'B': CDS_PINID='B';
NODE_NAME     C5U7 2
 '@BASEBOARD_FAB2_LIB.BASEBOARD_FAB2(SCH_1):PAGE217_I288@DEV_DISCRETE.CAP_A(CHIPS)':
 'B': CDS_PINID='B';
NODE_NAME     C5U8 2
 '@BASEBOARD_FAB2_LIB.BASEBOARD_FAB2(SCH_1):PAGE217_I289@DEV_DISCRETE.CAP_A(CHIPS)':
 'B': CDS_PINID='B';
NODE_NAME     C5U9 2
 '@BASEBOARD_FAB2_LIB.BASEBOARD_FAB2(SCH_1):PAGE217_I290@DEV_DISCRETE.CAP_A(CHIPS)':
 'B': CDS_PINID='B';
NODE_NAME     C5T12 2
 '@BASEBOARD_FAB2_LIB.BASEBOARD_FAB2(SCH_1):PAGE217_I291@DEV_DISCRETE.CAP_A(CHIPS)':
 'B': CDS_PINID='B';
NODE_NAME     C5T11 2
 '@BASEBOARD_FAB2_LIB.BASEBOARD_FAB2(SCH_1):PAGE217_I292@DEV_DISCRETE.CAP_A(CHIPS)':
 'B': CDS_PINID='B';
NODE_NAME     C5T10 2
 '@BASEBOARD_FAB2_LIB.BASEBOARD_FAB2(SCH_1):PAGE217_I293@DEV_DISCRETE.CAP_A(CHIPS)':
 'B': CDS_PINID='B';
NODE_NAME     C5T9 2
 '@BASEBOARD_FAB2_LIB.BASEBOARD_FAB2(SCH_1):PAGE217_I294@DEV_DISCRETE.CAP_A(CHIPS)':
 'B': CDS_PINID='B';
NODE_NAME     C5T8 2
 '@BASEBOARD_FAB2_LIB.BASEBOARD_FAB2(SCH_1):PAGE217_I295@DEV_DISCRETE.CAP_A(CHIPS)':
 'B': CDS_PINID='B';
NODE_NAME     C5T7 2
 '@BASEBOARD_FAB2_LIB.BASEBOARD_FAB2(SCH_1):PAGE217_I296@DEV_DISCRETE.CAP_A(CHIPS)':
 'B': CDS_PINID='B';
NODE_NAME     C5T6 2
 '@BASEBOARD_FAB2_LIB.BASEBOARD_FAB2(SCH_1):PAGE217_I297@DEV_DISCRETE.CAP_A(CHIPS)':
 'B': CDS_PINID='B';
NODE_NAME     C5T5 2
 '@BASEBOARD_FAB2_LIB.BASEBOARD_FAB2(SCH_1):PAGE217_I298@DEV_DISCRETE.CAP_A(CHIPS)':
 'B': CDS_PINID='B';
NODE_NAME     C5G11 2
 '@BASEBOARD_FAB2_LIB.BASEBOARD_FAB2(SCH_1):PAGE217_I299@DEV_DISCRETE.CAP_A(CHIPS)':
 'B': CDS_PINID='B';
NODE_NAME     C5G12 2
 '@BASEBOARD_FAB2_LIB.BASEBOARD_FAB2(SCH_1):PAGE217_I300@DEV_DISCRETE.CAP_A(CHIPS)':
 'B': CDS_PINID='B';
NODE_NAME     C5G2 2
 '@BASEBOARD_FAB2_LIB.BASEBOARD_FAB2(SCH_1):PAGE217_I301@DEV_DISCRETE.CAP_A(CHIPS)':
 'B': CDS_PINID='B';
NODE_NAME     C5G4 2
 '@BASEBOARD_FAB2_LIB.BASEBOARD_FAB2(SCH_1):PAGE217_I302@DEV_DISCRETE.CAP_A(CHIPS)':
 'B': CDS_PINID='B';
NODE_NAME     C5G13 2
 '@BASEBOARD_FAB2_LIB.BASEBOARD_FAB2(SCH_1):PAGE217_I303@DEV_DISCRETE.CAP_A(CHIPS)':
 'B': CDS_PINID='B';
NODE_NAME     C5G6 2
 '@BASEBOARD_FAB2_LIB.BASEBOARD_FAB2(SCH_1):PAGE217_I304@DEV_DISCRETE.CAP_A(CHIPS)':
 'B': CDS_PINID='B';
NODE_NAME     C5G5 2
 '@BASEBOARD_FAB2_LIB.BASEBOARD_FAB2(SCH_1):PAGE217_I305@DEV_DISCRETE.CAP_A(CHIPS)':
 'B': CDS_PINID='B';
NODE_NAME     C5G7 2
 '@BASEBOARD_FAB2_LIB.BASEBOARD_FAB2(SCH_1):PAGE217_I306@DEV_DISCRETE.CAP_A(CHIPS)':
 'B': CDS_PINID='B';
NODE_NAME     C5G1 2
 '@BASEBOARD_FAB2_LIB.BASEBOARD_FAB2(SCH_1):PAGE217_I307@DEV_DISCRETE.CAP_A(CHIPS)':
 'B': CDS_PINID='B';
NODE_NAME     C5G8 2
 '@BASEBOARD_FAB2_LIB.BASEBOARD_FAB2(SCH_1):PAGE217_I308@DEV_DISCRETE.CAP_A(CHIPS)':
 'B': CDS_PINID='B';
NODE_NAME     C5G18 2
 '@BASEBOARD_FAB2_LIB.BASEBOARD_FAB2(SCH_1):PAGE217_I309@DEV_DISCRETE.CAP_A(CHIPS)':
 'B': CDS_PINID='B';
NODE_NAME     C5G17 2
 '@BASEBOARD_FAB2_LIB.BASEBOARD_FAB2(SCH_1):PAGE217_I310@DEV_DISCRETE.CAP_A(CHIPS)':
 'B': CDS_PINID='B';
NODE_NAME     C5G14 2
 '@BASEBOARD_FAB2_LIB.BASEBOARD_FAB2(SCH_1):PAGE217_I311@DEV_DISCRETE.CAP_A(CHIPS)':
 'B': CDS_PINID='B';
NODE_NAME     C5G16 2
 '@BASEBOARD_FAB2_LIB.BASEBOARD_FAB2(SCH_1):PAGE217_I312@DEV_DISCRETE.CAP_A(CHIPS)':
 'B': CDS_PINID='B';
NODE_NAME     C5G15 2
 '@BASEBOARD_FAB2_LIB.BASEBOARD_FAB2(SCH_1):PAGE217_I313@DEV_DISCRETE.CAP_A(CHIPS)':
 'B': CDS_PINID='B';
NODE_NAME     C5G3 2
 '@BASEBOARD_FAB2_LIB.BASEBOARD_FAB2(SCH_1):PAGE217_I314@DEV_DISCRETE.CAP_A(CHIPS)':
 'B': CDS_PINID='B';
NODE_NAME     C5D9 2
 '@BASEBOARD_FAB2_LIB.BASEBOARD_FAB2(SCH_1):PAGE220_I258@DEV_DISCRETE.CAP_A(CHIPS)':
 'B': CDS_PINID='B';
NODE_NAME     C5D6 2
 '@BASEBOARD_FAB2_LIB.BASEBOARD_FAB2(SCH_1):PAGE220_I259@DEV_DISCRETE.CAP_A(CHIPS)':
 'B': CDS_PINID='B';
NODE_NAME     C5D7 2
 '@BASEBOARD_FAB2_LIB.BASEBOARD_FAB2(SCH_1):PAGE220_I260@DEV_DISCRETE.CAP_A(CHIPS)':
 'B': CDS_PINID='B';
NODE_NAME     C5D8 2
 '@BASEBOARD_FAB2_LIB.BASEBOARD_FAB2(SCH_1):PAGE220_I261@DEV_DISCRETE.CAP_A(CHIPS)':
 'B': CDS_PINID='B';
NODE_NAME     C5A1 2
 '@BASEBOARD_FAB2_LIB.BASEBOARD_FAB2(SCH_1):PAGE220_I262@DEV_DISCRETE.CAP_A(CHIPS)':
 'B': CDS_PINID='B';
NODE_NAME     C5A15 2
 '@BASEBOARD_FAB2_LIB.BASEBOARD_FAB2(SCH_1):PAGE220_I263@DEV_DISCRETE.CAP_A(CHIPS)':
 'B': CDS_PINID='B';
NODE_NAME     C5A12 2
 '@BASEBOARD_FAB2_LIB.BASEBOARD_FAB2(SCH_1):PAGE220_I264@DEV_DISCRETE.CAP_A(CHIPS)':
 'B': CDS_PINID='B';
NODE_NAME     C5A13 2
 '@BASEBOARD_FAB2_LIB.BASEBOARD_FAB2(SCH_1):PAGE220_I265@DEV_DISCRETE.CAP_A(CHIPS)':
 'B': CDS_PINID='B';
NODE_NAME     C5A2 2
 '@BASEBOARD_FAB2_LIB.BASEBOARD_FAB2(SCH_1):PAGE220_I266@DEV_DISCRETE.CAP_A(CHIPS)':
 'B': CDS_PINID='B';
NODE_NAME     C5A14 2
 '@BASEBOARD_FAB2_LIB.BASEBOARD_FAB2(SCH_1):PAGE220_I267@DEV_DISCRETE.CAP_A(CHIPS)':
 'B': CDS_PINID='B';
NODE_NAME     C5A6 2
 '@BASEBOARD_FAB2_LIB.BASEBOARD_FAB2(SCH_1):PAGE220_I268@DEV_DISCRETE.CAP_A(CHIPS)':
 'B': CDS_PINID='B';
NODE_NAME     C5A7 2
 '@BASEBOARD_FAB2_LIB.BASEBOARD_FAB2(SCH_1):PAGE220_I269@DEV_DISCRETE.CAP_A(CHIPS)':
 'B': CDS_PINID='B';
NODE_NAME     C5A3 2
 '@BASEBOARD_FAB2_LIB.BASEBOARD_FAB2(SCH_1):PAGE220_I270@DEV_DISCRETE.CAP_A(CHIPS)':
 'B': CDS_PINID='B';
NODE_NAME     C5A8 2
 '@BASEBOARD_FAB2_LIB.BASEBOARD_FAB2(SCH_1):PAGE220_I271@DEV_DISCRETE.CAP_A(CHIPS)':
 'B': CDS_PINID='B';
NODE_NAME     C5A9 2
 '@BASEBOARD_FAB2_LIB.BASEBOARD_FAB2(SCH_1):PAGE220_I272@DEV_DISCRETE.CAP_A(CHIPS)':
 'B': CDS_PINID='B';
NODE_NAME     C5A16 2
 '@BASEBOARD_FAB2_LIB.BASEBOARD_FAB2(SCH_1):PAGE220_I273@DEV_DISCRETE.CAP_A(CHIPS)':
 'B': CDS_PINID='B';
NODE_NAME     C5A4 2
 '@BASEBOARD_FAB2_LIB.BASEBOARD_FAB2(SCH_1):PAGE220_I274@DEV_DISCRETE.CAP_A(CHIPS)':
 'B': CDS_PINID='B';
NODE_NAME     C5A17 2
 '@BASEBOARD_FAB2_LIB.BASEBOARD_FAB2(SCH_1):PAGE220_I275@DEV_DISCRETE.CAP_A(CHIPS)':
 'B': CDS_PINID='B';
NODE_NAME     C5A18 2
 '@BASEBOARD_FAB2_LIB.BASEBOARD_FAB2(SCH_1):PAGE220_I276@DEV_DISCRETE.CAP_A(CHIPS)':
 'B': CDS_PINID='B';
NODE_NAME     C5A19 2
 '@BASEBOARD_FAB2_LIB.BASEBOARD_FAB2(SCH_1):PAGE220_I277@DEV_DISCRETE.CAP_A(CHIPS)':
 'B': CDS_PINID='B';
NODE_NAME     C5L6 2
 '@BASEBOARD_FAB2_LIB.BASEBOARD_FAB2(SCH_1):PAGE220_I278@DEV_DISCRETE.CAP_A(CHIPS)':
 'B': CDS_PINID='B';
NODE_NAME     C5L7 2
 '@BASEBOARD_FAB2_LIB.BASEBOARD_FAB2(SCH_1):PAGE220_I279@DEV_DISCRETE.CAP_A(CHIPS)':
 'B': CDS_PINID='B';
NODE_NAME     C5L8 2
 '@BASEBOARD_FAB2_LIB.BASEBOARD_FAB2(SCH_1):PAGE220_I280@DEV_DISCRETE.CAP_A(CHIPS)':
 'B': CDS_PINID='B';
NODE_NAME     C5L9 2
 '@BASEBOARD_FAB2_LIB.BASEBOARD_FAB2(SCH_1):PAGE220_I281@DEV_DISCRETE.CAP_A(CHIPS)':
 'B': CDS_PINID='B';
NODE_NAME     C5L10 2
 '@BASEBOARD_FAB2_LIB.BASEBOARD_FAB2(SCH_1):PAGE220_I282@DEV_DISCRETE.CAP_A(CHIPS)':
 'B': CDS_PINID='B';
NODE_NAME     C5L11 2
 '@BASEBOARD_FAB2_LIB.BASEBOARD_FAB2(SCH_1):PAGE220_I283@DEV_DISCRETE.CAP_A(CHIPS)':
 'B': CDS_PINID='B';
NODE_NAME     C5L12 2
 '@BASEBOARD_FAB2_LIB.BASEBOARD_FAB2(SCH_1):PAGE220_I284@DEV_DISCRETE.CAP_A(CHIPS)':
 'B': CDS_PINID='B';
NODE_NAME     C5L13 2
 '@BASEBOARD_FAB2_LIB.BASEBOARD_FAB2(SCH_1):PAGE220_I285@DEV_DISCRETE.CAP_A(CHIPS)':
 'B': CDS_PINID='B';
NODE_NAME     C5M7 2
 '@BASEBOARD_FAB2_LIB.BASEBOARD_FAB2(SCH_1):PAGE220_I286@DEV_DISCRETE.CAP_A(CHIPS)':
 'B': CDS_PINID='B';
NODE_NAME     C5M6 2
 '@BASEBOARD_FAB2_LIB.BASEBOARD_FAB2(SCH_1):PAGE220_I287@DEV_DISCRETE.CAP_A(CHIPS)':
 'B': CDS_PINID='B';
NODE_NAME     C5M5 2
 '@BASEBOARD_FAB2_LIB.BASEBOARD_FAB2(SCH_1):PAGE220_I288@DEV_DISCRETE.CAP_A(CHIPS)':
 'B': CDS_PINID='B';
NODE_NAME     C5M4 2
 '@BASEBOARD_FAB2_LIB.BASEBOARD_FAB2(SCH_1):PAGE220_I289@DEV_DISCRETE.CAP_A(CHIPS)':
 'B': CDS_PINID='B';
NODE_NAME     C5M2 2
 '@BASEBOARD_FAB2_LIB.BASEBOARD_FAB2(SCH_1):PAGE220_I290@DEV_DISCRETE.CAP_A(CHIPS)':
 'B': CDS_PINID='B';
NODE_NAME     C5M1 2
 '@BASEBOARD_FAB2_LIB.BASEBOARD_FAB2(SCH_1):PAGE220_I291@DEV_DISCRETE.CAP_A(CHIPS)':
 'B': CDS_PINID='B';
NODE_NAME     C4M2 2
 '@BASEBOARD_FAB2_LIB.BASEBOARD_FAB2(SCH_1):PAGE220_I292@DEV_DISCRETE.CAP_A(CHIPS)':
 'B': CDS_PINID='B';
NODE_NAME     C5A11 2
 '@BASEBOARD_FAB2_LIB.BASEBOARD_FAB2(SCH_1):PAGE220_I293@DEV_DISCRETE.CAP_A(CHIPS)':
 'B': CDS_PINID='B';
NODE_NAME     C2D43 2
 '@BASEBOARD_FAB2_LIB.BASEBOARD_FAB2(SCH_1):PAGE225_I270@DEV_DISCRETE.CAP_A(CHIPS)':
 'B': CDS_PINID='B';
NODE_NAME     C2D41 2
 '@BASEBOARD_FAB2_LIB.BASEBOARD_FAB2(SCH_1):PAGE225_I271@DEV_DISCRETE.CAP_A(CHIPS)':
 'B': CDS_PINID='B';
NODE_NAME     C2D44 2
 '@BASEBOARD_FAB2_LIB.BASEBOARD_FAB2(SCH_1):PAGE225_I272@DEV_DISCRETE.CAP_A(CHIPS)':
 'B': CDS_PINID='B';
NODE_NAME     C2D42 2
 '@BASEBOARD_FAB2_LIB.BASEBOARD_FAB2(SCH_1):PAGE225_I273@DEV_DISCRETE.CAP_A(CHIPS)':
 'B': CDS_PINID='B';
NODE_NAME     C2G10 2
 '@BASEBOARD_FAB2_LIB.BASEBOARD_FAB2(SCH_1):PAGE225_I274@DEV_DISCRETE.CAP_A(CHIPS)':
 'B': CDS_PINID='B';
NODE_NAME     C2G11 2
 '@BASEBOARD_FAB2_LIB.BASEBOARD_FAB2(SCH_1):PAGE225_I275@DEV_DISCRETE.CAP_A(CHIPS)':
 'B': CDS_PINID='B';
NODE_NAME     C2G12 2
 '@BASEBOARD_FAB2_LIB.BASEBOARD_FAB2(SCH_1):PAGE225_I276@DEV_DISCRETE.CAP_A(CHIPS)':
 'B': CDS_PINID='B';
NODE_NAME     C2G1 2
 '@BASEBOARD_FAB2_LIB.BASEBOARD_FAB2(SCH_1):PAGE225_I277@DEV_DISCRETE.CAP_A(CHIPS)':
 'B': CDS_PINID='B';
NODE_NAME     C2G9 2
 '@BASEBOARD_FAB2_LIB.BASEBOARD_FAB2(SCH_1):PAGE225_I278@DEV_DISCRETE.CAP_A(CHIPS)':
 'B': CDS_PINID='B';
NODE_NAME     C2G2 2
 '@BASEBOARD_FAB2_LIB.BASEBOARD_FAB2(SCH_1):PAGE225_I279@DEV_DISCRETE.CAP_A(CHIPS)':
 'B': CDS_PINID='B';
NODE_NAME     C2G3 2
 '@BASEBOARD_FAB2_LIB.BASEBOARD_FAB2(SCH_1):PAGE225_I280@DEV_DISCRETE.CAP_A(CHIPS)':
 'B': CDS_PINID='B';
NODE_NAME     C2G4 2
 '@BASEBOARD_FAB2_LIB.BASEBOARD_FAB2(SCH_1):PAGE225_I281@DEV_DISCRETE.CAP_A(CHIPS)':
 'B': CDS_PINID='B';
NODE_NAME     C2G5 2
 '@BASEBOARD_FAB2_LIB.BASEBOARD_FAB2(SCH_1):PAGE225_I282@DEV_DISCRETE.CAP_A(CHIPS)':
 'B': CDS_PINID='B';
NODE_NAME     C2G6 2
 '@BASEBOARD_FAB2_LIB.BASEBOARD_FAB2(SCH_1):PAGE225_I283@DEV_DISCRETE.CAP_A(CHIPS)':
 'B': CDS_PINID='B';
NODE_NAME     C3G1 2
 '@BASEBOARD_FAB2_LIB.BASEBOARD_FAB2(SCH_1):PAGE225_I284@DEV_DISCRETE.CAP_A(CHIPS)':
 'B': CDS_PINID='B';
NODE_NAME     C3G2 2
 '@BASEBOARD_FAB2_LIB.BASEBOARD_FAB2(SCH_1):PAGE225_I285@DEV_DISCRETE.CAP_A(CHIPS)':
 'B': CDS_PINID='B';
NODE_NAME     C2G13 2
 '@BASEBOARD_FAB2_LIB.BASEBOARD_FAB2(SCH_1):PAGE225_I286@DEV_DISCRETE.CAP_A(CHIPS)':
 'B': CDS_PINID='B';
NODE_NAME     C2G14 2
 '@BASEBOARD_FAB2_LIB.BASEBOARD_FAB2(SCH_1):PAGE225_I287@DEV_DISCRETE.CAP_A(CHIPS)':
 'B': CDS_PINID='B';
NODE_NAME     C3G5 2
 '@BASEBOARD_FAB2_LIB.BASEBOARD_FAB2(SCH_1):PAGE225_I288@DEV_DISCRETE.CAP_A(CHIPS)':
 'B': CDS_PINID='B';
NODE_NAME     C3G6 2
 '@BASEBOARD_FAB2_LIB.BASEBOARD_FAB2(SCH_1):PAGE225_I289@DEV_DISCRETE.CAP_A(CHIPS)':
 'B': CDS_PINID='B';
NODE_NAME     C8U7 2
 '@BASEBOARD_FAB2_LIB.BASEBOARD_FAB2(SCH_1):PAGE225_I290@DEV_DISCRETE.CAP_A(CHIPS)':
 'B': CDS_PINID='B';
NODE_NAME     C8U2 2
 '@BASEBOARD_FAB2_LIB.BASEBOARD_FAB2(SCH_1):PAGE225_I291@DEV_DISCRETE.CAP_A(CHIPS)':
 'B': CDS_PINID='B';
NODE_NAME     C7U2 2
 '@BASEBOARD_FAB2_LIB.BASEBOARD_FAB2(SCH_1):PAGE225_I292@DEV_DISCRETE.CAP_A(CHIPS)':
 'B': CDS_PINID='B';
NODE_NAME     C7U1 2
 '@BASEBOARD_FAB2_LIB.BASEBOARD_FAB2(SCH_1):PAGE225_I293@DEV_DISCRETE.CAP_A(CHIPS)':
 'B': CDS_PINID='B';
NODE_NAME     C8U3 2
 '@BASEBOARD_FAB2_LIB.BASEBOARD_FAB2(SCH_1):PAGE225_I294@DEV_DISCRETE.CAP_A(CHIPS)':
 'B': CDS_PINID='B';
NODE_NAME     C7T4 2
 '@BASEBOARD_FAB2_LIB.BASEBOARD_FAB2(SCH_1):PAGE225_I295@DEV_DISCRETE.CAP_A(CHIPS)':
 'B': CDS_PINID='B';
NODE_NAME     C7T5 2
 '@BASEBOARD_FAB2_LIB.BASEBOARD_FAB2(SCH_1):PAGE225_I296@DEV_DISCRETE.CAP_A(CHIPS)':
 'B': CDS_PINID='B';
NODE_NAME     C8T5 2
 '@BASEBOARD_FAB2_LIB.BASEBOARD_FAB2(SCH_1):PAGE225_I297@DEV_DISCRETE.CAP_A(CHIPS)':
 'B': CDS_PINID='B';
NODE_NAME     C8U6 2
 '@BASEBOARD_FAB2_LIB.BASEBOARD_FAB2(SCH_1):PAGE225_I298@DEV_DISCRETE.CAP_A(CHIPS)':
 'B': CDS_PINID='B';
NODE_NAME     C8T6 2
 '@BASEBOARD_FAB2_LIB.BASEBOARD_FAB2(SCH_1):PAGE225_I299@DEV_DISCRETE.CAP_A(CHIPS)':
 'B': CDS_PINID='B';
NODE_NAME     C8T7 2
 '@BASEBOARD_FAB2_LIB.BASEBOARD_FAB2(SCH_1):PAGE225_I300@DEV_DISCRETE.CAP_A(CHIPS)':
 'B': CDS_PINID='B';
NODE_NAME     C8T8 2
 '@BASEBOARD_FAB2_LIB.BASEBOARD_FAB2(SCH_1):PAGE225_I301@DEV_DISCRETE.CAP_A(CHIPS)':
 'B': CDS_PINID='B';
NODE_NAME     C8U5 2
 '@BASEBOARD_FAB2_LIB.BASEBOARD_FAB2(SCH_1):PAGE225_I302@DEV_DISCRETE.CAP_A(CHIPS)':
 'B': CDS_PINID='B';
NODE_NAME     C8T9 2
 '@BASEBOARD_FAB2_LIB.BASEBOARD_FAB2(SCH_1):PAGE225_I303@DEV_DISCRETE.CAP_A(CHIPS)':
 'B': CDS_PINID='B';
NODE_NAME     C8T10 2
 '@BASEBOARD_FAB2_LIB.BASEBOARD_FAB2(SCH_1):PAGE225_I304@DEV_DISCRETE.CAP_A(CHIPS)':
 'B': CDS_PINID='B';
NODE_NAME     C8U4 2
 '@BASEBOARD_FAB2_LIB.BASEBOARD_FAB2(SCH_1):PAGE225_I305@DEV_DISCRETE.CAP_A(CHIPS)':
 'B': CDS_PINID='B';
NODE_NAME     C2D7 2
 '@BASEBOARD_FAB2_LIB.BASEBOARD_FAB2(SCH_1):PAGE228_I264@DEV_DISCRETE.CAP_A(CHIPS)':
 'B': CDS_PINID='B';
NODE_NAME     C2D4 2
 '@BASEBOARD_FAB2_LIB.BASEBOARD_FAB2(SCH_1):PAGE228_I265@DEV_DISCRETE.CAP_A(CHIPS)':
 'B': CDS_PINID='B';
NODE_NAME     C2D5 2
 '@BASEBOARD_FAB2_LIB.BASEBOARD_FAB2(SCH_1):PAGE228_I266@DEV_DISCRETE.CAP_A(CHIPS)':
 'B': CDS_PINID='B';
NODE_NAME     C2D6 2
 '@BASEBOARD_FAB2_LIB.BASEBOARD_FAB2(SCH_1):PAGE228_I267@DEV_DISCRETE.CAP_A(CHIPS)':
 'B': CDS_PINID='B';
NODE_NAME     C7L5 2
 '@BASEBOARD_FAB2_LIB.BASEBOARD_FAB2(SCH_1):PAGE228_I268@DEV_DISCRETE.CAP_A(CHIPS)':
 'B': CDS_PINID='B';
NODE_NAME     C3A6 2
 '@BASEBOARD_FAB2_LIB.BASEBOARD_FAB2(SCH_1):PAGE228_I269@DEV_DISCRETE.CAP_A(CHIPS)':
 'B': CDS_PINID='B';
NODE_NAME     C3A5 2
 '@BASEBOARD_FAB2_LIB.BASEBOARD_FAB2(SCH_1):PAGE228_I270@DEV_DISCRETE.CAP_A(CHIPS)':
 'B': CDS_PINID='B';
NODE_NAME     C2A15 2
 '@BASEBOARD_FAB2_LIB.BASEBOARD_FAB2(SCH_1):PAGE228_I271@DEV_DISCRETE.CAP_A(CHIPS)':
 'B': CDS_PINID='B';
NODE_NAME     C2A14 2
 '@BASEBOARD_FAB2_LIB.BASEBOARD_FAB2(SCH_1):PAGE228_I272@DEV_DISCRETE.CAP_A(CHIPS)':
 'B': CDS_PINID='B';
NODE_NAME     C2A6 2
 '@BASEBOARD_FAB2_LIB.BASEBOARD_FAB2(SCH_1):PAGE228_I273@DEV_DISCRETE.CAP_A(CHIPS)':
 'B': CDS_PINID='B';
NODE_NAME     C2A7 2
 '@BASEBOARD_FAB2_LIB.BASEBOARD_FAB2(SCH_1):PAGE228_I274@DEV_DISCRETE.CAP_A(CHIPS)':
 'B': CDS_PINID='B';
NODE_NAME     C3A1 2
 '@BASEBOARD_FAB2_LIB.BASEBOARD_FAB2(SCH_1):PAGE228_I275@DEV_DISCRETE.CAP_A(CHIPS)':
 'B': CDS_PINID='B';
NODE_NAME     C3A2 2
 '@BASEBOARD_FAB2_LIB.BASEBOARD_FAB2(SCH_1):PAGE228_I276@DEV_DISCRETE.CAP_A(CHIPS)':
 'B': CDS_PINID='B';
NODE_NAME     C2A9 2
 '@BASEBOARD_FAB2_LIB.BASEBOARD_FAB2(SCH_1):PAGE228_I277@DEV_DISCRETE.CAP_A(CHIPS)':
 'B': CDS_PINID='B';
NODE_NAME     C2A10 2
 '@BASEBOARD_FAB2_LIB.BASEBOARD_FAB2(SCH_1):PAGE228_I278@DEV_DISCRETE.CAP_A(CHIPS)':
 'B': CDS_PINID='B';
NODE_NAME     C2A11 2
 '@BASEBOARD_FAB2_LIB.BASEBOARD_FAB2(SCH_1):PAGE228_I279@DEV_DISCRETE.CAP_A(CHIPS)':
 'B': CDS_PINID='B';
NODE_NAME     C2A13 2
 '@BASEBOARD_FAB2_LIB.BASEBOARD_FAB2(SCH_1):PAGE228_I280@DEV_DISCRETE.CAP_A(CHIPS)':
 'B': CDS_PINID='B';
NODE_NAME     C2A12 2
 '@BASEBOARD_FAB2_LIB.BASEBOARD_FAB2(SCH_1):PAGE228_I281@DEV_DISCRETE.CAP_A(CHIPS)':
 'B': CDS_PINID='B';
NODE_NAME     C2A1 2
 '@BASEBOARD_FAB2_LIB.BASEBOARD_FAB2(SCH_1):PAGE228_I282@DEV_DISCRETE.CAP_A(CHIPS)':
 'B': CDS_PINID='B';
NODE_NAME     C2A2 2
 '@BASEBOARD_FAB2_LIB.BASEBOARD_FAB2(SCH_1):PAGE228_I283@DEV_DISCRETE.CAP_A(CHIPS)':
 'B': CDS_PINID='B';
NODE_NAME     C8M1 2
 '@BASEBOARD_FAB2_LIB.BASEBOARD_FAB2(SCH_1):PAGE228_I284@DEV_DISCRETE.CAP_A(CHIPS)':
 'B': CDS_PINID='B';
NODE_NAME     C8L5 2
 '@BASEBOARD_FAB2_LIB.BASEBOARD_FAB2(SCH_1):PAGE228_I285@DEV_DISCRETE.CAP_A(CHIPS)':
 'B': CDS_PINID='B';
NODE_NAME     C8L6 2
 '@BASEBOARD_FAB2_LIB.BASEBOARD_FAB2(SCH_1):PAGE228_I286@DEV_DISCRETE.CAP_A(CHIPS)':
 'B': CDS_PINID='B';
NODE_NAME     C8L7 2
 '@BASEBOARD_FAB2_LIB.BASEBOARD_FAB2(SCH_1):PAGE228_I287@DEV_DISCRETE.CAP_A(CHIPS)':
 'B': CDS_PINID='B';
NODE_NAME     C7L4 2
 '@BASEBOARD_FAB2_LIB.BASEBOARD_FAB2(SCH_1):PAGE228_I288@DEV_DISCRETE.CAP_A(CHIPS)':
 'B': CDS_PINID='B';
NODE_NAME     C8L8 2
 '@BASEBOARD_FAB2_LIB.BASEBOARD_FAB2(SCH_1):PAGE228_I289@DEV_DISCRETE.CAP_A(CHIPS)':
 'B': CDS_PINID='B';
NODE_NAME     C8L9 2
 '@BASEBOARD_FAB2_LIB.BASEBOARD_FAB2(SCH_1):PAGE228_I290@DEV_DISCRETE.CAP_A(CHIPS)':
 'B': CDS_PINID='B';
NODE_NAME     C8M6 2
 '@BASEBOARD_FAB2_LIB.BASEBOARD_FAB2(SCH_1):PAGE228_I291@DEV_DISCRETE.CAP_A(CHIPS)':
 'B': CDS_PINID='B';
NODE_NAME     C2A4 2
 '@BASEBOARD_FAB2_LIB.BASEBOARD_FAB2(SCH_1):PAGE228_I292@DEV_DISCRETE.CAP_A(CHIPS)':
 'B': CDS_PINID='B';
NODE_NAME     C8M4 2
 '@BASEBOARD_FAB2_LIB.BASEBOARD_FAB2(SCH_1):PAGE228_I293@DEV_DISCRETE.CAP_A(CHIPS)':
 'B': CDS_PINID='B';
NODE_NAME     C7M2 2
 '@BASEBOARD_FAB2_LIB.BASEBOARD_FAB2(SCH_1):PAGE228_I294@DEV_DISCRETE.CAP_A(CHIPS)':
 'B': CDS_PINID='B';
NODE_NAME     C7M1 2
 '@BASEBOARD_FAB2_LIB.BASEBOARD_FAB2(SCH_1):PAGE228_I295@DEV_DISCRETE.CAP_A(CHIPS)':
 'B': CDS_PINID='B';
NODE_NAME     C2A3 2
 '@BASEBOARD_FAB2_LIB.BASEBOARD_FAB2(SCH_1):PAGE228_I296@DEV_DISCRETE.CAP_A(CHIPS)':
 'B': CDS_PINID='B';
NODE_NAME     C8L10 2
 '@BASEBOARD_FAB2_LIB.BASEBOARD_FAB2(SCH_1):PAGE228_I297@DEV_DISCRETE.CAP_A(CHIPS)':
 'B': CDS_PINID='B';
NODE_NAME     C8M5 2
 '@BASEBOARD_FAB2_LIB.BASEBOARD_FAB2(SCH_1):PAGE228_I298@DEV_DISCRETE.CAP_A(CHIPS)':
 'B': CDS_PINID='B';
NODE_NAME     C8M3 2
 '@BASEBOARD_FAB2_LIB.BASEBOARD_FAB2(SCH_1):PAGE228_I299@DEV_DISCRETE.CAP_A(CHIPS)':
 'B': CDS_PINID='B';
NODE_NAME     C7W5 2
 '@BASEBOARD_FAB2_LIB.BASEBOARD_FAB2(SCH_1):PAGE220_I298@W_HDL.SC22U16V5MX-4-GP(CHIPS)':
 '2': CDS_PINID='\2\';
NODE_NAME     C7W9 2
 '@BASEBOARD_FAB2_LIB.BASEBOARD_FAB2(SCH_1):PAGE220_I299@W_HDL.SC22U16V5MX-4-GP(CHIPS)':
 '2': CDS_PINID='\2\';
NODE_NAME     C7W8 2
 '@BASEBOARD_FAB2_LIB.BASEBOARD_FAB2(SCH_1):PAGE220_I300@W_HDL.SC22U16V5MX-4-GP(CHIPS)':
 '2': CDS_PINID='\2\';
NODE_NAME     C7W7 2
 '@BASEBOARD_FAB2_LIB.BASEBOARD_FAB2(SCH_1):PAGE220_I301@W_HDL.SC22U16V5MX-4-GP(CHIPS)':
 '2': CDS_PINID='\2\';
NODE_NAME     C7W6 2
 '@BASEBOARD_FAB2_LIB.BASEBOARD_FAB2(SCH_1):PAGE220_I302@W_HDL.SC22U16V5MX-4-GP(CHIPS)':
 '2': CDS_PINID='\2\';
NODE_NAME     C7W13 2
 '@BASEBOARD_FAB2_LIB.BASEBOARD_FAB2(SCH_1):PAGE220_I303@W_HDL.SC22U16V5MX-4-GP(CHIPS)':
 '2': CDS_PINID='\2\';
NODE_NAME     C7W12 2
 '@BASEBOARD_FAB2_LIB.BASEBOARD_FAB2(SCH_1):PAGE220_I304@W_HDL.SC22U16V5MX-4-GP(CHIPS)':
 '2': CDS_PINID='\2\';
NODE_NAME     C7W11 2
 '@BASEBOARD_FAB2_LIB.BASEBOARD_FAB2(SCH_1):PAGE220_I305@W_HDL.SC22U16V5MX-4-GP(CHIPS)':
 '2': CDS_PINID='\2\';
NODE_NAME     C7W10 2
 '@BASEBOARD_FAB2_LIB.BASEBOARD_FAB2(SCH_1):PAGE220_I306@W_HDL.SC22U16V5MX-4-GP(CHIPS)':
 '2': CDS_PINID='\2\';
NODE_NAME     J8D4 2
 '@BASEBOARD_FAB2_LIB.BASEBOARD_FAB2(SCH_1):PAGE201_I191@W_HDL.PIN-CON3-27-GP(CHIPS)':
 '2': CDS_PINID='\2\';
NODE_NAME     C25W8 2
 '@BASEBOARD_FAB2_LIB.BASEBOARD_FAB2(SCH_1):PAGE147_I162@DEV_DISCRETE.CAP_A(CHIPS)':
 'B': CDS_PINID='B';
NODE_NAME     C8E7 2
 '@BASEBOARD_FAB2_LIB.BASEBOARD_FAB2(SCH_1):PAGE241_I103@W_HDL.SC22U16V5MX-4-GP(CHIPS)':
 '2': CDS_PINID='\2\';
NODE_NAME     C8E9 2
 '@BASEBOARD_FAB2_LIB.BASEBOARD_FAB2(SCH_1):PAGE241_I104@W_HDL.SC22U16V5MX-4-GP(CHIPS)':
 '2': CDS_PINID='\2\';
NODE_NAME     Q8D1 1
 '@BASEBOARD_FAB2_LIB.BASEBOARD_FAB2(SCH_1):PAGE89_I46@MSTR_DISCRETE.NPN_DUAL(CHIPS)':
 'E'<0>: CDS_PINID='E(0)';
NODE_NAME     Q8W1 1
 '@BASEBOARD_FAB2_LIB.BASEBOARD_FAB2(SCH_1):PAGE89_I51@MSTR_DISCRETE.NPN_DUAL(CHIPS)':
 'E'<0>: CDS_PINID='E(0)';
NODE_NAME     Q8W1 4
 '@BASEBOARD_FAB2_LIB.BASEBOARD_FAB2(SCH_1):PAGE89_I52@MSTR_DISCRETE.NPN_DUAL(CHIPS)':
 'E'<0>: CDS_PINID='E(0)';
NODE_NAME     Q1F1 2
 '@BASEBOARD_FAB2_LIB.BASEBOARD_FAB2(SCH_1):PAGE89_I53@MSTR_DISCRETE.NPN(CHIPS)':
 'E': CDS_PINID='E';
NODE_NAME     Q1W6 2
 '@BASEBOARD_FAB2_LIB.BASEBOARD_FAB2(SCH_1):PAGE89_I55@MSTR_DISCRETE.NPN(CHIPS)':
 'E': CDS_PINID='E';
NODE_NAME     C30W3 2
 '@BASEBOARD_FAB2_LIB.BASEBOARD_FAB2(SCH_1):PAGE253_I35@W_HDL.SC22U16V5MX-4-GP(CHIPS)':
 '2': CDS_PINID='\2\';
NODE_NAME     C30W4 2
 '@BASEBOARD_FAB2_LIB.BASEBOARD_FAB2(SCH_1):PAGE253_I36@W_HDL.SC22U16V5MX-4-GP(CHIPS)':
 '2': CDS_PINID='\2\';
NODE_NAME     C30W6 2
 '@BASEBOARD_FAB2_LIB.BASEBOARD_FAB2(SCH_1):PAGE253_I37@W_HDL.SC22U16V5MX-4-GP(CHIPS)':
 '2': CDS_PINID='\2\';
NODE_NAME     C30W5 2
 '@BASEBOARD_FAB2_LIB.BASEBOARD_FAB2(SCH_1):PAGE253_I38@W_HDL.SC22U16V5MX-4-GP(CHIPS)':
 '2': CDS_PINID='\2\';
NODE_NAME     C30W9 2
 '@BASEBOARD_FAB2_LIB.BASEBOARD_FAB2(SCH_1):PAGE253_I40@W_HDL.SC22U16V5MX-4-GP(CHIPS)':
 '2': CDS_PINID='\2\';
NODE_NAME     C30W8 2
 '@BASEBOARD_FAB2_LIB.BASEBOARD_FAB2(SCH_1):PAGE253_I41@W_HDL.SC22U16V5MX-4-GP(CHIPS)':
 '2': CDS_PINID='\2\';
NODE_NAME     C30W7 2
 '@BASEBOARD_FAB2_LIB.BASEBOARD_FAB2(SCH_1):PAGE253_I42@W_HDL.SC22U16V5MX-4-GP(CHIPS)':
 '2': CDS_PINID='\2\';
NODE_NAME     R4P1 1
 '@BASEBOARD_FAB2_LIB.BASEBOARD_FAB2(SCH_1):PAGE90_I98@MSTR_DISCRETE.RES(CHIPS)':
 'A': CDS_PINID='A';
NODE_NAME     R3D13 1
 '@BASEBOARD_FAB2_LIB.BASEBOARD_FAB2(SCH_1):PAGE90_I99@MSTR_DISCRETE.RES(CHIPS)':
 'A': CDS_PINID='A';
NODE_NAME     R7P14 1
 '@BASEBOARD_FAB2_LIB.BASEBOARD_FAB2(SCH_1):PAGE90_I100@MSTR_DISCRETE.RES(CHIPS)':
 'A': CDS_PINID='A';
NODE_NAME     R1U15 2
 '@BASEBOARD_FAB2_LIB.BASEBOARD_FAB2(SCH_1):PAGE164_I48@MSTR_DISCRETE.RES(CHIPS)':
 'B': CDS_PINID='B';
NODE_NAME     R6D6 1
 '@BASEBOARD_FAB2_LIB.BASEBOARD_FAB2(SCH_1):PAGE90_I101@MSTR_DISCRETE.RES(CHIPS)':
 'A': CDS_PINID='A';
NODE_NAME     R3D12 1
 '@BASEBOARD_FAB2_LIB.BASEBOARD_FAB2(SCH_1):PAGE90_I102@MSTR_DISCRETE.RES(CHIPS)':
 'A': CDS_PINID='A';
NODE_NAME     R2T1 2
 '@BASEBOARD_FAB2_LIB.BASEBOARD_FAB2(SCH_1):PAGE125_I89@MSTR_DISCRETE.RES(CHIPS)':
 'B': CDS_PINID='B';
NODE_NAME     R9F32 2
 '@BASEBOARD_FAB2_LIB.BASEBOARD_FAB2(SCH_1):PAGE239_I100@MSTR_DISCRETE.RES(CHIPS)':
 'B': CDS_PINID='B';
NODE_NAME     R9W32 2
 '@BASEBOARD_FAB2_LIB.BASEBOARD_FAB2(SCH_1):PAGE239_I101@MSTR_DISCRETE.RES(CHIPS)':
 'B': CDS_PINID='B';
NODE_NAME     R7G8 2
 '@BASEBOARD_FAB2_LIB.BASEBOARD_FAB2(SCH_1):PAGE215_I72@MSTR_DISCRETE.RES(CHIPS)':
 'B': CDS_PINID='B';
NODE_NAME     R1B12 2
 '@BASEBOARD_FAB2_LIB.BASEBOARD_FAB2(SCH_1):PAGE226_I72@MSTR_DISCRETE.RES(CHIPS)':
 'B': CDS_PINID='B';
NODE_NAME     Q6W4 2
 '@BASEBOARD_FAB2_LIB.BASEBOARD_FAB2(SCH_1):PAGE168_I43@MSTR_DISCRETE.FET_N(CHIPS)':
 'SRC': CDS_PINID='SRC';
NODE_NAME     R6W38 2
 '@BASEBOARD_FAB2_LIB.BASEBOARD_FAB2(SCH_1):PAGE176_I156@MSTR_DISCRETE.RES(CHIPS)':
 'B': CDS_PINID='B';
NODE_NAME     C5M13 2
 '@BASEBOARD_FAB2_LIB.BASEBOARD_FAB2(SCH_1):PAGE222_I41@DEV_DISCRETE.CAP_A(CHIPS)':
 'B': CDS_PINID='B';
NODE_NAME     C5T3 2
 '@BASEBOARD_FAB2_LIB.BASEBOARD_FAB2(SCH_1):PAGE221_I40@DEV_DISCRETE.CAP_A(CHIPS)':
 'B': CDS_PINID='B';
NODE_NAME     C1W18 2
 '@BASEBOARD_FAB2_LIB.BASEBOARD_FAB2(SCH_1):PAGE176_I163@DEV_DISCRETE.CAP_A(CHIPS)':
 'B': CDS_PINID='B';
NODE_NAME     C1W19 2
 '@BASEBOARD_FAB2_LIB.BASEBOARD_FAB2(SCH_1):PAGE176_I166@DEV_DISCRETE.CAP_A(CHIPS)':
 'B': CDS_PINID='B';
NODE_NAME     C1W20 2
 '@BASEBOARD_FAB2_LIB.BASEBOARD_FAB2(SCH_1):PAGE151_I220@MSTR_DISCRETE.CAP(CHIPS)':
 'B': CDS_PINID='B';
NODE_NAME     C1W21 2
 '@BASEBOARD_FAB2_LIB.BASEBOARD_FAB2(SCH_1):PAGE146_I160@MSTR_DISCRETE.CAP(CHIPS)':
 'B': CDS_PINID='B';
NODE_NAME     R1T12 2
 '@BASEBOARD_FAB2_LIB.BASEBOARD_FAB2(SCH_1):PAGE164_I53@MSTR_DISCRETE.RES(CHIPS)':
 'B': CDS_PINID='B';
NODE_NAME     R3N22 2
 '@BASEBOARD_FAB2_LIB.BASEBOARD_FAB2(SCH_1):PAGE211_I102@MSTR_DISCRETE.RES(CHIPS)':
 'B': CDS_PINID='B';
NODE_NAME     R4E2 2
 '@BASEBOARD_FAB2_LIB.BASEBOARD_FAB2(SCH_1):PAGE213_I103@MSTR_DISCRETE.RES(CHIPS)':
 'B': CDS_PINID='B';
NODE_NAME     R4D64 2
 '@BASEBOARD_FAB2_LIB.BASEBOARD_FAB2(SCH_1):PAGE213_I104@MSTR_DISCRETE.RES(CHIPS)':
 'B': CDS_PINID='B';
NODE_NAME     R7G10 2
 '@BASEBOARD_FAB2_LIB.BASEBOARD_FAB2(SCH_1):PAGE215_I73@MSTR_DISCRETE.RES(CHIPS)':
 'B': CDS_PINID='B';
NODE_NAME     R7A10 2
 '@BASEBOARD_FAB2_LIB.BASEBOARD_FAB2(SCH_1):PAGE218_I73@MSTR_DISCRETE.RES(CHIPS)':
 'B': CDS_PINID='B';
NODE_NAME     R7A8 2
 '@BASEBOARD_FAB2_LIB.BASEBOARD_FAB2(SCH_1):PAGE218_I74@MSTR_DISCRETE.RES(CHIPS)':
 'B': CDS_PINID='B';
NODE_NAME     R1G23 2
 '@BASEBOARD_FAB2_LIB.BASEBOARD_FAB2(SCH_1):PAGE223_I73@MSTR_DISCRETE.RES(CHIPS)':
 'B': CDS_PINID='B';
NODE_NAME     R1G22 2
 '@BASEBOARD_FAB2_LIB.BASEBOARD_FAB2(SCH_1):PAGE223_I74@MSTR_DISCRETE.RES(CHIPS)':
 'B': CDS_PINID='B';
NODE_NAME     R2L9 2
 '@BASEBOARD_FAB2_LIB.BASEBOARD_FAB2(SCH_1):PAGE235_I254@MSTR_DISCRETE.RES(CHIPS)':
 'B': CDS_PINID='B';
NODE_NAME     R25W58 2
 '@BASEBOARD_FAB2_LIB.BASEBOARD_FAB2(SCH_1):PAGE144_I150@W_HDL.18KR2F-GP(CHIPS)':
 '2': CDS_PINID='\2\';
NODE_NAME     R25W1 1
 '@BASEBOARD_FAB2_LIB.BASEBOARD_FAB2(SCH_1):PAGE151_I248@W_HDL.120R2F-GP(CHIPS)':
 '1': CDS_PINID='\1\';
NODE_NAME     R25W2 1
 '@BASEBOARD_FAB2_LIB.BASEBOARD_FAB2(SCH_1):PAGE151_I249@W_HDL.120R2F-GP(CHIPS)':
 '1': CDS_PINID='\1\';
NODE_NAME     R25W3 1
 '@BASEBOARD_FAB2_LIB.BASEBOARD_FAB2(SCH_1):PAGE151_I250@W_HDL.120R2F-GP(CHIPS)':
 '1': CDS_PINID='\1\';
NODE_NAME     R25W4 1
 '@BASEBOARD_FAB2_LIB.BASEBOARD_FAB2(SCH_1):PAGE151_I251@W_HDL.120R2F-GP(CHIPS)':
 '1': CDS_PINID='\1\';
NODE_NAME     R25W5 1
 '@BASEBOARD_FAB2_LIB.BASEBOARD_FAB2(SCH_1):PAGE151_I252@W_HDL.120R2F-GP(CHIPS)':
 '1': CDS_PINID='\1\';
NODE_NAME     R25W6 1
 '@BASEBOARD_FAB2_LIB.BASEBOARD_FAB2(SCH_1):PAGE151_I253@W_HDL.120R2F-GP(CHIPS)':
 '1': CDS_PINID='\1\';
NODE_NAME     R25W7 1
 '@BASEBOARD_FAB2_LIB.BASEBOARD_FAB2(SCH_1):PAGE151_I254@W_HDL.120R2F-GP(CHIPS)':
 '1': CDS_PINID='\1\';
NODE_NAME     R25W8 1
 '@BASEBOARD_FAB2_LIB.BASEBOARD_FAB2(SCH_1):PAGE151_I255@W_HDL.120R2F-GP(CHIPS)':
 '1': CDS_PINID='\1\';
NODE_NAME     R25W12 1
 '@BASEBOARD_FAB2_LIB.BASEBOARD_FAB2(SCH_1):PAGE151_I256@W_HDL.120R2F-GP(CHIPS)':
 '1': CDS_PINID='\1\';
NODE_NAME     R25W11 1
 '@BASEBOARD_FAB2_LIB.BASEBOARD_FAB2(SCH_1):PAGE151_I257@W_HDL.120R2F-GP(CHIPS)':
 '1': CDS_PINID='\1\';
NODE_NAME     R25W9 1
 '@BASEBOARD_FAB2_LIB.BASEBOARD_FAB2(SCH_1):PAGE151_I258@W_HDL.120R2F-GP(CHIPS)':
 '1': CDS_PINID='\1\';
NODE_NAME     R25W10 1
 '@BASEBOARD_FAB2_LIB.BASEBOARD_FAB2(SCH_1):PAGE151_I259@W_HDL.120R2F-GP(CHIPS)':
 '1': CDS_PINID='\1\';
NODE_NAME     R25W13 1
 '@BASEBOARD_FAB2_LIB.BASEBOARD_FAB2(SCH_1):PAGE151_I260@W_HDL.120R2F-GP(CHIPS)':
 '1': CDS_PINID='\1\';
NODE_NAME     R25W16 1
 '@BASEBOARD_FAB2_LIB.BASEBOARD_FAB2(SCH_1):PAGE151_I261@W_HDL.120R2F-GP(CHIPS)':
 '1': CDS_PINID='\1\';
NODE_NAME     R25W15 1
 '@BASEBOARD_FAB2_LIB.BASEBOARD_FAB2(SCH_1):PAGE151_I262@W_HDL.120R2F-GP(CHIPS)':
 '1': CDS_PINID='\1\';
NODE_NAME     R25W14 1
 '@BASEBOARD_FAB2_LIB.BASEBOARD_FAB2(SCH_1):PAGE151_I263@W_HDL.120R2F-GP(CHIPS)':
 '1': CDS_PINID='\1\';
NODE_NAME     R25W17 1
 '@BASEBOARD_FAB2_LIB.BASEBOARD_FAB2(SCH_1):PAGE151_I264@W_HDL.120R2F-GP(CHIPS)':
 '1': CDS_PINID='\1\';
NODE_NAME     R25W18 1
 '@BASEBOARD_FAB2_LIB.BASEBOARD_FAB2(SCH_1):PAGE151_I265@W_HDL.120R2F-GP(CHIPS)':
 '1': CDS_PINID='\1\';
NODE_NAME     R25W20 1
 '@BASEBOARD_FAB2_LIB.BASEBOARD_FAB2(SCH_1):PAGE151_I266@W_HDL.120R2F-GP(CHIPS)':
 '1': CDS_PINID='\1\';
NODE_NAME     R25W19 1
 '@BASEBOARD_FAB2_LIB.BASEBOARD_FAB2(SCH_1):PAGE151_I267@W_HDL.120R2F-GP(CHIPS)':
 '1': CDS_PINID='\1\';
NODE_NAME     R25W24 1
 '@BASEBOARD_FAB2_LIB.BASEBOARD_FAB2(SCH_1):PAGE151_I268@W_HDL.120R2F-GP(CHIPS)':
 '1': CDS_PINID='\1\';
NODE_NAME     R25W23 1
 '@BASEBOARD_FAB2_LIB.BASEBOARD_FAB2(SCH_1):PAGE151_I269@W_HDL.120R2F-GP(CHIPS)':
 '1': CDS_PINID='\1\';
NODE_NAME     R25W22 1
 '@BASEBOARD_FAB2_LIB.BASEBOARD_FAB2(SCH_1):PAGE151_I270@W_HDL.120R2F-GP(CHIPS)':
 '1': CDS_PINID='\1\';
NODE_NAME     R25W21 1
 '@BASEBOARD_FAB2_LIB.BASEBOARD_FAB2(SCH_1):PAGE151_I271@W_HDL.120R2F-GP(CHIPS)':
 '1': CDS_PINID='\1\';
NODE_NAME     R25W26 1
 '@BASEBOARD_FAB2_LIB.BASEBOARD_FAB2(SCH_1):PAGE151_I274@W_HDL.120R2F-GP(CHIPS)':
 '1': CDS_PINID='\1\';
NODE_NAME     R25W25 1
 '@BASEBOARD_FAB2_LIB.BASEBOARD_FAB2(SCH_1):PAGE151_I275@W_HDL.120R2F-GP(CHIPS)':
 '1': CDS_PINID='\1\';
NODE_NAME     R9B7 2
 '@BASEBOARD_FAB2_LIB.BASEBOARD_FAB2(SCH_1):PAGE186_I358@W_HDL.887R2F-L-GP(CHIPS)':
 '2': CDS_PINID='\2\';
NODE_NAME     R2R8 2
 '@BASEBOARD_FAB2_LIB.BASEBOARD_FAB2(SCH_1):PAGE187_I175@W_HDL.887R2F-L-GP(CHIPS)':
 '2': CDS_PINID='\2\';
NODE_NAME     RT2 2
 '@BASEBOARD_FAB2_LIB.BASEBOARD_FAB2(SCH_1):PAGE202_I114@W_HDL.1R3F-GP(CHIPS)':
 '2': CDS_PINID='\2\';
NODE_NAME     RT4 2
 '@BASEBOARD_FAB2_LIB.BASEBOARD_FAB2(SCH_1):PAGE202_I115@W_HDL.1R3F-GP(CHIPS)':
 '2': CDS_PINID='\2\';
NODE_NAME     RT26 2
 '@BASEBOARD_FAB2_LIB.BASEBOARD_FAB2(SCH_1):PAGE203_I134@W_HDL.1R3F-GP(CHIPS)':
 '2': CDS_PINID='\2\';
NODE_NAME     RT27 2
 '@BASEBOARD_FAB2_LIB.BASEBOARD_FAB2(SCH_1):PAGE203_I135@W_HDL.1R3F-GP(CHIPS)':
 '2': CDS_PINID='\2\';
NODE_NAME     RT39 2
 '@BASEBOARD_FAB2_LIB.BASEBOARD_FAB2(SCH_1):PAGE205_I84@W_HDL.1R3F-GP(CHIPS)':
 '2': CDS_PINID='\2\';
NODE_NAME     RT16 2
 '@BASEBOARD_FAB2_LIB.BASEBOARD_FAB2(SCH_1):PAGE207_I111@W_HDL.1R3F-GP(CHIPS)':
 '2': CDS_PINID='\2\';
NODE_NAME     RT18 2
 '@BASEBOARD_FAB2_LIB.BASEBOARD_FAB2(SCH_1):PAGE207_I112@W_HDL.1R3F-GP(CHIPS)':
 '2': CDS_PINID='\2\';
NODE_NAME     RT24 2
 '@BASEBOARD_FAB2_LIB.BASEBOARD_FAB2(SCH_1):PAGE204_I114@W_HDL.1R3F-GP(CHIPS)':
 '2': CDS_PINID='\2\';
NODE_NAME     RT12 2
 '@BASEBOARD_FAB2_LIB.BASEBOARD_FAB2(SCH_1):PAGE208_I120@W_HDL.1R3F-GP(CHIPS)':
 '2': CDS_PINID='\2\';
NODE_NAME     RT13 2
 '@BASEBOARD_FAB2_LIB.BASEBOARD_FAB2(SCH_1):PAGE208_I121@W_HDL.1R3F-GP(CHIPS)':
 '2': CDS_PINID='\2\';
NODE_NAME     RT10 2
 '@BASEBOARD_FAB2_LIB.BASEBOARD_FAB2(SCH_1):PAGE209_I90@W_HDL.1R3F-GP(CHIPS)':
 '2': CDS_PINID='\2\';
NODE_NAME     RT38 2
 '@BASEBOARD_FAB2_LIB.BASEBOARD_FAB2(SCH_1):PAGE210_I74@W_HDL.1R3F-GP(CHIPS)':
 '2': CDS_PINID='\2\';
NODE_NAME     RT48 2
 '@BASEBOARD_FAB2_LIB.BASEBOARD_FAB2(SCH_1):PAGE212_I144@W_HDL.1R3F-GP(CHIPS)':
 '2': CDS_PINID='\2\';
NODE_NAME     RT42 2
 '@BASEBOARD_FAB2_LIB.BASEBOARD_FAB2(SCH_1):PAGE214_I176@W_HDL.1R3F-GP(CHIPS)':
 '2': CDS_PINID='\2\';
NODE_NAME     RT34 2
 '@BASEBOARD_FAB2_LIB.BASEBOARD_FAB2(SCH_1):PAGE216_I151@W_HDL.1R3F-GP(CHIPS)':
 '2': CDS_PINID='\2\';
NODE_NAME     RT35 2
 '@BASEBOARD_FAB2_LIB.BASEBOARD_FAB2(SCH_1):PAGE216_I152@W_HDL.1R3F-GP(CHIPS)':
 '2': CDS_PINID='\2\';
NODE_NAME     RT29 2
 '@BASEBOARD_FAB2_LIB.BASEBOARD_FAB2(SCH_1):PAGE219_I153@W_HDL.1R3F-GP(CHIPS)':
 '2': CDS_PINID='\2\';
NODE_NAME     RT32 2
 '@BASEBOARD_FAB2_LIB.BASEBOARD_FAB2(SCH_1):PAGE219_I154@W_HDL.1R3F-GP(CHIPS)':
 '2': CDS_PINID='\2\';
NODE_NAME     RT20 2
 '@BASEBOARD_FAB2_LIB.BASEBOARD_FAB2(SCH_1):PAGE224_I156@W_HDL.1R3F-GP(CHIPS)':
 '2': CDS_PINID='\2\';
NODE_NAME     RT22 2
 '@BASEBOARD_FAB2_LIB.BASEBOARD_FAB2(SCH_1):PAGE224_I157@W_HDL.1R3F-GP(CHIPS)':
 '2': CDS_PINID='\2\';
NODE_NAME     RT43 2
 '@BASEBOARD_FAB2_LIB.BASEBOARD_FAB2(SCH_1):PAGE236_I182@W_HDL.1R3F-GP(CHIPS)':
 '2': CDS_PINID='\2\';
NODE_NAME     RT45 2
 '@BASEBOARD_FAB2_LIB.BASEBOARD_FAB2(SCH_1):PAGE236_I183@W_HDL.1R3F-GP(CHIPS)':
 '2': CDS_PINID='\2\';
NODE_NAME     RT6 2
 '@BASEBOARD_FAB2_LIB.BASEBOARD_FAB2(SCH_1):PAGE227_I149@W_HDL.1R3F-GP(CHIPS)':
 '2': CDS_PINID='\2\';
NODE_NAME     RT7 2
 '@BASEBOARD_FAB2_LIB.BASEBOARD_FAB2(SCH_1):PAGE227_I150@W_HDL.1R3F-GP(CHIPS)':
 '2': CDS_PINID='\2\';
NODE_NAME     R1B15 2
 '@BASEBOARD_FAB2_LIB.BASEBOARD_FAB2(SCH_1):PAGE226_I73@MSTR_DISCRETE.RES(CHIPS)':
 'B': CDS_PINID='B';
NODE_NAME     R6W9 2
 '@BASEBOARD_FAB2_LIB.BASEBOARD_FAB2(SCH_1):PAGE247_I162@MSTR_DISCRETE.RES(CHIPS)':
 'B': CDS_PINID='B';
NODE_NAME     R6W8 2
 '@BASEBOARD_FAB2_LIB.BASEBOARD_FAB2(SCH_1):PAGE247_I163@MSTR_DISCRETE.RES(CHIPS)':
 'B': CDS_PINID='B';
NODE_NAME     R6W7 2
 '@BASEBOARD_FAB2_LIB.BASEBOARD_FAB2(SCH_1):PAGE247_I164@MSTR_DISCRETE.RES(CHIPS)':
 'B': CDS_PINID='B';
NODE_NAME     J1B2 1
 '@BASEBOARD_FAB2_LIB.BASEBOARD_FAB2(SCH_1):PAGE251_I25@MSTR_CONN.CONN6_C74770005(CHIPS)':
 'IO1': CDS_PINID='IO1';
NODE_NAME     C10W5 2
 '@BASEBOARD_FAB2_LIB.BASEBOARD_FAB2(SCH_1):PAGE251_I29@DEV_DISCRETE.CAP_A(CHIPS)':
 'B': CDS_PINID='B';
NODE_NAME     C8F19 2
 '@BASEBOARD_FAB2_LIB.BASEBOARD_FAB2(SCH_1):PAGE101_I146@MSTR_DISCRETE.CAP(CHIPS)':
 'B': CDS_PINID='B';
NODE_NAME     C8F18 2
 '@BASEBOARD_FAB2_LIB.BASEBOARD_FAB2(SCH_1):PAGE101_I147@MSTR_DISCRETE.CAP(CHIPS)':
 'B': CDS_PINID='B';
NODE_NAME     J1F2 1
 '@BASEBOARD_FAB2_LIB.BASEBOARD_FAB2(SCH_1):PAGE161_I139@W_HDL.LOTES-CON4-S1-GP(CHIPS)':
 '1': CDS_PINID='\1\';
NODE_NAME     J10W1 1
 '@BASEBOARD_FAB2_LIB.BASEBOARD_FAB2(SCH_1):PAGE161_I140@W_HDL.LOTES-CON4-S1-GP(CHIPS)':
 '1': CDS_PINID='\1\';
NODE_NAME     C8W4 2
 '@BASEBOARD_FAB2_LIB.BASEBOARD_FAB2(SCH_1):PAGE76_I245@MSTR_DISCRETE.CAP(CHIPS)':
 'B': CDS_PINID='B';
NODE_NAME     C5U1 2
 '@BASEBOARD_FAB2_LIB.BASEBOARD_FAB2(SCH_1):PAGE217_I316@MSTR_DISCRETE.CAP(CHIPS)':
 'B': CDS_PINID='B';
NODE_NAME     C5U10 2
 '@BASEBOARD_FAB2_LIB.BASEBOARD_FAB2(SCH_1):PAGE217_I317@MSTR_DISCRETE.CAP(CHIPS)':
 'B': CDS_PINID='B';
NODE_NAME     C5G9 2
 '@BASEBOARD_FAB2_LIB.BASEBOARD_FAB2(SCH_1):PAGE217_I318@MSTR_DISCRETE.CAP(CHIPS)':
 'B': CDS_PINID='B';
NODE_NAME     C4T4 2
 '@BASEBOARD_FAB2_LIB.BASEBOARD_FAB2(SCH_1):PAGE217_I319@MSTR_DISCRETE.CAP(CHIPS)':
 'B': CDS_PINID='B';
NODE_NAME     C5U15 2
 '@BASEBOARD_FAB2_LIB.BASEBOARD_FAB2(SCH_1):PAGE217_I320@MSTR_DISCRETE.CAP(CHIPS)':
 'B': CDS_PINID='B';
NODE_NAME     C5U13 2
 '@BASEBOARD_FAB2_LIB.BASEBOARD_FAB2(SCH_1):PAGE217_I321@MSTR_DISCRETE.CAP(CHIPS)':
 'B': CDS_PINID='B';
NODE_NAME     C5U14 2
 '@BASEBOARD_FAB2_LIB.BASEBOARD_FAB2(SCH_1):PAGE217_I322@MSTR_DISCRETE.CAP(CHIPS)':
 'B': CDS_PINID='B';
NODE_NAME     C5P41 2
 '@BASEBOARD_FAB2_LIB.BASEBOARD_FAB2(SCH_1):PAGE217_I323@MSTR_DISCRETE.CAP(CHIPS)':
 'B': CDS_PINID='B';
NODE_NAME     C5P44 2
 '@BASEBOARD_FAB2_LIB.BASEBOARD_FAB2(SCH_1):PAGE217_I324@MSTR_DISCRETE.CAP(CHIPS)':
 'B': CDS_PINID='B';
NODE_NAME     C5P42 2
 '@BASEBOARD_FAB2_LIB.BASEBOARD_FAB2(SCH_1):PAGE217_I325@MSTR_DISCRETE.CAP(CHIPS)':
 'B': CDS_PINID='B';
NODE_NAME     C5P43 2
 '@BASEBOARD_FAB2_LIB.BASEBOARD_FAB2(SCH_1):PAGE217_I326@MSTR_DISCRETE.CAP(CHIPS)':
 'B': CDS_PINID='B';
NODE_NAME     C5P38 2
 '@BASEBOARD_FAB2_LIB.BASEBOARD_FAB2(SCH_1):PAGE217_I327@MSTR_DISCRETE.CAP(CHIPS)':
 'B': CDS_PINID='B';
NODE_NAME     C5P39 2
 '@BASEBOARD_FAB2_LIB.BASEBOARD_FAB2(SCH_1):PAGE217_I328@MSTR_DISCRETE.CAP(CHIPS)':
 'B': CDS_PINID='B';
NODE_NAME     C5G20 2
 '@BASEBOARD_FAB2_LIB.BASEBOARD_FAB2(SCH_1):PAGE217_I329@MSTR_DISCRETE.CAP(CHIPS)':
 'B': CDS_PINID='B';
NODE_NAME     C5A20 2
 '@BASEBOARD_FAB2_LIB.BASEBOARD_FAB2(SCH_1):PAGE220_I308@MSTR_DISCRETE.CAP(CHIPS)':
 'B': CDS_PINID='B';
NODE_NAME     C5L1 2
 '@BASEBOARD_FAB2_LIB.BASEBOARD_FAB2(SCH_1):PAGE220_I309@MSTR_DISCRETE.CAP(CHIPS)':
 'B': CDS_PINID='B';
NODE_NAME     C5L3 2
 '@BASEBOARD_FAB2_LIB.BASEBOARD_FAB2(SCH_1):PAGE220_I310@MSTR_DISCRETE.CAP(CHIPS)':
 'B': CDS_PINID='B';
NODE_NAME     C5L2 2
 '@BASEBOARD_FAB2_LIB.BASEBOARD_FAB2(SCH_1):PAGE220_I311@MSTR_DISCRETE.CAP(CHIPS)':
 'B': CDS_PINID='B';
NODE_NAME     C5M12 2
 '@BASEBOARD_FAB2_LIB.BASEBOARD_FAB2(SCH_1):PAGE220_I312@MSTR_DISCRETE.CAP(CHIPS)':
 'B': CDS_PINID='B';
NODE_NAME     C5L14 2
 '@BASEBOARD_FAB2_LIB.BASEBOARD_FAB2(SCH_1):PAGE220_I313@MSTR_DISCRETE.CAP(CHIPS)':
 'B': CDS_PINID='B';
NODE_NAME     C5M8 2
 '@BASEBOARD_FAB2_LIB.BASEBOARD_FAB2(SCH_1):PAGE220_I314@MSTR_DISCRETE.CAP(CHIPS)':
 'B': CDS_PINID='B';
NODE_NAME     C5P3 2
 '@BASEBOARD_FAB2_LIB.BASEBOARD_FAB2(SCH_1):PAGE220_I315@MSTR_DISCRETE.CAP(CHIPS)':
 'B': CDS_PINID='B';
NODE_NAME     C5P6 2
 '@BASEBOARD_FAB2_LIB.BASEBOARD_FAB2(SCH_1):PAGE220_I316@MSTR_DISCRETE.CAP(CHIPS)':
 'B': CDS_PINID='B';
NODE_NAME     C5P5 2
 '@BASEBOARD_FAB2_LIB.BASEBOARD_FAB2(SCH_1):PAGE220_I317@MSTR_DISCRETE.CAP(CHIPS)':
 'B': CDS_PINID='B';
NODE_NAME     C5P4 2
 '@BASEBOARD_FAB2_LIB.BASEBOARD_FAB2(SCH_1):PAGE220_I318@MSTR_DISCRETE.CAP(CHIPS)':
 'B': CDS_PINID='B';
NODE_NAME     C5P2 2
 '@BASEBOARD_FAB2_LIB.BASEBOARD_FAB2(SCH_1):PAGE220_I319@MSTR_DISCRETE.CAP(CHIPS)':
 'B': CDS_PINID='B';
NODE_NAME     C5P1 2
 '@BASEBOARD_FAB2_LIB.BASEBOARD_FAB2(SCH_1):PAGE220_I320@MSTR_DISCRETE.CAP(CHIPS)':
 'B': CDS_PINID='B';
NODE_NAME     C5A10 2
 '@BASEBOARD_FAB2_LIB.BASEBOARD_FAB2(SCH_1):PAGE220_I321@MSTR_DISCRETE.CAP(CHIPS)':
 'B': CDS_PINID='B';
NODE_NAME     C6W11 2
 '@BASEBOARD_FAB2_LIB.BASEBOARD_FAB2(SCH_1):PAGE221_I44@MSTR_DISCRETE.CAP(CHIPS)':
 'B': CDS_PINID='B';
NODE_NAME     C5U12 2
 '@BASEBOARD_FAB2_LIB.BASEBOARD_FAB2(SCH_1):PAGE221_I45@MSTR_DISCRETE.CAP(CHIPS)':
 'B': CDS_PINID='B';
NODE_NAME     C5U16 2
 '@BASEBOARD_FAB2_LIB.BASEBOARD_FAB2(SCH_1):PAGE221_I46@MSTR_DISCRETE.CAP(CHIPS)':
 'B': CDS_PINID='B';
NODE_NAME     C5L5 2
 '@BASEBOARD_FAB2_LIB.BASEBOARD_FAB2(SCH_1):PAGE222_I44@MSTR_DISCRETE.CAP(CHIPS)':
 'B': CDS_PINID='B';
NODE_NAME     C5L4 2
 '@BASEBOARD_FAB2_LIB.BASEBOARD_FAB2(SCH_1):PAGE222_I45@MSTR_DISCRETE.CAP(CHIPS)':
 'B': CDS_PINID='B';
NODE_NAME     C4W5 2
 '@BASEBOARD_FAB2_LIB.BASEBOARD_FAB2(SCH_1):PAGE222_I46@MSTR_DISCRETE.CAP(CHIPS)':
 'B': CDS_PINID='B';
NODE_NAME     C8U11 2
 '@BASEBOARD_FAB2_LIB.BASEBOARD_FAB2(SCH_1):PAGE225_I307@MSTR_DISCRETE.CAP(CHIPS)':
 'B': CDS_PINID='B';
NODE_NAME     C7U7 2
 '@BASEBOARD_FAB2_LIB.BASEBOARD_FAB2(SCH_1):PAGE225_I308@MSTR_DISCRETE.CAP(CHIPS)':
 'B': CDS_PINID='B';
NODE_NAME     C7T1 2
 '@BASEBOARD_FAB2_LIB.BASEBOARD_FAB2(SCH_1):PAGE225_I309@MSTR_DISCRETE.CAP(CHIPS)':
 'B': CDS_PINID='B';
NODE_NAME     C8U12 2
 '@BASEBOARD_FAB2_LIB.BASEBOARD_FAB2(SCH_1):PAGE225_I310@MSTR_DISCRETE.CAP(CHIPS)':
 'B': CDS_PINID='B';
NODE_NAME     C2G16 2
 '@BASEBOARD_FAB2_LIB.BASEBOARD_FAB2(SCH_1):PAGE225_I311@MSTR_DISCRETE.CAP(CHIPS)':
 'B': CDS_PINID='B';
NODE_NAME     C2G7 2
 '@BASEBOARD_FAB2_LIB.BASEBOARD_FAB2(SCH_1):PAGE225_I312@MSTR_DISCRETE.CAP(CHIPS)':
 'B': CDS_PINID='B';
NODE_NAME     C8P30 2
 '@BASEBOARD_FAB2_LIB.BASEBOARD_FAB2(SCH_1):PAGE225_I313@MSTR_DISCRETE.CAP(CHIPS)':
 'B': CDS_PINID='B';
NODE_NAME     C8P31 2
 '@BASEBOARD_FAB2_LIB.BASEBOARD_FAB2(SCH_1):PAGE225_I314@MSTR_DISCRETE.CAP(CHIPS)':
 'B': CDS_PINID='B';
NODE_NAME     C8P34 2
 '@BASEBOARD_FAB2_LIB.BASEBOARD_FAB2(SCH_1):PAGE225_I315@MSTR_DISCRETE.CAP(CHIPS)':
 'B': CDS_PINID='B';
NODE_NAME     C8P33 2
 '@BASEBOARD_FAB2_LIB.BASEBOARD_FAB2(SCH_1):PAGE225_I316@MSTR_DISCRETE.CAP(CHIPS)':
 'B': CDS_PINID='B';
NODE_NAME     C8P32 2
 '@BASEBOARD_FAB2_LIB.BASEBOARD_FAB2(SCH_1):PAGE225_I317@MSTR_DISCRETE.CAP(CHIPS)':
 'B': CDS_PINID='B';
NODE_NAME     C7P20 2
 '@BASEBOARD_FAB2_LIB.BASEBOARD_FAB2(SCH_1):PAGE225_I318@MSTR_DISCRETE.CAP(CHIPS)':
 'B': CDS_PINID='B';
NODE_NAME     C8U1 2
 '@BASEBOARD_FAB2_LIB.BASEBOARD_FAB2(SCH_1):PAGE225_I319@MSTR_DISCRETE.CAP(CHIPS)':
 'B': CDS_PINID='B';
NODE_NAME     C8U8 2
 '@BASEBOARD_FAB2_LIB.BASEBOARD_FAB2(SCH_1):PAGE225_I320@MSTR_DISCRETE.CAP(CHIPS)':
 'B': CDS_PINID='B';
NODE_NAME     C8L1 2
 '@BASEBOARD_FAB2_LIB.BASEBOARD_FAB2(SCH_1):PAGE228_I301@MSTR_DISCRETE.CAP(CHIPS)':
 'B': CDS_PINID='B';
NODE_NAME     C8L11 2
 '@BASEBOARD_FAB2_LIB.BASEBOARD_FAB2(SCH_1):PAGE228_I302@MSTR_DISCRETE.CAP(CHIPS)':
 'B': CDS_PINID='B';
NODE_NAME     C8P2 2
 '@BASEBOARD_FAB2_LIB.BASEBOARD_FAB2(SCH_1):PAGE228_I303@MSTR_DISCRETE.CAP(CHIPS)':
 'B': CDS_PINID='B';
NODE_NAME     C8P1 2
 '@BASEBOARD_FAB2_LIB.BASEBOARD_FAB2(SCH_1):PAGE228_I304@MSTR_DISCRETE.CAP(CHIPS)':
 'B': CDS_PINID='B';
NODE_NAME     C7P2 2
 '@BASEBOARD_FAB2_LIB.BASEBOARD_FAB2(SCH_1):PAGE228_I305@MSTR_DISCRETE.CAP(CHIPS)':
 'B': CDS_PINID='B';
NODE_NAME     C8P3 2
 '@BASEBOARD_FAB2_LIB.BASEBOARD_FAB2(SCH_1):PAGE228_I306@MSTR_DISCRETE.CAP(CHIPS)':
 'B': CDS_PINID='B';
NODE_NAME     C8P4 2
 '@BASEBOARD_FAB2_LIB.BASEBOARD_FAB2(SCH_1):PAGE228_I307@MSTR_DISCRETE.CAP(CHIPS)':
 'B': CDS_PINID='B';
NODE_NAME     C7P1 2
 '@BASEBOARD_FAB2_LIB.BASEBOARD_FAB2(SCH_1):PAGE228_I308@MSTR_DISCRETE.CAP(CHIPS)':
 'B': CDS_PINID='B';
NODE_NAME     C2A8 2
 '@BASEBOARD_FAB2_LIB.BASEBOARD_FAB2(SCH_1):PAGE228_I309@MSTR_DISCRETE.CAP(CHIPS)':
 'B': CDS_PINID='B';
NODE_NAME     C8L2 2
 '@BASEBOARD_FAB2_LIB.BASEBOARD_FAB2(SCH_1):PAGE228_I310@MSTR_DISCRETE.CAP(CHIPS)':
 'B': CDS_PINID='B';
NODE_NAME     C8M11 2
 '@BASEBOARD_FAB2_LIB.BASEBOARD_FAB2(SCH_1):PAGE228_I311@MSTR_DISCRETE.CAP(CHIPS)':
 'B': CDS_PINID='B';
NODE_NAME     C8M7 2
 '@BASEBOARD_FAB2_LIB.BASEBOARD_FAB2(SCH_1):PAGE228_I312@MSTR_DISCRETE.CAP(CHIPS)':
 'B': CDS_PINID='B';
NODE_NAME     C2A16 2
 '@BASEBOARD_FAB2_LIB.BASEBOARD_FAB2(SCH_1):PAGE228_I313@MSTR_DISCRETE.CAP(CHIPS)':
 'B': CDS_PINID='B';
NODE_NAME     C7L1 2
 '@BASEBOARD_FAB2_LIB.BASEBOARD_FAB2(SCH_1):PAGE228_I314@MSTR_DISCRETE.CAP(CHIPS)':
 'B': CDS_PINID='B';
NODE_NAME     C8T3 2
 '@BASEBOARD_FAB2_LIB.BASEBOARD_FAB2(SCH_1):PAGE229_I41@MSTR_DISCRETE.CAP(CHIPS)':
 'B': CDS_PINID='B';
NODE_NAME     C8U10 2
 '@BASEBOARD_FAB2_LIB.BASEBOARD_FAB2(SCH_1):PAGE229_I42@MSTR_DISCRETE.CAP(CHIPS)':
 'B': CDS_PINID='B';
NODE_NAME     C6W12 2
 '@BASEBOARD_FAB2_LIB.BASEBOARD_FAB2(SCH_1):PAGE229_I43@MSTR_DISCRETE.CAP(CHIPS)':
 'B': CDS_PINID='B';
NODE_NAME     C8L3 2
 '@BASEBOARD_FAB2_LIB.BASEBOARD_FAB2(SCH_1):PAGE230_I41@MSTR_DISCRETE.CAP(CHIPS)':
 'B': CDS_PINID='B';
NODE_NAME     C8L4 2
 '@BASEBOARD_FAB2_LIB.BASEBOARD_FAB2(SCH_1):PAGE230_I42@MSTR_DISCRETE.CAP(CHIPS)':
 'B': CDS_PINID='B';
NODE_NAME     C6W13 2
 '@BASEBOARD_FAB2_LIB.BASEBOARD_FAB2(SCH_1):PAGE230_I43@MSTR_DISCRETE.CAP(CHIPS)':
 'B': CDS_PINID='B';
NODE_NAME     C7C13 2
 '@BASEBOARD_FAB2_LIB.BASEBOARD_FAB2(SCH_1):PAGE114_I195@MSTR_DISCRETE.CAP(CHIPS)':
 'B': CDS_PINID='B';
NODE_NAME     C7C15 2
 '@BASEBOARD_FAB2_LIB.BASEBOARD_FAB2(SCH_1):PAGE114_I196@MSTR_DISCRETE.CAP(CHIPS)':
 'B': CDS_PINID='B';
NODE_NAME     C3N26 2
 '@BASEBOARD_FAB2_LIB.BASEBOARD_FAB2(SCH_1):PAGE212_I145@MSTR_DISCRETE.CAPP(CHIPS)':
 'B': CDS_PINID='B';
NODE_NAME     C3N38 2
 '@BASEBOARD_FAB2_LIB.BASEBOARD_FAB2(SCH_1):PAGE212_I146@MSTR_DISCRETE.CAPP(CHIPS)':
 'B': CDS_PINID='B';
NODE_NAME     C6R12 2
 '@BASEBOARD_FAB2_LIB.BASEBOARD_FAB2(SCH_1):PAGE214_I177@MSTR_DISCRETE.CAPP(CHIPS)':
 'B': CDS_PINID='B';
NODE_NAME     C4E7 2
 '@BASEBOARD_FAB2_LIB.BASEBOARD_FAB2(SCH_1):PAGE214_I178@MSTR_DISCRETE.CAPP(CHIPS)':
 'B': CDS_PINID='B';
NODE_NAME     C5P8 2
 '@BASEBOARD_FAB2_LIB.BASEBOARD_FAB2(SCH_1):PAGE42_I214@MSTR_DISCRETE.CAP(CHIPS)':
 'B': CDS_PINID='B';
NODE_NAME     C5P9 2
 '@BASEBOARD_FAB2_LIB.BASEBOARD_FAB2(SCH_1):PAGE42_I215@MSTR_DISCRETE.CAP(CHIPS)':
 'B': CDS_PINID='B';
NODE_NAME     C8P5 2
 '@BASEBOARD_FAB2_LIB.BASEBOARD_FAB2(SCH_1):PAGE76_I246@MSTR_DISCRETE.CAP(CHIPS)':
 'B': CDS_PINID='B';
NODE_NAME     C8P6 2
 '@BASEBOARD_FAB2_LIB.BASEBOARD_FAB2(SCH_1):PAGE76_I247@MSTR_DISCRETE.CAP(CHIPS)':
 'B': CDS_PINID='B';
NODE_NAME     C8P7 2
 '@BASEBOARD_FAB2_LIB.BASEBOARD_FAB2(SCH_1):PAGE76_I248@MSTR_DISCRETE.CAP(CHIPS)':
 'B': CDS_PINID='B';
NODE_NAME     C8P21 2
 '@BASEBOARD_FAB2_LIB.BASEBOARD_FAB2(SCH_1):PAGE76_I249@MSTR_DISCRETE.CAP(CHIPS)':
 'B': CDS_PINID='B';
NODE_NAME     C8P27 2
 '@BASEBOARD_FAB2_LIB.BASEBOARD_FAB2(SCH_1):PAGE76_I250@MSTR_DISCRETE.CAP(CHIPS)':
 'B': CDS_PINID='B';
NODE_NAME     C8P25 2
 '@BASEBOARD_FAB2_LIB.BASEBOARD_FAB2(SCH_1):PAGE76_I251@MSTR_DISCRETE.CAP(CHIPS)':
 'B': CDS_PINID='B';
NODE_NAME     C8P17 2
 '@BASEBOARD_FAB2_LIB.BASEBOARD_FAB2(SCH_1):PAGE76_I252@MSTR_DISCRETE.CAP(CHIPS)':
 'B': CDS_PINID='B';
NODE_NAME     R25W157 2
 '@BASEBOARD_FAB2_LIB.BASEBOARD_FAB2(SCH_1):PAGE147_I164@MSTR_DISCRETE.RES(CHIPS)':
 'B': CDS_PINID='B';
NODE_NAME     C32W1 2
 '@BASEBOARD_FAB2_LIB.BASEBOARD_FAB2(SCH_1):PAGE185_I188@DEV_DISCRETE.CAP_A(CHIPS)':
 'B': CDS_PINID='B';
NODE_NAME     C32W3 2
 '@BASEBOARD_FAB2_LIB.BASEBOARD_FAB2(SCH_1):PAGE185_I190@DEV_DISCRETE.CAP_A(CHIPS)':
 'B': CDS_PINID='B';
NODE_NAME     U32W1 4
 '@BASEBOARD_FAB2_LIB.BASEBOARD_FAB2(SCH_1):PAGE185_I191@W_HDL.TCA9517DGKR-GP(CHIPS)':
 'GND': CDS_PINID='GND';
NODE_NAME     C32W2 2
 '@BASEBOARD_FAB2_LIB.BASEBOARD_FAB2(SCH_1):PAGE185_I193@DEV_DISCRETE.CAP_A(CHIPS)':
 'B': CDS_PINID='B';
NODE_NAME     C32W4 2
 '@BASEBOARD_FAB2_LIB.BASEBOARD_FAB2(SCH_1):PAGE185_I196@DEV_DISCRETE.CAP_A(CHIPS)':
 'B': CDS_PINID='B';
NODE_NAME     R32W9 2
 '@BASEBOARD_FAB2_LIB.BASEBOARD_FAB2(SCH_1):PAGE185_I200@MSTR_DISCRETE.RES(CHIPS)':
 'B': CDS_PINID='B';
NODE_NAME     U32W2 4
 '@BASEBOARD_FAB2_LIB.BASEBOARD_FAB2(SCH_1):PAGE185_I204@W_HDL.TCA9517DGKR-GP(CHIPS)':
 'GND': CDS_PINID='GND';
NODE_NAME     R32W3 2
 '@BASEBOARD_FAB2_LIB.BASEBOARD_FAB2(SCH_1):PAGE185_I206@MSTR_DISCRETE.RES(CHIPS)':
 'B': CDS_PINID='B';
NODE_NAME     R32W4 2
 '@BASEBOARD_FAB2_LIB.BASEBOARD_FAB2(SCH_1):PAGE185_I211@MSTR_DISCRETE.RES(CHIPS)':
 'B': CDS_PINID='B';
NODE_NAME     VR32W1 3
 '@BASEBOARD_FAB2_LIB.BASEBOARD_FAB2(SCH_1):PAGE185_I213@W_HDL.LMV431AIMFX-GP(CHIPS)':
 'ANODE': CDS_PINID='ANODE';
NODE_NAME     C9E9 2
 '@BASEBOARD_FAB2_LIB.BASEBOARD_FAB2(SCH_1):PAGE139_I249@MSTR_DISCRETE.CAP(CHIPS)':
 'B': CDS_PINID='B';
NODE_NAME     C9E8 2
 '@BASEBOARD_FAB2_LIB.BASEBOARD_FAB2(SCH_1):PAGE139_I250@MSTR_DISCRETE.CAP(CHIPS)':
 'B': CDS_PINID='B';
NODE_NAME     C32W5 2
 '@BASEBOARD_FAB2_LIB.BASEBOARD_FAB2(SCH_1):PAGE185_I217@MSTR_DISCRETE.CAP(CHIPS)':
 'B': CDS_PINID='B';
NODE_NAME     Q9W3 2
 '@BASEBOARD_FAB2_LIB.BASEBOARD_FAB2(SCH_1):PAGE249_I49@MSTR_DISCRETE.NPN(CHIPS)':
 'E': CDS_PINID='E';
NODE_NAME     C4D20 2
 '@BASEBOARD_FAB2_LIB.BASEBOARD_FAB2(SCH_1):PAGE201_I192@DEV_DISCRETE.CAP_A(CHIPS)':
 'B': CDS_PINID='B';
NODE_NAME     C1C8 2
 '@BASEBOARD_FAB2_LIB.BASEBOARD_FAB2(SCH_1):PAGE206_I156@DEV_DISCRETE.CAP_A(CHIPS)':
 'B': CDS_PINID='B';
NODE_NAME     C3P2 2
 '@BASEBOARD_FAB2_LIB.BASEBOARD_FAB2(SCH_1):PAGE211_I103@DEV_DISCRETE.CAP_A(CHIPS)':
 'B': CDS_PINID='B';
NODE_NAME     C4D40 2
 '@BASEBOARD_FAB2_LIB.BASEBOARD_FAB2(SCH_1):PAGE213_I105@DEV_DISCRETE.CAP_A(CHIPS)':
 'B': CDS_PINID='B';
NODE_NAME     C8A3 2
 '@BASEBOARD_FAB2_LIB.BASEBOARD_FAB2(SCH_1):PAGE235_I255@DEV_DISCRETE.CAP_A(CHIPS)':
 'B': CDS_PINID='B';
NODE_NAME     R3W2 2
 '@BASEBOARD_FAB2_LIB.BASEBOARD_FAB2(SCH_1):PAGE249_I56@MSTR_DISCRETE.RES(CHIPS)':
 'B': CDS_PINID='B';
NODE_NAME     C3W2 2
 '@BASEBOARD_FAB2_LIB.BASEBOARD_FAB2(SCH_1):PAGE249_I57@DEV_DISCRETE.CAP_A(CHIPS)':
 'B': CDS_PINID='B';
NODE_NAME     C5W1 2
 '@BASEBOARD_FAB2_LIB.BASEBOARD_FAB2(SCH_1):PAGE42_I217@DEV_DISCRETE.CAP_A(CHIPS)':
 'B': CDS_PINID='B';
NODE_NAME     C5W2 2
 '@BASEBOARD_FAB2_LIB.BASEBOARD_FAB2(SCH_1):PAGE42_I218@DEV_DISCRETE.CAP_A(CHIPS)':
 'B': CDS_PINID='B';
NODE_NAME     C3W4 2
 '@BASEBOARD_FAB2_LIB.BASEBOARD_FAB2(SCH_1):PAGE76_I254@DEV_DISCRETE.CAP_A(CHIPS)':
 'B': CDS_PINID='B';
NODE_NAME     C3W3 2
 '@BASEBOARD_FAB2_LIB.BASEBOARD_FAB2(SCH_1):PAGE76_I256@DEV_DISCRETE.CAP_A(CHIPS)':
 'B': CDS_PINID='B';
NODE_NAME     C6W14 2
 '@BASEBOARD_FAB2_LIB.BASEBOARD_FAB2(SCH_1):PAGE164_I66@DEV_DISCRETE.CAP_A(CHIPS)':
 'B': CDS_PINID='B';
NODE_NAME     R6W47 2
 '@BASEBOARD_FAB2_LIB.BASEBOARD_FAB2(SCH_1):PAGE164_I76@MSTR_DISCRETE.RES(CHIPS)':
 'B': CDS_PINID='B';
NODE_NAME     R25W167 2
 '@BASEBOARD_FAB2_LIB.BASEBOARD_FAB2(SCH_1):PAGE269_I10@MSTR_DISCRETE.RES(CHIPS)':
 'B': CDS_PINID='B';
NODE_NAME     R25W168 2
 '@BASEBOARD_FAB2_LIB.BASEBOARD_FAB2(SCH_1):PAGE269_I11@MSTR_DISCRETE.RES(CHIPS)':
 'B': CDS_PINID='B';
NODE_NAME     R25W169 2
 '@BASEBOARD_FAB2_LIB.BASEBOARD_FAB2(SCH_1):PAGE269_I12@MSTR_DISCRETE.RES(CHIPS)':
 'B': CDS_PINID='B';
NODE_NAME     R25W170 2
 '@BASEBOARD_FAB2_LIB.BASEBOARD_FAB2(SCH_1):PAGE269_I13@MSTR_DISCRETE.RES(CHIPS)':
 'B': CDS_PINID='B';
NODE_NAME     R25W159 1
 '@BASEBOARD_FAB2_LIB.BASEBOARD_FAB2(SCH_1):PAGE269_I24@MSTR_DISCRETE.RES(CHIPS)':
 'A': CDS_PINID='A';
NODE_NAME     C25W91 2
 '@BASEBOARD_FAB2_LIB.BASEBOARD_FAB2(SCH_1):PAGE269_I26@DEV_DISCRETE.CAP_A(CHIPS)':
 'B': CDS_PINID='B';
NODE_NAME     C25W94 2
 '@BASEBOARD_FAB2_LIB.BASEBOARD_FAB2(SCH_1):PAGE269_I32@MSTR_DISCRETE.CAP(CHIPS)':
 'B': CDS_PINID='B';
NODE_NAME     U25W10 7
 '@BASEBOARD_FAB2_LIB.BASEBOARD_FAB2(SCH_1):PAGE269_I49@MSTR_DIGITAL.GTL2014(CHIPS)':
 'GND'<0>: CDS_PINID='GND(0)';
NODE_NAME     U25W10 8
 '@BASEBOARD_FAB2_LIB.BASEBOARD_FAB2(SCH_1):PAGE269_I49@MSTR_DIGITAL.GTL2014(CHIPS)':
 'GND'<1>: CDS_PINID='GND(1)';
NODE_NAME     U25W10 11
 '@BASEBOARD_FAB2_LIB.BASEBOARD_FAB2(SCH_1):PAGE269_I49@MSTR_DIGITAL.GTL2014(CHIPS)':
 'GND'<2>: CDS_PINID='GND(2)';
NODE_NAME     C25W97 2
 '@BASEBOARD_FAB2_LIB.BASEBOARD_FAB2(SCH_1):PAGE268_I4@DEV_DISCRETE.CAP_A(CHIPS)':
 'B': CDS_PINID='B';
NODE_NAME     C25W96 2
 '@BASEBOARD_FAB2_LIB.BASEBOARD_FAB2(SCH_1):PAGE268_I9@DEV_DISCRETE.CAP_A(CHIPS)':
 'B': CDS_PINID='B';
NODE_NAME     R25W176 2
 '@BASEBOARD_FAB2_LIB.BASEBOARD_FAB2(SCH_1):PAGE268_I14@MSTR_DISCRETE.RES(CHIPS)':
 'B': CDS_PINID='B';
NODE_NAME     R25W175 2
 '@BASEBOARD_FAB2_LIB.BASEBOARD_FAB2(SCH_1):PAGE268_I17@MSTR_DISCRETE.RES(CHIPS)':
 'B': CDS_PINID='B';
NODE_NAME     C25W92 2
 '@BASEBOARD_FAB2_LIB.BASEBOARD_FAB2(SCH_1):PAGE268_I23@MSTR_DISCRETE.CAP(CHIPS)':
 'B': CDS_PINID='B';
NODE_NAME     R25W166 2
 '@BASEBOARD_FAB2_LIB.BASEBOARD_FAB2(SCH_1):PAGE268_I26@MSTR_DISCRETE.RES(CHIPS)':
 'B': CDS_PINID='B';
NODE_NAME     C25W93 2
 '@BASEBOARD_FAB2_LIB.BASEBOARD_FAB2(SCH_1):PAGE268_I27@DEV_DISCRETE.CAP_A(CHIPS)':
 'B': CDS_PINID='B';
NODE_NAME     R25W165 2
 '@BASEBOARD_FAB2_LIB.BASEBOARD_FAB2(SCH_1):PAGE268_I28@MSTR_DISCRETE.RES(CHIPS)':
 'B': CDS_PINID='B';
NODE_NAME     U25W11 7
 '@BASEBOARD_FAB2_LIB.BASEBOARD_FAB2(SCH_1):PAGE268_I33@MSTR_DIGITAL.GTL2014(CHIPS)':
 'GND'<0>: CDS_PINID='GND(0)';
NODE_NAME     U25W11 8
 '@BASEBOARD_FAB2_LIB.BASEBOARD_FAB2(SCH_1):PAGE268_I33@MSTR_DIGITAL.GTL2014(CHIPS)':
 'GND'<1>: CDS_PINID='GND(1)';
NODE_NAME     U25W11 11
 '@BASEBOARD_FAB2_LIB.BASEBOARD_FAB2(SCH_1):PAGE268_I33@MSTR_DIGITAL.GTL2014(CHIPS)':
 'GND'<2>: CDS_PINID='GND(2)';
NODE_NAME     U25W13 5
 '@BASEBOARD_FAB2_LIB.BASEBOARD_FAB2(SCH_1):PAGE269_I53@W_HDL.MAX4564EKA-GP(CHIPS)':
 'GND': CDS_PINID='GND';
NODE_NAME     U25W13 6
 '@BASEBOARD_FAB2_LIB.BASEBOARD_FAB2(SCH_1):PAGE269_I53@W_HDL.MAX4564EKA-GP(CHIPS)':
 'V-': CDS_PINID='\v-\';
NODE_NAME     C25W95 2
 '@BASEBOARD_FAB2_LIB.BASEBOARD_FAB2(SCH_1):PAGE269_I56@DEV_DISCRETE.CAP_A(CHIPS)':
 'B': CDS_PINID='B';
NODE_NAME     R6W46 2
 '@BASEBOARD_FAB2_LIB.BASEBOARD_FAB2(SCH_1):PAGE164_I93@MSTR_DISCRETE.RES(CHIPS)':
 'B': CDS_PINID='B';
NODE_NAME     R6W45 2
 '@BASEBOARD_FAB2_LIB.BASEBOARD_FAB2(SCH_1):PAGE164_I94@MSTR_DISCRETE.RES(CHIPS)':
 'B': CDS_PINID='B';
NODE_NAME     C25W29 2
 '@BASEBOARD_FAB2_LIB.BASEBOARD_FAB2(SCH_1):PAGE149_I129@MSTR_DISCRETE.CAP(CHIPS)':
 'B': CDS_PINID='B';
NODE_NAME     C25W57 2
 '@BASEBOARD_FAB2_LIB.BASEBOARD_FAB2(SCH_1):PAGE149_I130@MSTR_DISCRETE.CAP(CHIPS)':
 'B': CDS_PINID='B';
NODE_NAME     Q6W2 2
 '@BASEBOARD_FAB2_LIB.BASEBOARD_FAB2(SCH_1):PAGE168_I47@MSTR_DISCRETE.NPN(CHIPS)':
 'E': CDS_PINID='E';
NODE_NAME     U6W11 8
 '@BASEBOARD_FAB2_LIB.BASEBOARD_FAB2(SCH_1):PAGE164_I97@W_HDL.PCA9554PWR-GP(CHIPS)':
 'GND': CDS_PINID='GND';
NODE_NAME     C1L119 2
 '@BASEBOARD_FAB2_LIB.BASEBOARD_FAB2(SCH_1):PAGE189_I69@MSTR_DISCRETE.CAP(CHIPS)':
 'B': CDS_PINID='B';
NODE_NAME     C4E29 2
 '@BASEBOARD_FAB2_LIB.BASEBOARD_FAB2(SCH_1):PAGE193_I175@MSTR_DISCRETE.CAPP(CHIPS)':
 'B': CDS_PINID='B';
NODE_NAME     C5P29 2
 '@BASEBOARD_FAB2_LIB.BASEBOARD_FAB2(SCH_1):PAGE42_I220@MSTR_DISCRETE.CAP(CHIPS)':
 'B': CDS_PINID='B';
NODE_NAME     C5P30 2
 '@BASEBOARD_FAB2_LIB.BASEBOARD_FAB2(SCH_1):PAGE42_I221@MSTR_DISCRETE.CAP(CHIPS)':
 'B': CDS_PINID='B';
NODE_NAME     C5P19 2
 '@BASEBOARD_FAB2_LIB.BASEBOARD_FAB2(SCH_1):PAGE42_I222@MSTR_DISCRETE.CAP(CHIPS)':
 'B': CDS_PINID='B';
NODE_NAME     C4P4 2
 '@BASEBOARD_FAB2_LIB.BASEBOARD_FAB2(SCH_1):PAGE42_I223@MSTR_DISCRETE.CAP(CHIPS)':
 'B': CDS_PINID='B';
NODE_NAME     C4P7 2
 '@BASEBOARD_FAB2_LIB.BASEBOARD_FAB2(SCH_1):PAGE42_I224@MSTR_DISCRETE.CAP(CHIPS)':
 'B': CDS_PINID='B';
NODE_NAME     C4P3 2
 '@BASEBOARD_FAB2_LIB.BASEBOARD_FAB2(SCH_1):PAGE42_I225@MSTR_DISCRETE.CAP(CHIPS)':
 'B': CDS_PINID='B';
NODE_NAME     C5P10 2
 '@BASEBOARD_FAB2_LIB.BASEBOARD_FAB2(SCH_1):PAGE42_I226@MSTR_DISCRETE.CAP(CHIPS)':
 'B': CDS_PINID='B';
NODE_NAME     C5P11 2
 '@BASEBOARD_FAB2_LIB.BASEBOARD_FAB2(SCH_1):PAGE42_I227@MSTR_DISCRETE.CAP(CHIPS)':
 'B': CDS_PINID='B';
NODE_NAME     C5P18 2
 '@BASEBOARD_FAB2_LIB.BASEBOARD_FAB2(SCH_1):PAGE42_I228@MSTR_DISCRETE.CAP(CHIPS)':
 'B': CDS_PINID='B';
NODE_NAME     C5P28 2
 '@BASEBOARD_FAB2_LIB.BASEBOARD_FAB2(SCH_1):PAGE42_I229@MSTR_DISCRETE.CAP(CHIPS)':
 'B': CDS_PINID='B';
NODE_NAME     C4P2 2
 '@BASEBOARD_FAB2_LIB.BASEBOARD_FAB2(SCH_1):PAGE42_I230@MSTR_DISCRETE.CAP(CHIPS)':
 'B': CDS_PINID='B';
NODE_NAME     C5P31 2
 '@BASEBOARD_FAB2_LIB.BASEBOARD_FAB2(SCH_1):PAGE42_I231@MSTR_DISCRETE.CAP(CHIPS)':
 'B': CDS_PINID='B';
NODE_NAME     C5P13 2
 '@BASEBOARD_FAB2_LIB.BASEBOARD_FAB2(SCH_1):PAGE42_I232@MSTR_DISCRETE.CAP(CHIPS)':
 'B': CDS_PINID='B';
NODE_NAME     C4P5 2
 '@BASEBOARD_FAB2_LIB.BASEBOARD_FAB2(SCH_1):PAGE42_I233@MSTR_DISCRETE.CAP(CHIPS)':
 'B': CDS_PINID='B';
NODE_NAME     C5P20 2
 '@BASEBOARD_FAB2_LIB.BASEBOARD_FAB2(SCH_1):PAGE42_I234@MSTR_DISCRETE.CAP(CHIPS)':
 'B': CDS_PINID='B';
NODE_NAME     C5P21 2
 '@BASEBOARD_FAB2_LIB.BASEBOARD_FAB2(SCH_1):PAGE42_I235@MSTR_DISCRETE.CAP(CHIPS)':
 'B': CDS_PINID='B';
NODE_NAME     C5P12 2
 '@BASEBOARD_FAB2_LIB.BASEBOARD_FAB2(SCH_1):PAGE42_I236@MSTR_DISCRETE.CAP(CHIPS)':
 'B': CDS_PINID='B';
NODE_NAME     C7P9 2
 '@BASEBOARD_FAB2_LIB.BASEBOARD_FAB2(SCH_1):PAGE76_I258@MSTR_DISCRETE.CAP(CHIPS)':
 'B': CDS_PINID='B';
NODE_NAME     C7P5 2
 '@BASEBOARD_FAB2_LIB.BASEBOARD_FAB2(SCH_1):PAGE76_I259@MSTR_DISCRETE.CAP(CHIPS)':
 'B': CDS_PINID='B';
NODE_NAME     C8P23 2
 '@BASEBOARD_FAB2_LIB.BASEBOARD_FAB2(SCH_1):PAGE76_I260@MSTR_DISCRETE.CAP(CHIPS)':
 'B': CDS_PINID='B';
NODE_NAME     C7P14 2
 '@BASEBOARD_FAB2_LIB.BASEBOARD_FAB2(SCH_1):PAGE76_I261@MSTR_DISCRETE.CAP(CHIPS)':
 'B': CDS_PINID='B';
NODE_NAME     C7P11 2
 '@BASEBOARD_FAB2_LIB.BASEBOARD_FAB2(SCH_1):PAGE76_I262@MSTR_DISCRETE.CAP(CHIPS)':
 'B': CDS_PINID='B';
NODE_NAME     C7P15 2
 '@BASEBOARD_FAB2_LIB.BASEBOARD_FAB2(SCH_1):PAGE76_I263@MSTR_DISCRETE.CAP(CHIPS)':
 'B': CDS_PINID='B';
NODE_NAME     C8P22 2
 '@BASEBOARD_FAB2_LIB.BASEBOARD_FAB2(SCH_1):PAGE76_I264@MSTR_DISCRETE.CAP(CHIPS)':
 'B': CDS_PINID='B';
NODE_NAME     C7P8 2
 '@BASEBOARD_FAB2_LIB.BASEBOARD_FAB2(SCH_1):PAGE76_I265@MSTR_DISCRETE.CAP(CHIPS)':
 'B': CDS_PINID='B';
NODE_NAME     C7P10 2
 '@BASEBOARD_FAB2_LIB.BASEBOARD_FAB2(SCH_1):PAGE76_I266@MSTR_DISCRETE.CAP(CHIPS)':
 'B': CDS_PINID='B';
NODE_NAME     C7P7 2
 '@BASEBOARD_FAB2_LIB.BASEBOARD_FAB2(SCH_1):PAGE76_I267@MSTR_DISCRETE.CAP(CHIPS)':
 'B': CDS_PINID='B';
NODE_NAME     C7P6 2
 '@BASEBOARD_FAB2_LIB.BASEBOARD_FAB2(SCH_1):PAGE76_I268@MSTR_DISCRETE.CAP(CHIPS)':
 'B': CDS_PINID='B';
NODE_NAME     C7P13 2
 '@BASEBOARD_FAB2_LIB.BASEBOARD_FAB2(SCH_1):PAGE76_I269@MSTR_DISCRETE.CAP(CHIPS)':
 'B': CDS_PINID='B';
NODE_NAME     C8P15 2
 '@BASEBOARD_FAB2_LIB.BASEBOARD_FAB2(SCH_1):PAGE76_I270@MSTR_DISCRETE.CAP(CHIPS)':
 'B': CDS_PINID='B';
NODE_NAME     C7P4 2
 '@BASEBOARD_FAB2_LIB.BASEBOARD_FAB2(SCH_1):PAGE76_I271@MSTR_DISCRETE.CAP(CHIPS)':
 'B': CDS_PINID='B';
NODE_NAME     C8P14 2
 '@BASEBOARD_FAB2_LIB.BASEBOARD_FAB2(SCH_1):PAGE76_I272@MSTR_DISCRETE.CAP(CHIPS)':
 'B': CDS_PINID='B';
NODE_NAME     C8P9 2
 '@BASEBOARD_FAB2_LIB.BASEBOARD_FAB2(SCH_1):PAGE76_I273@MSTR_DISCRETE.CAP(CHIPS)':
 'B': CDS_PINID='B';
NODE_NAME     C8P8 2
 '@BASEBOARD_FAB2_LIB.BASEBOARD_FAB2(SCH_1):PAGE76_I274@MSTR_DISCRETE.CAP(CHIPS)':
 'B': CDS_PINID='B';
NODE_NAME     C25W98 2
 '@BASEBOARD_FAB2_LIB.BASEBOARD_FAB2(SCH_1):PAGE268_I40@MSTR_DISCRETE.CAP(CHIPS)':
 'B': CDS_PINID='B';
NODE_NAME     Q25W5 2
 '@BASEBOARD_FAB2_LIB.BASEBOARD_FAB2(SCH_1):PAGE268_I51@MSTR_DISCRETE.FET_N(CHIPS)':
 'SRC': CDS_PINID='SRC';
NODE_NAME     EU1D4 2
 '@BASEBOARD_FAB2_LIB.BASEBOARD_FAB2(SCH_1):PAGE207_I113@MSTR_DISCRETE.IR354XX(CHIPS)':
 'LGND': CDS_PINID='LGND';
NODE_NAME     EU1D4 5
 '@BASEBOARD_FAB2_LIB.BASEBOARD_FAB2(SCH_1):PAGE207_I113@MSTR_DISCRETE.IR354XX(CHIPS)':
 'PGND'<0>: CDS_PINID='PGND(0)';
NODE_NAME     EU1D4 7
 '@BASEBOARD_FAB2_LIB.BASEBOARD_FAB2(SCH_1):PAGE207_I113@MSTR_DISCRETE.IR354XX(CHIPS)':
 'PGND'<1>: CDS_PINID='PGND(1)';
NODE_NAME     EU1D4 40
 '@BASEBOARD_FAB2_LIB.BASEBOARD_FAB2(SCH_1):PAGE207_I113@MSTR_DISCRETE.IR354XX(CHIPS)':
 'PGND'<2>: CDS_PINID='PGND(2)';
NODE_NAME     C25W99 2
 '@BASEBOARD_FAB2_LIB.BASEBOARD_FAB2(SCH_1):PAGE269_I62@DEV_DISCRETE.CAP_A(CHIPS)':
 'B': CDS_PINID='B';
NODE_NAME     C25W100 2
 '@BASEBOARD_FAB2_LIB.BASEBOARD_FAB2(SCH_1):PAGE268_I60@DEV_DISCRETE.CAP_A(CHIPS)':
 'B': CDS_PINID='B';
NODE_NAME     C9W14 2
 '@BASEBOARD_FAB2_LIB.BASEBOARD_FAB2(SCH_1):PAGE238_I46@MSTR_DISCRETE.CAP(CHIPS)':
 'B': CDS_PINID='B';
NODE_NAME     C9W17 2
 '@BASEBOARD_FAB2_LIB.BASEBOARD_FAB2(SCH_1):PAGE239_I104@MSTR_DISCRETE.CAP(CHIPS)':
 'B': CDS_PINID='B';
NODE_NAME     C9W16 2
 '@BASEBOARD_FAB2_LIB.BASEBOARD_FAB2(SCH_1):PAGE238_I50@DEV_DISCRETE.CAP_A(CHIPS)':
 'B': CDS_PINID='B';
NODE_NAME     C9W19 2
 '@BASEBOARD_FAB2_LIB.BASEBOARD_FAB2(SCH_1):PAGE239_I111@DEV_DISCRETE.CAP_A(CHIPS)':
 'B': CDS_PINID='B';
NODE_NAME     S9W1 3
 '@BASEBOARD_FAB2_LIB.BASEBOARD_FAB2(SCH_1):PAGE268_I63@W_HDL.SW-SLIDE75-GP(CHIPS)':
 '3': CDS_PINID='\3\';
NODE_NAME     S9W1 4
 '@BASEBOARD_FAB2_LIB.BASEBOARD_FAB2(SCH_1):PAGE268_I63@W_HDL.SW-SLIDE75-GP(CHIPS)':
 '4': CDS_PINID='\4\';
NODE_NAME     S9W1 5
 '@BASEBOARD_FAB2_LIB.BASEBOARD_FAB2(SCH_1):PAGE268_I63@W_HDL.SW-SLIDE75-GP(CHIPS)':
 '5': CDS_PINID='\5\';
NODE_NAME     S9W1 6
 '@BASEBOARD_FAB2_LIB.BASEBOARD_FAB2(SCH_1):PAGE268_I63@W_HDL.SW-SLIDE75-GP(CHIPS)':
 '6': CDS_PINID='\6\';
NODE_NAME     S9W1 7
 '@BASEBOARD_FAB2_LIB.BASEBOARD_FAB2(SCH_1):PAGE268_I63@W_HDL.SW-SLIDE75-GP(CHIPS)':
 '7': CDS_PINID='\7\';
NODE_NAME     C1G15 2
 '@BASEBOARD_FAB2_LIB.BASEBOARD_FAB2(SCH_1):PAGE225_I327@W_HDL.ST270U2D5VBM-GP(CHIPS)':
 '2': CDS_PINID='\2\';
NODE_NAME     C1G12 2
 '@BASEBOARD_FAB2_LIB.BASEBOARD_FAB2(SCH_1):PAGE225_I328@W_HDL.ST270U2D5VBM-GP(CHIPS)':
 '2': CDS_PINID='\2\';
NODE_NAME     C1G7 2
 '@BASEBOARD_FAB2_LIB.BASEBOARD_FAB2(SCH_1):PAGE225_I329@W_HDL.ST270U2D5VBM-GP(CHIPS)':
 '2': CDS_PINID='\2\';
NODE_NAME     C7W2 2
 '@BASEBOARD_FAB2_LIB.BASEBOARD_FAB2(SCH_1):PAGE220_I324@W_HDL.SE100U16VM-48-GP(CHIPS)':
 '2': CDS_PINID='\2\';
NODE_NAME     T1P1 GND1
 '@BASEBOARD_FAB2_LIB.BASEBOARD_FAB2(SCH_1):PAGE271_I3@W_HDL.TPAD-DIFF-4P-GP(CHIPS)':
 'GND1': CDS_PINID='GND1';
NODE_NAME     T1P1 GND2
 '@BASEBOARD_FAB2_LIB.BASEBOARD_FAB2(SCH_1):PAGE271_I3@W_HDL.TPAD-DIFF-4P-GP(CHIPS)':
 'GND2': CDS_PINID='GND2';
NODE_NAME     T1D1 3
 '@BASEBOARD_FAB2_LIB.BASEBOARD_FAB2(SCH_1):PAGE270_I1@W_HDL.TEST-PAD-12P-1-GP-U(CHIPS)':
 'GND'<0>: CDS_PINID='GND(0)';
NODE_NAME     T1D1 4
 '@BASEBOARD_FAB2_LIB.BASEBOARD_FAB2(SCH_1):PAGE270_I1@W_HDL.TEST-PAD-12P-1-GP-U(CHIPS)':
 'GND'<1>: CDS_PINID='GND(1)';
NODE_NAME     T1D1 5
 '@BASEBOARD_FAB2_LIB.BASEBOARD_FAB2(SCH_1):PAGE270_I1@W_HDL.TEST-PAD-12P-1-GP-U(CHIPS)':
 'GND'<2>: CDS_PINID='GND(2)';
NODE_NAME     T1D1 6
 '@BASEBOARD_FAB2_LIB.BASEBOARD_FAB2(SCH_1):PAGE270_I1@W_HDL.TEST-PAD-12P-1-GP-U(CHIPS)':
 'GND'<3>: CDS_PINID='GND(3)';
NODE_NAME     T1D1 7
 '@BASEBOARD_FAB2_LIB.BASEBOARD_FAB2(SCH_1):PAGE270_I1@W_HDL.TEST-PAD-12P-1-GP-U(CHIPS)':
 'GND'<4>: CDS_PINID='GND(4)';
NODE_NAME     T1D1 8
 '@BASEBOARD_FAB2_LIB.BASEBOARD_FAB2(SCH_1):PAGE270_I1@W_HDL.TEST-PAD-12P-1-GP-U(CHIPS)':
 'GND'<5>: CDS_PINID='GND(5)';
NODE_NAME     T1D1 9
 '@BASEBOARD_FAB2_LIB.BASEBOARD_FAB2(SCH_1):PAGE270_I1@W_HDL.TEST-PAD-12P-1-GP-U(CHIPS)':
 'GND'<6>: CDS_PINID='GND(6)';
NODE_NAME     T1D1 10
 '@BASEBOARD_FAB2_LIB.BASEBOARD_FAB2(SCH_1):PAGE270_I1@W_HDL.TEST-PAD-12P-1-GP-U(CHIPS)':
 'GND'<7>: CDS_PINID='GND(7)';
NODE_NAME     T1D1 11
 '@BASEBOARD_FAB2_LIB.BASEBOARD_FAB2(SCH_1):PAGE270_I1@W_HDL.TEST-PAD-12P-1-GP-U(CHIPS)':
 'GND'<8>: CDS_PINID='GND(8)';
NODE_NAME     T1D1 12
 '@BASEBOARD_FAB2_LIB.BASEBOARD_FAB2(SCH_1):PAGE270_I1@W_HDL.TEST-PAD-12P-1-GP-U(CHIPS)':
 'GND'<9>: CDS_PINID='GND(9)';
NODE_NAME     T1D2 3
 '@BASEBOARD_FAB2_LIB.BASEBOARD_FAB2(SCH_1):PAGE270_I3@W_HDL.TEST-PAD-12P-1-GP-U(CHIPS)':
 'GND'<0>: CDS_PINID='GND(0)';
NODE_NAME     T1D2 4
 '@BASEBOARD_FAB2_LIB.BASEBOARD_FAB2(SCH_1):PAGE270_I3@W_HDL.TEST-PAD-12P-1-GP-U(CHIPS)':
 'GND'<1>: CDS_PINID='GND(1)';
NODE_NAME     T1D2 5
 '@BASEBOARD_FAB2_LIB.BASEBOARD_FAB2(SCH_1):PAGE270_I3@W_HDL.TEST-PAD-12P-1-GP-U(CHIPS)':
 'GND'<2>: CDS_PINID='GND(2)';
NODE_NAME     T1D2 6
 '@BASEBOARD_FAB2_LIB.BASEBOARD_FAB2(SCH_1):PAGE270_I3@W_HDL.TEST-PAD-12P-1-GP-U(CHIPS)':
 'GND'<3>: CDS_PINID='GND(3)';
NODE_NAME     T1D2 7
 '@BASEBOARD_FAB2_LIB.BASEBOARD_FAB2(SCH_1):PAGE270_I3@W_HDL.TEST-PAD-12P-1-GP-U(CHIPS)':
 'GND'<4>: CDS_PINID='GND(4)';
NODE_NAME     T1D2 8
 '@BASEBOARD_FAB2_LIB.BASEBOARD_FAB2(SCH_1):PAGE270_I3@W_HDL.TEST-PAD-12P-1-GP-U(CHIPS)':
 'GND'<5>: CDS_PINID='GND(5)';
NODE_NAME     T1D2 9
 '@BASEBOARD_FAB2_LIB.BASEBOARD_FAB2(SCH_1):PAGE270_I3@W_HDL.TEST-PAD-12P-1-GP-U(CHIPS)':
 'GND'<6>: CDS_PINID='GND(6)';
NODE_NAME     T1D2 10
 '@BASEBOARD_FAB2_LIB.BASEBOARD_FAB2(SCH_1):PAGE270_I3@W_HDL.TEST-PAD-12P-1-GP-U(CHIPS)':
 'GND'<7>: CDS_PINID='GND(7)';
NODE_NAME     T1D2 11
 '@BASEBOARD_FAB2_LIB.BASEBOARD_FAB2(SCH_1):PAGE270_I3@W_HDL.TEST-PAD-12P-1-GP-U(CHIPS)':
 'GND'<8>: CDS_PINID='GND(8)';
NODE_NAME     T1D2 12
 '@BASEBOARD_FAB2_LIB.BASEBOARD_FAB2(SCH_1):PAGE270_I3@W_HDL.TEST-PAD-12P-1-GP-U(CHIPS)':
 'GND'<9>: CDS_PINID='GND(9)';
NODE_NAME     T1D3 3
 '@BASEBOARD_FAB2_LIB.BASEBOARD_FAB2(SCH_1):PAGE270_I5@W_HDL.TEST-PAD-12P-1-GP-U(CHIPS)':
 'GND'<0>: CDS_PINID='GND(0)';
NODE_NAME     T1D3 4
 '@BASEBOARD_FAB2_LIB.BASEBOARD_FAB2(SCH_1):PAGE270_I5@W_HDL.TEST-PAD-12P-1-GP-U(CHIPS)':
 'GND'<1>: CDS_PINID='GND(1)';
NODE_NAME     T1D3 5
 '@BASEBOARD_FAB2_LIB.BASEBOARD_FAB2(SCH_1):PAGE270_I5@W_HDL.TEST-PAD-12P-1-GP-U(CHIPS)':
 'GND'<2>: CDS_PINID='GND(2)';
NODE_NAME     T1D3 6
 '@BASEBOARD_FAB2_LIB.BASEBOARD_FAB2(SCH_1):PAGE270_I5@W_HDL.TEST-PAD-12P-1-GP-U(CHIPS)':
 'GND'<3>: CDS_PINID='GND(3)';
NODE_NAME     T1D3 7
 '@BASEBOARD_FAB2_LIB.BASEBOARD_FAB2(SCH_1):PAGE270_I5@W_HDL.TEST-PAD-12P-1-GP-U(CHIPS)':
 'GND'<4>: CDS_PINID='GND(4)';
NODE_NAME     T1D3 8
 '@BASEBOARD_FAB2_LIB.BASEBOARD_FAB2(SCH_1):PAGE270_I5@W_HDL.TEST-PAD-12P-1-GP-U(CHIPS)':
 'GND'<5>: CDS_PINID='GND(5)';
NODE_NAME     T1D3 9
 '@BASEBOARD_FAB2_LIB.BASEBOARD_FAB2(SCH_1):PAGE270_I5@W_HDL.TEST-PAD-12P-1-GP-U(CHIPS)':
 'GND'<6>: CDS_PINID='GND(6)';
NODE_NAME     T1D3 10
 '@BASEBOARD_FAB2_LIB.BASEBOARD_FAB2(SCH_1):PAGE270_I5@W_HDL.TEST-PAD-12P-1-GP-U(CHIPS)':
 'GND'<7>: CDS_PINID='GND(7)';
NODE_NAME     T1D3 11
 '@BASEBOARD_FAB2_LIB.BASEBOARD_FAB2(SCH_1):PAGE270_I5@W_HDL.TEST-PAD-12P-1-GP-U(CHIPS)':
 'GND'<8>: CDS_PINID='GND(8)';
NODE_NAME     T1D3 12
 '@BASEBOARD_FAB2_LIB.BASEBOARD_FAB2(SCH_1):PAGE270_I5@W_HDL.TEST-PAD-12P-1-GP-U(CHIPS)':
 'GND'<9>: CDS_PINID='GND(9)';
NODE_NAME     T1D4 3
 '@BASEBOARD_FAB2_LIB.BASEBOARD_FAB2(SCH_1):PAGE270_I6@W_HDL.TEST-PAD-12P-1-GP-U(CHIPS)':
 'GND'<0>: CDS_PINID='GND(0)';
NODE_NAME     T1D4 4
 '@BASEBOARD_FAB2_LIB.BASEBOARD_FAB2(SCH_1):PAGE270_I6@W_HDL.TEST-PAD-12P-1-GP-U(CHIPS)':
 'GND'<1>: CDS_PINID='GND(1)';
NODE_NAME     T1D4 5
 '@BASEBOARD_FAB2_LIB.BASEBOARD_FAB2(SCH_1):PAGE270_I6@W_HDL.TEST-PAD-12P-1-GP-U(CHIPS)':
 'GND'<2>: CDS_PINID='GND(2)';
NODE_NAME     T1D4 6
 '@BASEBOARD_FAB2_LIB.BASEBOARD_FAB2(SCH_1):PAGE270_I6@W_HDL.TEST-PAD-12P-1-GP-U(CHIPS)':
 'GND'<3>: CDS_PINID='GND(3)';
NODE_NAME     T1D4 7
 '@BASEBOARD_FAB2_LIB.BASEBOARD_FAB2(SCH_1):PAGE270_I6@W_HDL.TEST-PAD-12P-1-GP-U(CHIPS)':
 'GND'<4>: CDS_PINID='GND(4)';
NODE_NAME     T1D4 8
 '@BASEBOARD_FAB2_LIB.BASEBOARD_FAB2(SCH_1):PAGE270_I6@W_HDL.TEST-PAD-12P-1-GP-U(CHIPS)':
 'GND'<5>: CDS_PINID='GND(5)';
NODE_NAME     T1D4 9
 '@BASEBOARD_FAB2_LIB.BASEBOARD_FAB2(SCH_1):PAGE270_I6@W_HDL.TEST-PAD-12P-1-GP-U(CHIPS)':
 'GND'<6>: CDS_PINID='GND(6)';
NODE_NAME     T1D4 10
 '@BASEBOARD_FAB2_LIB.BASEBOARD_FAB2(SCH_1):PAGE270_I6@W_HDL.TEST-PAD-12P-1-GP-U(CHIPS)':
 'GND'<7>: CDS_PINID='GND(7)';
NODE_NAME     T1D4 11
 '@BASEBOARD_FAB2_LIB.BASEBOARD_FAB2(SCH_1):PAGE270_I6@W_HDL.TEST-PAD-12P-1-GP-U(CHIPS)':
 'GND'<8>: CDS_PINID='GND(8)';
NODE_NAME     T1D4 12
 '@BASEBOARD_FAB2_LIB.BASEBOARD_FAB2(SCH_1):PAGE270_I6@W_HDL.TEST-PAD-12P-1-GP-U(CHIPS)':
 'GND'<9>: CDS_PINID='GND(9)';
NODE_NAME     T1D6 3
 '@BASEBOARD_FAB2_LIB.BASEBOARD_FAB2(SCH_1):PAGE270_I9@W_HDL.TEST-PAD-12P-1-GP-U(CHIPS)':
 'GND'<0>: CDS_PINID='GND(0)';
NODE_NAME     T1D6 4
 '@BASEBOARD_FAB2_LIB.BASEBOARD_FAB2(SCH_1):PAGE270_I9@W_HDL.TEST-PAD-12P-1-GP-U(CHIPS)':
 'GND'<1>: CDS_PINID='GND(1)';
NODE_NAME     T1D6 5
 '@BASEBOARD_FAB2_LIB.BASEBOARD_FAB2(SCH_1):PAGE270_I9@W_HDL.TEST-PAD-12P-1-GP-U(CHIPS)':
 'GND'<2>: CDS_PINID='GND(2)';
NODE_NAME     T1D6 6
 '@BASEBOARD_FAB2_LIB.BASEBOARD_FAB2(SCH_1):PAGE270_I9@W_HDL.TEST-PAD-12P-1-GP-U(CHIPS)':
 'GND'<3>: CDS_PINID='GND(3)';
NODE_NAME     T1D6 7
 '@BASEBOARD_FAB2_LIB.BASEBOARD_FAB2(SCH_1):PAGE270_I9@W_HDL.TEST-PAD-12P-1-GP-U(CHIPS)':
 'GND'<4>: CDS_PINID='GND(4)';
NODE_NAME     T1D6 8
 '@BASEBOARD_FAB2_LIB.BASEBOARD_FAB2(SCH_1):PAGE270_I9@W_HDL.TEST-PAD-12P-1-GP-U(CHIPS)':
 'GND'<5>: CDS_PINID='GND(5)';
NODE_NAME     T1D6 9
 '@BASEBOARD_FAB2_LIB.BASEBOARD_FAB2(SCH_1):PAGE270_I9@W_HDL.TEST-PAD-12P-1-GP-U(CHIPS)':
 'GND'<6>: CDS_PINID='GND(6)';
NODE_NAME     T1D6 10
 '@BASEBOARD_FAB2_LIB.BASEBOARD_FAB2(SCH_1):PAGE270_I9@W_HDL.TEST-PAD-12P-1-GP-U(CHIPS)':
 'GND'<7>: CDS_PINID='GND(7)';
NODE_NAME     T1D6 11
 '@BASEBOARD_FAB2_LIB.BASEBOARD_FAB2(SCH_1):PAGE270_I9@W_HDL.TEST-PAD-12P-1-GP-U(CHIPS)':
 'GND'<8>: CDS_PINID='GND(8)';
NODE_NAME     T1D6 12
 '@BASEBOARD_FAB2_LIB.BASEBOARD_FAB2(SCH_1):PAGE270_I9@W_HDL.TEST-PAD-12P-1-GP-U(CHIPS)':
 'GND'<9>: CDS_PINID='GND(9)';
NODE_NAME     T1D5 3
 '@BASEBOARD_FAB2_LIB.BASEBOARD_FAB2(SCH_1):PAGE270_I12@W_HDL.TEST-PAD-12P-1-GP-U(CHIPS)':
 'GND'<0>: CDS_PINID='GND(0)';
NODE_NAME     T1D5 4
 '@BASEBOARD_FAB2_LIB.BASEBOARD_FAB2(SCH_1):PAGE270_I12@W_HDL.TEST-PAD-12P-1-GP-U(CHIPS)':
 'GND'<1>: CDS_PINID='GND(1)';
NODE_NAME     T1D5 5
 '@BASEBOARD_FAB2_LIB.BASEBOARD_FAB2(SCH_1):PAGE270_I12@W_HDL.TEST-PAD-12P-1-GP-U(CHIPS)':
 'GND'<2>: CDS_PINID='GND(2)';
NODE_NAME     T1D5 6
 '@BASEBOARD_FAB2_LIB.BASEBOARD_FAB2(SCH_1):PAGE270_I12@W_HDL.TEST-PAD-12P-1-GP-U(CHIPS)':
 'GND'<3>: CDS_PINID='GND(3)';
NODE_NAME     T1D5 7
 '@BASEBOARD_FAB2_LIB.BASEBOARD_FAB2(SCH_1):PAGE270_I12@W_HDL.TEST-PAD-12P-1-GP-U(CHIPS)':
 'GND'<4>: CDS_PINID='GND(4)';
NODE_NAME     T1D5 8
 '@BASEBOARD_FAB2_LIB.BASEBOARD_FAB2(SCH_1):PAGE270_I12@W_HDL.TEST-PAD-12P-1-GP-U(CHIPS)':
 'GND'<5>: CDS_PINID='GND(5)';
NODE_NAME     T1D5 9
 '@BASEBOARD_FAB2_LIB.BASEBOARD_FAB2(SCH_1):PAGE270_I12@W_HDL.TEST-PAD-12P-1-GP-U(CHIPS)':
 'GND'<6>: CDS_PINID='GND(6)';
NODE_NAME     T1D5 10
 '@BASEBOARD_FAB2_LIB.BASEBOARD_FAB2(SCH_1):PAGE270_I12@W_HDL.TEST-PAD-12P-1-GP-U(CHIPS)':
 'GND'<7>: CDS_PINID='GND(7)';
NODE_NAME     T1D5 11
 '@BASEBOARD_FAB2_LIB.BASEBOARD_FAB2(SCH_1):PAGE270_I12@W_HDL.TEST-PAD-12P-1-GP-U(CHIPS)':
 'GND'<8>: CDS_PINID='GND(8)';
NODE_NAME     T1D5 12
 '@BASEBOARD_FAB2_LIB.BASEBOARD_FAB2(SCH_1):PAGE270_I12@W_HDL.TEST-PAD-12P-1-GP-U(CHIPS)':
 'GND'<9>: CDS_PINID='GND(9)';
NODE_NAME     T1D8 3
 '@BASEBOARD_FAB2_LIB.BASEBOARD_FAB2(SCH_1):PAGE270_I13@W_HDL.TEST-PAD-12P-1-GP-U(CHIPS)':
 'GND'<0>: CDS_PINID='GND(0)';
NODE_NAME     T1D8 4
 '@BASEBOARD_FAB2_LIB.BASEBOARD_FAB2(SCH_1):PAGE270_I13@W_HDL.TEST-PAD-12P-1-GP-U(CHIPS)':
 'GND'<1>: CDS_PINID='GND(1)';
NODE_NAME     T1D8 5
 '@BASEBOARD_FAB2_LIB.BASEBOARD_FAB2(SCH_1):PAGE270_I13@W_HDL.TEST-PAD-12P-1-GP-U(CHIPS)':
 'GND'<2>: CDS_PINID='GND(2)';
NODE_NAME     T1D8 6
 '@BASEBOARD_FAB2_LIB.BASEBOARD_FAB2(SCH_1):PAGE270_I13@W_HDL.TEST-PAD-12P-1-GP-U(CHIPS)':
 'GND'<3>: CDS_PINID='GND(3)';
NODE_NAME     T1D8 7
 '@BASEBOARD_FAB2_LIB.BASEBOARD_FAB2(SCH_1):PAGE270_I13@W_HDL.TEST-PAD-12P-1-GP-U(CHIPS)':
 'GND'<4>: CDS_PINID='GND(4)';
NODE_NAME     T1D8 8
 '@BASEBOARD_FAB2_LIB.BASEBOARD_FAB2(SCH_1):PAGE270_I13@W_HDL.TEST-PAD-12P-1-GP-U(CHIPS)':
 'GND'<5>: CDS_PINID='GND(5)';
NODE_NAME     T1D8 9
 '@BASEBOARD_FAB2_LIB.BASEBOARD_FAB2(SCH_1):PAGE270_I13@W_HDL.TEST-PAD-12P-1-GP-U(CHIPS)':
 'GND'<6>: CDS_PINID='GND(6)';
NODE_NAME     T1D8 10
 '@BASEBOARD_FAB2_LIB.BASEBOARD_FAB2(SCH_1):PAGE270_I13@W_HDL.TEST-PAD-12P-1-GP-U(CHIPS)':
 'GND'<7>: CDS_PINID='GND(7)';
NODE_NAME     T1D8 11
 '@BASEBOARD_FAB2_LIB.BASEBOARD_FAB2(SCH_1):PAGE270_I13@W_HDL.TEST-PAD-12P-1-GP-U(CHIPS)':
 'GND'<8>: CDS_PINID='GND(8)';
NODE_NAME     T1D8 12
 '@BASEBOARD_FAB2_LIB.BASEBOARD_FAB2(SCH_1):PAGE270_I13@W_HDL.TEST-PAD-12P-1-GP-U(CHIPS)':
 'GND'<9>: CDS_PINID='GND(9)';
NODE_NAME     T1D7 3
 '@BASEBOARD_FAB2_LIB.BASEBOARD_FAB2(SCH_1):PAGE270_I16@W_HDL.TEST-PAD-12P-1-GP-U(CHIPS)':
 'GND'<0>: CDS_PINID='GND(0)';
NODE_NAME     T1D7 4
 '@BASEBOARD_FAB2_LIB.BASEBOARD_FAB2(SCH_1):PAGE270_I16@W_HDL.TEST-PAD-12P-1-GP-U(CHIPS)':
 'GND'<1>: CDS_PINID='GND(1)';
NODE_NAME     T1D7 5
 '@BASEBOARD_FAB2_LIB.BASEBOARD_FAB2(SCH_1):PAGE270_I16@W_HDL.TEST-PAD-12P-1-GP-U(CHIPS)':
 'GND'<2>: CDS_PINID='GND(2)';
NODE_NAME     T1D7 6
 '@BASEBOARD_FAB2_LIB.BASEBOARD_FAB2(SCH_1):PAGE270_I16@W_HDL.TEST-PAD-12P-1-GP-U(CHIPS)':
 'GND'<3>: CDS_PINID='GND(3)';
NODE_NAME     T1D7 7
 '@BASEBOARD_FAB2_LIB.BASEBOARD_FAB2(SCH_1):PAGE270_I16@W_HDL.TEST-PAD-12P-1-GP-U(CHIPS)':
 'GND'<4>: CDS_PINID='GND(4)';
NODE_NAME     T1D7 8
 '@BASEBOARD_FAB2_LIB.BASEBOARD_FAB2(SCH_1):PAGE270_I16@W_HDL.TEST-PAD-12P-1-GP-U(CHIPS)':
 'GND'<5>: CDS_PINID='GND(5)';
NODE_NAME     T1D7 9
 '@BASEBOARD_FAB2_LIB.BASEBOARD_FAB2(SCH_1):PAGE270_I16@W_HDL.TEST-PAD-12P-1-GP-U(CHIPS)':
 'GND'<6>: CDS_PINID='GND(6)';
NODE_NAME     T1D7 10
 '@BASEBOARD_FAB2_LIB.BASEBOARD_FAB2(SCH_1):PAGE270_I16@W_HDL.TEST-PAD-12P-1-GP-U(CHIPS)':
 'GND'<7>: CDS_PINID='GND(7)';
NODE_NAME     T1D7 11
 '@BASEBOARD_FAB2_LIB.BASEBOARD_FAB2(SCH_1):PAGE270_I16@W_HDL.TEST-PAD-12P-1-GP-U(CHIPS)':
 'GND'<8>: CDS_PINID='GND(8)';
NODE_NAME     T1D7 12
 '@BASEBOARD_FAB2_LIB.BASEBOARD_FAB2(SCH_1):PAGE270_I16@W_HDL.TEST-PAD-12P-1-GP-U(CHIPS)':
 'GND'<9>: CDS_PINID='GND(9)';
NODE_NAME     T1D10 3
 '@BASEBOARD_FAB2_LIB.BASEBOARD_FAB2(SCH_1):PAGE270_I17@W_HDL.TEST-PAD-12P-1-GP-U(CHIPS)':
 'GND'<0>: CDS_PINID='GND(0)';
NODE_NAME     T1D10 4
 '@BASEBOARD_FAB2_LIB.BASEBOARD_FAB2(SCH_1):PAGE270_I17@W_HDL.TEST-PAD-12P-1-GP-U(CHIPS)':
 'GND'<1>: CDS_PINID='GND(1)';
NODE_NAME     T1D10 5
 '@BASEBOARD_FAB2_LIB.BASEBOARD_FAB2(SCH_1):PAGE270_I17@W_HDL.TEST-PAD-12P-1-GP-U(CHIPS)':
 'GND'<2>: CDS_PINID='GND(2)';
NODE_NAME     T1D10 6
 '@BASEBOARD_FAB2_LIB.BASEBOARD_FAB2(SCH_1):PAGE270_I17@W_HDL.TEST-PAD-12P-1-GP-U(CHIPS)':
 'GND'<3>: CDS_PINID='GND(3)';
NODE_NAME     T1D10 7
 '@BASEBOARD_FAB2_LIB.BASEBOARD_FAB2(SCH_1):PAGE270_I17@W_HDL.TEST-PAD-12P-1-GP-U(CHIPS)':
 'GND'<4>: CDS_PINID='GND(4)';
NODE_NAME     T1D10 8
 '@BASEBOARD_FAB2_LIB.BASEBOARD_FAB2(SCH_1):PAGE270_I17@W_HDL.TEST-PAD-12P-1-GP-U(CHIPS)':
 'GND'<5>: CDS_PINID='GND(5)';
NODE_NAME     T1D10 9
 '@BASEBOARD_FAB2_LIB.BASEBOARD_FAB2(SCH_1):PAGE270_I17@W_HDL.TEST-PAD-12P-1-GP-U(CHIPS)':
 'GND'<6>: CDS_PINID='GND(6)';
NODE_NAME     T1D10 10
 '@BASEBOARD_FAB2_LIB.BASEBOARD_FAB2(SCH_1):PAGE270_I17@W_HDL.TEST-PAD-12P-1-GP-U(CHIPS)':
 'GND'<7>: CDS_PINID='GND(7)';
NODE_NAME     T1D10 11
 '@BASEBOARD_FAB2_LIB.BASEBOARD_FAB2(SCH_1):PAGE270_I17@W_HDL.TEST-PAD-12P-1-GP-U(CHIPS)':
 'GND'<8>: CDS_PINID='GND(8)';
NODE_NAME     T1D10 12
 '@BASEBOARD_FAB2_LIB.BASEBOARD_FAB2(SCH_1):PAGE270_I17@W_HDL.TEST-PAD-12P-1-GP-U(CHIPS)':
 'GND'<9>: CDS_PINID='GND(9)';
NODE_NAME     T1D9 3
 '@BASEBOARD_FAB2_LIB.BASEBOARD_FAB2(SCH_1):PAGE270_I18@W_HDL.TEST-PAD-12P-1-GP-U(CHIPS)':
 'GND'<0>: CDS_PINID='GND(0)';
NODE_NAME     T1D9 4
 '@BASEBOARD_FAB2_LIB.BASEBOARD_FAB2(SCH_1):PAGE270_I18@W_HDL.TEST-PAD-12P-1-GP-U(CHIPS)':
 'GND'<1>: CDS_PINID='GND(1)';
NODE_NAME     T1D9 5
 '@BASEBOARD_FAB2_LIB.BASEBOARD_FAB2(SCH_1):PAGE270_I18@W_HDL.TEST-PAD-12P-1-GP-U(CHIPS)':
 'GND'<2>: CDS_PINID='GND(2)';
NODE_NAME     T1D9 6
 '@BASEBOARD_FAB2_LIB.BASEBOARD_FAB2(SCH_1):PAGE270_I18@W_HDL.TEST-PAD-12P-1-GP-U(CHIPS)':
 'GND'<3>: CDS_PINID='GND(3)';
NODE_NAME     T1D9 7
 '@BASEBOARD_FAB2_LIB.BASEBOARD_FAB2(SCH_1):PAGE270_I18@W_HDL.TEST-PAD-12P-1-GP-U(CHIPS)':
 'GND'<4>: CDS_PINID='GND(4)';
NODE_NAME     T1D9 8
 '@BASEBOARD_FAB2_LIB.BASEBOARD_FAB2(SCH_1):PAGE270_I18@W_HDL.TEST-PAD-12P-1-GP-U(CHIPS)':
 'GND'<5>: CDS_PINID='GND(5)';
NODE_NAME     T1D9 9
 '@BASEBOARD_FAB2_LIB.BASEBOARD_FAB2(SCH_1):PAGE270_I18@W_HDL.TEST-PAD-12P-1-GP-U(CHIPS)':
 'GND'<6>: CDS_PINID='GND(6)';
NODE_NAME     T1D9 10
 '@BASEBOARD_FAB2_LIB.BASEBOARD_FAB2(SCH_1):PAGE270_I18@W_HDL.TEST-PAD-12P-1-GP-U(CHIPS)':
 'GND'<7>: CDS_PINID='GND(7)';
NODE_NAME     T1D9 11
 '@BASEBOARD_FAB2_LIB.BASEBOARD_FAB2(SCH_1):PAGE270_I18@W_HDL.TEST-PAD-12P-1-GP-U(CHIPS)':
 'GND'<8>: CDS_PINID='GND(8)';
NODE_NAME     T1D9 12
 '@BASEBOARD_FAB2_LIB.BASEBOARD_FAB2(SCH_1):PAGE270_I18@W_HDL.TEST-PAD-12P-1-GP-U(CHIPS)':
 'GND'<9>: CDS_PINID='GND(9)';
NODE_NAME     T1D12 3
 '@BASEBOARD_FAB2_LIB.BASEBOARD_FAB2(SCH_1):PAGE270_I21@W_HDL.TEST-PAD-12P-1-GP-U(CHIPS)':
 'GND'<0>: CDS_PINID='GND(0)';
NODE_NAME     T1D12 4
 '@BASEBOARD_FAB2_LIB.BASEBOARD_FAB2(SCH_1):PAGE270_I21@W_HDL.TEST-PAD-12P-1-GP-U(CHIPS)':
 'GND'<1>: CDS_PINID='GND(1)';
NODE_NAME     T1D12 5
 '@BASEBOARD_FAB2_LIB.BASEBOARD_FAB2(SCH_1):PAGE270_I21@W_HDL.TEST-PAD-12P-1-GP-U(CHIPS)':
 'GND'<2>: CDS_PINID='GND(2)';
NODE_NAME     T1D12 6
 '@BASEBOARD_FAB2_LIB.BASEBOARD_FAB2(SCH_1):PAGE270_I21@W_HDL.TEST-PAD-12P-1-GP-U(CHIPS)':
 'GND'<3>: CDS_PINID='GND(3)';
NODE_NAME     T1D12 7
 '@BASEBOARD_FAB2_LIB.BASEBOARD_FAB2(SCH_1):PAGE270_I21@W_HDL.TEST-PAD-12P-1-GP-U(CHIPS)':
 'GND'<4>: CDS_PINID='GND(4)';
NODE_NAME     T1D12 8
 '@BASEBOARD_FAB2_LIB.BASEBOARD_FAB2(SCH_1):PAGE270_I21@W_HDL.TEST-PAD-12P-1-GP-U(CHIPS)':
 'GND'<5>: CDS_PINID='GND(5)';
NODE_NAME     T1D12 9
 '@BASEBOARD_FAB2_LIB.BASEBOARD_FAB2(SCH_1):PAGE270_I21@W_HDL.TEST-PAD-12P-1-GP-U(CHIPS)':
 'GND'<6>: CDS_PINID='GND(6)';
NODE_NAME     T1D12 10
 '@BASEBOARD_FAB2_LIB.BASEBOARD_FAB2(SCH_1):PAGE270_I21@W_HDL.TEST-PAD-12P-1-GP-U(CHIPS)':
 'GND'<7>: CDS_PINID='GND(7)';
NODE_NAME     T1D12 11
 '@BASEBOARD_FAB2_LIB.BASEBOARD_FAB2(SCH_1):PAGE270_I21@W_HDL.TEST-PAD-12P-1-GP-U(CHIPS)':
 'GND'<8>: CDS_PINID='GND(8)';
NODE_NAME     T1D12 12
 '@BASEBOARD_FAB2_LIB.BASEBOARD_FAB2(SCH_1):PAGE270_I21@W_HDL.TEST-PAD-12P-1-GP-U(CHIPS)':
 'GND'<9>: CDS_PINID='GND(9)';
NODE_NAME     T1D11 3
 '@BASEBOARD_FAB2_LIB.BASEBOARD_FAB2(SCH_1):PAGE270_I24@W_HDL.TEST-PAD-12P-1-GP-U(CHIPS)':
 'GND'<0>: CDS_PINID='GND(0)';
NODE_NAME     T1D11 4
 '@BASEBOARD_FAB2_LIB.BASEBOARD_FAB2(SCH_1):PAGE270_I24@W_HDL.TEST-PAD-12P-1-GP-U(CHIPS)':
 'GND'<1>: CDS_PINID='GND(1)';
NODE_NAME     T1D11 5
 '@BASEBOARD_FAB2_LIB.BASEBOARD_FAB2(SCH_1):PAGE270_I24@W_HDL.TEST-PAD-12P-1-GP-U(CHIPS)':
 'GND'<2>: CDS_PINID='GND(2)';
NODE_NAME     T1D11 6
 '@BASEBOARD_FAB2_LIB.BASEBOARD_FAB2(SCH_1):PAGE270_I24@W_HDL.TEST-PAD-12P-1-GP-U(CHIPS)':
 'GND'<3>: CDS_PINID='GND(3)';
NODE_NAME     T1D11 7
 '@BASEBOARD_FAB2_LIB.BASEBOARD_FAB2(SCH_1):PAGE270_I24@W_HDL.TEST-PAD-12P-1-GP-U(CHIPS)':
 'GND'<4>: CDS_PINID='GND(4)';
NODE_NAME     T1D11 8
 '@BASEBOARD_FAB2_LIB.BASEBOARD_FAB2(SCH_1):PAGE270_I24@W_HDL.TEST-PAD-12P-1-GP-U(CHIPS)':
 'GND'<5>: CDS_PINID='GND(5)';
NODE_NAME     T1D11 9
 '@BASEBOARD_FAB2_LIB.BASEBOARD_FAB2(SCH_1):PAGE270_I24@W_HDL.TEST-PAD-12P-1-GP-U(CHIPS)':
 'GND'<6>: CDS_PINID='GND(6)';
NODE_NAME     T1D11 10
 '@BASEBOARD_FAB2_LIB.BASEBOARD_FAB2(SCH_1):PAGE270_I24@W_HDL.TEST-PAD-12P-1-GP-U(CHIPS)':
 'GND'<7>: CDS_PINID='GND(7)';
NODE_NAME     T1D11 11
 '@BASEBOARD_FAB2_LIB.BASEBOARD_FAB2(SCH_1):PAGE270_I24@W_HDL.TEST-PAD-12P-1-GP-U(CHIPS)':
 'GND'<8>: CDS_PINID='GND(8)';
NODE_NAME     T1D11 12
 '@BASEBOARD_FAB2_LIB.BASEBOARD_FAB2(SCH_1):PAGE270_I24@W_HDL.TEST-PAD-12P-1-GP-U(CHIPS)':
 'GND'<9>: CDS_PINID='GND(9)';
NODE_NAME     T1D17 3
 '@BASEBOARD_FAB2_LIB.BASEBOARD_FAB2(SCH_1):PAGE272_I1@W_HDL.TEST-PAD-12P-1-GP-U(CHIPS)':
 'GND'<0>: CDS_PINID='GND(0)';
NODE_NAME     T1D17 4
 '@BASEBOARD_FAB2_LIB.BASEBOARD_FAB2(SCH_1):PAGE272_I1@W_HDL.TEST-PAD-12P-1-GP-U(CHIPS)':
 'GND'<1>: CDS_PINID='GND(1)';
NODE_NAME     T1D17 5
 '@BASEBOARD_FAB2_LIB.BASEBOARD_FAB2(SCH_1):PAGE272_I1@W_HDL.TEST-PAD-12P-1-GP-U(CHIPS)':
 'GND'<2>: CDS_PINID='GND(2)';
NODE_NAME     T1D17 6
 '@BASEBOARD_FAB2_LIB.BASEBOARD_FAB2(SCH_1):PAGE272_I1@W_HDL.TEST-PAD-12P-1-GP-U(CHIPS)':
 'GND'<3>: CDS_PINID='GND(3)';
NODE_NAME     T1D17 7
 '@BASEBOARD_FAB2_LIB.BASEBOARD_FAB2(SCH_1):PAGE272_I1@W_HDL.TEST-PAD-12P-1-GP-U(CHIPS)':
 'GND'<4>: CDS_PINID='GND(4)';
NODE_NAME     T1D17 8
 '@BASEBOARD_FAB2_LIB.BASEBOARD_FAB2(SCH_1):PAGE272_I1@W_HDL.TEST-PAD-12P-1-GP-U(CHIPS)':
 'GND'<5>: CDS_PINID='GND(5)';
NODE_NAME     T1D17 9
 '@BASEBOARD_FAB2_LIB.BASEBOARD_FAB2(SCH_1):PAGE272_I1@W_HDL.TEST-PAD-12P-1-GP-U(CHIPS)':
 'GND'<6>: CDS_PINID='GND(6)';
NODE_NAME     T1D17 10
 '@BASEBOARD_FAB2_LIB.BASEBOARD_FAB2(SCH_1):PAGE272_I1@W_HDL.TEST-PAD-12P-1-GP-U(CHIPS)':
 'GND'<7>: CDS_PINID='GND(7)';
NODE_NAME     T1D17 11
 '@BASEBOARD_FAB2_LIB.BASEBOARD_FAB2(SCH_1):PAGE272_I1@W_HDL.TEST-PAD-12P-1-GP-U(CHIPS)':
 'GND'<8>: CDS_PINID='GND(8)';
NODE_NAME     T1D17 12
 '@BASEBOARD_FAB2_LIB.BASEBOARD_FAB2(SCH_1):PAGE272_I1@W_HDL.TEST-PAD-12P-1-GP-U(CHIPS)':
 'GND'<9>: CDS_PINID='GND(9)';
NODE_NAME     T1D15 3
 '@BASEBOARD_FAB2_LIB.BASEBOARD_FAB2(SCH_1):PAGE272_I3@W_HDL.TEST-PAD-12P-1-GP-U(CHIPS)':
 'GND'<0>: CDS_PINID='GND(0)';
NODE_NAME     T1D15 4
 '@BASEBOARD_FAB2_LIB.BASEBOARD_FAB2(SCH_1):PAGE272_I3@W_HDL.TEST-PAD-12P-1-GP-U(CHIPS)':
 'GND'<1>: CDS_PINID='GND(1)';
NODE_NAME     T1D15 5
 '@BASEBOARD_FAB2_LIB.BASEBOARD_FAB2(SCH_1):PAGE272_I3@W_HDL.TEST-PAD-12P-1-GP-U(CHIPS)':
 'GND'<2>: CDS_PINID='GND(2)';
NODE_NAME     T1D15 6
 '@BASEBOARD_FAB2_LIB.BASEBOARD_FAB2(SCH_1):PAGE272_I3@W_HDL.TEST-PAD-12P-1-GP-U(CHIPS)':
 'GND'<3>: CDS_PINID='GND(3)';
NODE_NAME     T1D15 7
 '@BASEBOARD_FAB2_LIB.BASEBOARD_FAB2(SCH_1):PAGE272_I3@W_HDL.TEST-PAD-12P-1-GP-U(CHIPS)':
 'GND'<4>: CDS_PINID='GND(4)';
NODE_NAME     T1D15 8
 '@BASEBOARD_FAB2_LIB.BASEBOARD_FAB2(SCH_1):PAGE272_I3@W_HDL.TEST-PAD-12P-1-GP-U(CHIPS)':
 'GND'<5>: CDS_PINID='GND(5)';
NODE_NAME     T1D15 9
 '@BASEBOARD_FAB2_LIB.BASEBOARD_FAB2(SCH_1):PAGE272_I3@W_HDL.TEST-PAD-12P-1-GP-U(CHIPS)':
 'GND'<6>: CDS_PINID='GND(6)';
NODE_NAME     T1D15 10
 '@BASEBOARD_FAB2_LIB.BASEBOARD_FAB2(SCH_1):PAGE272_I3@W_HDL.TEST-PAD-12P-1-GP-U(CHIPS)':
 'GND'<7>: CDS_PINID='GND(7)';
NODE_NAME     T1D15 11
 '@BASEBOARD_FAB2_LIB.BASEBOARD_FAB2(SCH_1):PAGE272_I3@W_HDL.TEST-PAD-12P-1-GP-U(CHIPS)':
 'GND'<8>: CDS_PINID='GND(8)';
NODE_NAME     T1D15 12
 '@BASEBOARD_FAB2_LIB.BASEBOARD_FAB2(SCH_1):PAGE272_I3@W_HDL.TEST-PAD-12P-1-GP-U(CHIPS)':
 'GND'<9>: CDS_PINID='GND(9)';
NODE_NAME     T1D13 3
 '@BASEBOARD_FAB2_LIB.BASEBOARD_FAB2(SCH_1):PAGE272_I5@W_HDL.TEST-PAD-12P-1-GP-U(CHIPS)':
 'GND'<0>: CDS_PINID='GND(0)';
NODE_NAME     T1D13 4
 '@BASEBOARD_FAB2_LIB.BASEBOARD_FAB2(SCH_1):PAGE272_I5@W_HDL.TEST-PAD-12P-1-GP-U(CHIPS)':
 'GND'<1>: CDS_PINID='GND(1)';
NODE_NAME     T1D13 5
 '@BASEBOARD_FAB2_LIB.BASEBOARD_FAB2(SCH_1):PAGE272_I5@W_HDL.TEST-PAD-12P-1-GP-U(CHIPS)':
 'GND'<2>: CDS_PINID='GND(2)';
NODE_NAME     T1D13 6
 '@BASEBOARD_FAB2_LIB.BASEBOARD_FAB2(SCH_1):PAGE272_I5@W_HDL.TEST-PAD-12P-1-GP-U(CHIPS)':
 'GND'<3>: CDS_PINID='GND(3)';
NODE_NAME     T1D13 7
 '@BASEBOARD_FAB2_LIB.BASEBOARD_FAB2(SCH_1):PAGE272_I5@W_HDL.TEST-PAD-12P-1-GP-U(CHIPS)':
 'GND'<4>: CDS_PINID='GND(4)';
NODE_NAME     T1D13 8
 '@BASEBOARD_FAB2_LIB.BASEBOARD_FAB2(SCH_1):PAGE272_I5@W_HDL.TEST-PAD-12P-1-GP-U(CHIPS)':
 'GND'<5>: CDS_PINID='GND(5)';
NODE_NAME     T1D13 9
 '@BASEBOARD_FAB2_LIB.BASEBOARD_FAB2(SCH_1):PAGE272_I5@W_HDL.TEST-PAD-12P-1-GP-U(CHIPS)':
 'GND'<6>: CDS_PINID='GND(6)';
NODE_NAME     T1D13 10
 '@BASEBOARD_FAB2_LIB.BASEBOARD_FAB2(SCH_1):PAGE272_I5@W_HDL.TEST-PAD-12P-1-GP-U(CHIPS)':
 'GND'<7>: CDS_PINID='GND(7)';
NODE_NAME     T1D13 11
 '@BASEBOARD_FAB2_LIB.BASEBOARD_FAB2(SCH_1):PAGE272_I5@W_HDL.TEST-PAD-12P-1-GP-U(CHIPS)':
 'GND'<8>: CDS_PINID='GND(8)';
NODE_NAME     T1D13 12
 '@BASEBOARD_FAB2_LIB.BASEBOARD_FAB2(SCH_1):PAGE272_I5@W_HDL.TEST-PAD-12P-1-GP-U(CHIPS)':
 'GND'<9>: CDS_PINID='GND(9)';
NODE_NAME     T1D18 3
 '@BASEBOARD_FAB2_LIB.BASEBOARD_FAB2(SCH_1):PAGE272_I8@W_HDL.TEST-PAD-12P-1-GP-U(CHIPS)':
 'GND'<0>: CDS_PINID='GND(0)';
NODE_NAME     T1D18 4
 '@BASEBOARD_FAB2_LIB.BASEBOARD_FAB2(SCH_1):PAGE272_I8@W_HDL.TEST-PAD-12P-1-GP-U(CHIPS)':
 'GND'<1>: CDS_PINID='GND(1)';
NODE_NAME     T1D18 5
 '@BASEBOARD_FAB2_LIB.BASEBOARD_FAB2(SCH_1):PAGE272_I8@W_HDL.TEST-PAD-12P-1-GP-U(CHIPS)':
 'GND'<2>: CDS_PINID='GND(2)';
NODE_NAME     T1D18 6
 '@BASEBOARD_FAB2_LIB.BASEBOARD_FAB2(SCH_1):PAGE272_I8@W_HDL.TEST-PAD-12P-1-GP-U(CHIPS)':
 'GND'<3>: CDS_PINID='GND(3)';
NODE_NAME     T1D18 7
 '@BASEBOARD_FAB2_LIB.BASEBOARD_FAB2(SCH_1):PAGE272_I8@W_HDL.TEST-PAD-12P-1-GP-U(CHIPS)':
 'GND'<4>: CDS_PINID='GND(4)';
NODE_NAME     T1D18 8
 '@BASEBOARD_FAB2_LIB.BASEBOARD_FAB2(SCH_1):PAGE272_I8@W_HDL.TEST-PAD-12P-1-GP-U(CHIPS)':
 'GND'<5>: CDS_PINID='GND(5)';
NODE_NAME     T1D18 9
 '@BASEBOARD_FAB2_LIB.BASEBOARD_FAB2(SCH_1):PAGE272_I8@W_HDL.TEST-PAD-12P-1-GP-U(CHIPS)':
 'GND'<6>: CDS_PINID='GND(6)';
NODE_NAME     T1D18 10
 '@BASEBOARD_FAB2_LIB.BASEBOARD_FAB2(SCH_1):PAGE272_I8@W_HDL.TEST-PAD-12P-1-GP-U(CHIPS)':
 'GND'<7>: CDS_PINID='GND(7)';
NODE_NAME     T1D18 11
 '@BASEBOARD_FAB2_LIB.BASEBOARD_FAB2(SCH_1):PAGE272_I8@W_HDL.TEST-PAD-12P-1-GP-U(CHIPS)':
 'GND'<8>: CDS_PINID='GND(8)';
NODE_NAME     T1D18 12
 '@BASEBOARD_FAB2_LIB.BASEBOARD_FAB2(SCH_1):PAGE272_I8@W_HDL.TEST-PAD-12P-1-GP-U(CHIPS)':
 'GND'<9>: CDS_PINID='GND(9)';
NODE_NAME     T1D23 3
 '@BASEBOARD_FAB2_LIB.BASEBOARD_FAB2(SCH_1):PAGE272_I9@W_HDL.TEST-PAD-12P-1-GP-U(CHIPS)':
 'GND'<0>: CDS_PINID='GND(0)';
NODE_NAME     T1D23 4
 '@BASEBOARD_FAB2_LIB.BASEBOARD_FAB2(SCH_1):PAGE272_I9@W_HDL.TEST-PAD-12P-1-GP-U(CHIPS)':
 'GND'<1>: CDS_PINID='GND(1)';
NODE_NAME     T1D23 5
 '@BASEBOARD_FAB2_LIB.BASEBOARD_FAB2(SCH_1):PAGE272_I9@W_HDL.TEST-PAD-12P-1-GP-U(CHIPS)':
 'GND'<2>: CDS_PINID='GND(2)';
NODE_NAME     T1D23 6
 '@BASEBOARD_FAB2_LIB.BASEBOARD_FAB2(SCH_1):PAGE272_I9@W_HDL.TEST-PAD-12P-1-GP-U(CHIPS)':
 'GND'<3>: CDS_PINID='GND(3)';
NODE_NAME     T1D23 7
 '@BASEBOARD_FAB2_LIB.BASEBOARD_FAB2(SCH_1):PAGE272_I9@W_HDL.TEST-PAD-12P-1-GP-U(CHIPS)':
 'GND'<4>: CDS_PINID='GND(4)';
NODE_NAME     T1D23 8
 '@BASEBOARD_FAB2_LIB.BASEBOARD_FAB2(SCH_1):PAGE272_I9@W_HDL.TEST-PAD-12P-1-GP-U(CHIPS)':
 'GND'<5>: CDS_PINID='GND(5)';
NODE_NAME     T1D23 9
 '@BASEBOARD_FAB2_LIB.BASEBOARD_FAB2(SCH_1):PAGE272_I9@W_HDL.TEST-PAD-12P-1-GP-U(CHIPS)':
 'GND'<6>: CDS_PINID='GND(6)';
NODE_NAME     T1D23 10
 '@BASEBOARD_FAB2_LIB.BASEBOARD_FAB2(SCH_1):PAGE272_I9@W_HDL.TEST-PAD-12P-1-GP-U(CHIPS)':
 'GND'<7>: CDS_PINID='GND(7)';
NODE_NAME     T1D23 11
 '@BASEBOARD_FAB2_LIB.BASEBOARD_FAB2(SCH_1):PAGE272_I9@W_HDL.TEST-PAD-12P-1-GP-U(CHIPS)':
 'GND'<8>: CDS_PINID='GND(8)';
NODE_NAME     T1D23 12
 '@BASEBOARD_FAB2_LIB.BASEBOARD_FAB2(SCH_1):PAGE272_I9@W_HDL.TEST-PAD-12P-1-GP-U(CHIPS)':
 'GND'<9>: CDS_PINID='GND(9)';
NODE_NAME     T1D24 3
 '@BASEBOARD_FAB2_LIB.BASEBOARD_FAB2(SCH_1):PAGE272_I12@W_HDL.TEST-PAD-12P-1-GP-U(CHIPS)':
 'GND'<0>: CDS_PINID='GND(0)';
NODE_NAME     T1D24 4
 '@BASEBOARD_FAB2_LIB.BASEBOARD_FAB2(SCH_1):PAGE272_I12@W_HDL.TEST-PAD-12P-1-GP-U(CHIPS)':
 'GND'<1>: CDS_PINID='GND(1)';
NODE_NAME     T1D24 5
 '@BASEBOARD_FAB2_LIB.BASEBOARD_FAB2(SCH_1):PAGE272_I12@W_HDL.TEST-PAD-12P-1-GP-U(CHIPS)':
 'GND'<2>: CDS_PINID='GND(2)';
NODE_NAME     T1D24 6
 '@BASEBOARD_FAB2_LIB.BASEBOARD_FAB2(SCH_1):PAGE272_I12@W_HDL.TEST-PAD-12P-1-GP-U(CHIPS)':
 'GND'<3>: CDS_PINID='GND(3)';
NODE_NAME     T1D24 7
 '@BASEBOARD_FAB2_LIB.BASEBOARD_FAB2(SCH_1):PAGE272_I12@W_HDL.TEST-PAD-12P-1-GP-U(CHIPS)':
 'GND'<4>: CDS_PINID='GND(4)';
NODE_NAME     T1D24 8
 '@BASEBOARD_FAB2_LIB.BASEBOARD_FAB2(SCH_1):PAGE272_I12@W_HDL.TEST-PAD-12P-1-GP-U(CHIPS)':
 'GND'<5>: CDS_PINID='GND(5)';
NODE_NAME     T1D24 9
 '@BASEBOARD_FAB2_LIB.BASEBOARD_FAB2(SCH_1):PAGE272_I12@W_HDL.TEST-PAD-12P-1-GP-U(CHIPS)':
 'GND'<6>: CDS_PINID='GND(6)';
NODE_NAME     T1D24 10
 '@BASEBOARD_FAB2_LIB.BASEBOARD_FAB2(SCH_1):PAGE272_I12@W_HDL.TEST-PAD-12P-1-GP-U(CHIPS)':
 'GND'<7>: CDS_PINID='GND(7)';
NODE_NAME     T1D24 11
 '@BASEBOARD_FAB2_LIB.BASEBOARD_FAB2(SCH_1):PAGE272_I12@W_HDL.TEST-PAD-12P-1-GP-U(CHIPS)':
 'GND'<8>: CDS_PINID='GND(8)';
NODE_NAME     T1D24 12
 '@BASEBOARD_FAB2_LIB.BASEBOARD_FAB2(SCH_1):PAGE272_I12@W_HDL.TEST-PAD-12P-1-GP-U(CHIPS)':
 'GND'<9>: CDS_PINID='GND(9)';
NODE_NAME     T1D16 3
 '@BASEBOARD_FAB2_LIB.BASEBOARD_FAB2(SCH_1):PAGE272_I14@W_HDL.TEST-PAD-12P-1-GP-U(CHIPS)':
 'GND'<0>: CDS_PINID='GND(0)';
NODE_NAME     T1D16 4
 '@BASEBOARD_FAB2_LIB.BASEBOARD_FAB2(SCH_1):PAGE272_I14@W_HDL.TEST-PAD-12P-1-GP-U(CHIPS)':
 'GND'<1>: CDS_PINID='GND(1)';
NODE_NAME     T1D16 5
 '@BASEBOARD_FAB2_LIB.BASEBOARD_FAB2(SCH_1):PAGE272_I14@W_HDL.TEST-PAD-12P-1-GP-U(CHIPS)':
 'GND'<2>: CDS_PINID='GND(2)';
NODE_NAME     T1D16 6
 '@BASEBOARD_FAB2_LIB.BASEBOARD_FAB2(SCH_1):PAGE272_I14@W_HDL.TEST-PAD-12P-1-GP-U(CHIPS)':
 'GND'<3>: CDS_PINID='GND(3)';
NODE_NAME     T1D16 7
 '@BASEBOARD_FAB2_LIB.BASEBOARD_FAB2(SCH_1):PAGE272_I14@W_HDL.TEST-PAD-12P-1-GP-U(CHIPS)':
 'GND'<4>: CDS_PINID='GND(4)';
NODE_NAME     T1D16 8
 '@BASEBOARD_FAB2_LIB.BASEBOARD_FAB2(SCH_1):PAGE272_I14@W_HDL.TEST-PAD-12P-1-GP-U(CHIPS)':
 'GND'<5>: CDS_PINID='GND(5)';
NODE_NAME     T1D16 9
 '@BASEBOARD_FAB2_LIB.BASEBOARD_FAB2(SCH_1):PAGE272_I14@W_HDL.TEST-PAD-12P-1-GP-U(CHIPS)':
 'GND'<6>: CDS_PINID='GND(6)';
NODE_NAME     T1D16 10
 '@BASEBOARD_FAB2_LIB.BASEBOARD_FAB2(SCH_1):PAGE272_I14@W_HDL.TEST-PAD-12P-1-GP-U(CHIPS)':
 'GND'<7>: CDS_PINID='GND(7)';
NODE_NAME     T1D16 11
 '@BASEBOARD_FAB2_LIB.BASEBOARD_FAB2(SCH_1):PAGE272_I14@W_HDL.TEST-PAD-12P-1-GP-U(CHIPS)':
 'GND'<8>: CDS_PINID='GND(8)';
NODE_NAME     T1D16 12
 '@BASEBOARD_FAB2_LIB.BASEBOARD_FAB2(SCH_1):PAGE272_I14@W_HDL.TEST-PAD-12P-1-GP-U(CHIPS)':
 'GND'<9>: CDS_PINID='GND(9)';
NODE_NAME     T1D21 3
 '@BASEBOARD_FAB2_LIB.BASEBOARD_FAB2(SCH_1):PAGE272_I16@W_HDL.TEST-PAD-12P-1-GP-U(CHIPS)':
 'GND'<0>: CDS_PINID='GND(0)';
NODE_NAME     T1D21 4
 '@BASEBOARD_FAB2_LIB.BASEBOARD_FAB2(SCH_1):PAGE272_I16@W_HDL.TEST-PAD-12P-1-GP-U(CHIPS)':
 'GND'<1>: CDS_PINID='GND(1)';
NODE_NAME     T1D21 5
 '@BASEBOARD_FAB2_LIB.BASEBOARD_FAB2(SCH_1):PAGE272_I16@W_HDL.TEST-PAD-12P-1-GP-U(CHIPS)':
 'GND'<2>: CDS_PINID='GND(2)';
NODE_NAME     T1D21 6
 '@BASEBOARD_FAB2_LIB.BASEBOARD_FAB2(SCH_1):PAGE272_I16@W_HDL.TEST-PAD-12P-1-GP-U(CHIPS)':
 'GND'<3>: CDS_PINID='GND(3)';
NODE_NAME     T1D21 7
 '@BASEBOARD_FAB2_LIB.BASEBOARD_FAB2(SCH_1):PAGE272_I16@W_HDL.TEST-PAD-12P-1-GP-U(CHIPS)':
 'GND'<4>: CDS_PINID='GND(4)';
NODE_NAME     T1D21 8
 '@BASEBOARD_FAB2_LIB.BASEBOARD_FAB2(SCH_1):PAGE272_I16@W_HDL.TEST-PAD-12P-1-GP-U(CHIPS)':
 'GND'<5>: CDS_PINID='GND(5)';
NODE_NAME     T1D21 9
 '@BASEBOARD_FAB2_LIB.BASEBOARD_FAB2(SCH_1):PAGE272_I16@W_HDL.TEST-PAD-12P-1-GP-U(CHIPS)':
 'GND'<6>: CDS_PINID='GND(6)';
NODE_NAME     T1D21 10
 '@BASEBOARD_FAB2_LIB.BASEBOARD_FAB2(SCH_1):PAGE272_I16@W_HDL.TEST-PAD-12P-1-GP-U(CHIPS)':
 'GND'<7>: CDS_PINID='GND(7)';
NODE_NAME     T1D21 11
 '@BASEBOARD_FAB2_LIB.BASEBOARD_FAB2(SCH_1):PAGE272_I16@W_HDL.TEST-PAD-12P-1-GP-U(CHIPS)':
 'GND'<8>: CDS_PINID='GND(8)';
NODE_NAME     T1D21 12
 '@BASEBOARD_FAB2_LIB.BASEBOARD_FAB2(SCH_1):PAGE272_I16@W_HDL.TEST-PAD-12P-1-GP-U(CHIPS)':
 'GND'<9>: CDS_PINID='GND(9)';
NODE_NAME     T1D22 3
 '@BASEBOARD_FAB2_LIB.BASEBOARD_FAB2(SCH_1):PAGE272_I21@W_HDL.TEST-PAD-12P-1-GP-U(CHIPS)':
 'GND'<0>: CDS_PINID='GND(0)';
NODE_NAME     T1D22 4
 '@BASEBOARD_FAB2_LIB.BASEBOARD_FAB2(SCH_1):PAGE272_I21@W_HDL.TEST-PAD-12P-1-GP-U(CHIPS)':
 'GND'<1>: CDS_PINID='GND(1)';
NODE_NAME     T1D22 5
 '@BASEBOARD_FAB2_LIB.BASEBOARD_FAB2(SCH_1):PAGE272_I21@W_HDL.TEST-PAD-12P-1-GP-U(CHIPS)':
 'GND'<2>: CDS_PINID='GND(2)';
NODE_NAME     T1D22 6
 '@BASEBOARD_FAB2_LIB.BASEBOARD_FAB2(SCH_1):PAGE272_I21@W_HDL.TEST-PAD-12P-1-GP-U(CHIPS)':
 'GND'<3>: CDS_PINID='GND(3)';
NODE_NAME     T1D22 7
 '@BASEBOARD_FAB2_LIB.BASEBOARD_FAB2(SCH_1):PAGE272_I21@W_HDL.TEST-PAD-12P-1-GP-U(CHIPS)':
 'GND'<4>: CDS_PINID='GND(4)';
NODE_NAME     T1D22 8
 '@BASEBOARD_FAB2_LIB.BASEBOARD_FAB2(SCH_1):PAGE272_I21@W_HDL.TEST-PAD-12P-1-GP-U(CHIPS)':
 'GND'<5>: CDS_PINID='GND(5)';
NODE_NAME     T1D22 9
 '@BASEBOARD_FAB2_LIB.BASEBOARD_FAB2(SCH_1):PAGE272_I21@W_HDL.TEST-PAD-12P-1-GP-U(CHIPS)':
 'GND'<6>: CDS_PINID='GND(6)';
NODE_NAME     T1D22 10
 '@BASEBOARD_FAB2_LIB.BASEBOARD_FAB2(SCH_1):PAGE272_I21@W_HDL.TEST-PAD-12P-1-GP-U(CHIPS)':
 'GND'<7>: CDS_PINID='GND(7)';
NODE_NAME     T1D22 11
 '@BASEBOARD_FAB2_LIB.BASEBOARD_FAB2(SCH_1):PAGE272_I21@W_HDL.TEST-PAD-12P-1-GP-U(CHIPS)':
 'GND'<8>: CDS_PINID='GND(8)';
NODE_NAME     T1D22 12
 '@BASEBOARD_FAB2_LIB.BASEBOARD_FAB2(SCH_1):PAGE272_I21@W_HDL.TEST-PAD-12P-1-GP-U(CHIPS)':
 'GND'<9>: CDS_PINID='GND(9)';
NODE_NAME     T1D14 3
 '@BASEBOARD_FAB2_LIB.BASEBOARD_FAB2(SCH_1):PAGE272_I22@W_HDL.TEST-PAD-12P-1-GP-U(CHIPS)':
 'GND'<0>: CDS_PINID='GND(0)';
NODE_NAME     T1D14 4
 '@BASEBOARD_FAB2_LIB.BASEBOARD_FAB2(SCH_1):PAGE272_I22@W_HDL.TEST-PAD-12P-1-GP-U(CHIPS)':
 'GND'<1>: CDS_PINID='GND(1)';
NODE_NAME     T1D14 5
 '@BASEBOARD_FAB2_LIB.BASEBOARD_FAB2(SCH_1):PAGE272_I22@W_HDL.TEST-PAD-12P-1-GP-U(CHIPS)':
 'GND'<2>: CDS_PINID='GND(2)';
NODE_NAME     T1D14 6
 '@BASEBOARD_FAB2_LIB.BASEBOARD_FAB2(SCH_1):PAGE272_I22@W_HDL.TEST-PAD-12P-1-GP-U(CHIPS)':
 'GND'<3>: CDS_PINID='GND(3)';
NODE_NAME     T1D14 7
 '@BASEBOARD_FAB2_LIB.BASEBOARD_FAB2(SCH_1):PAGE272_I22@W_HDL.TEST-PAD-12P-1-GP-U(CHIPS)':
 'GND'<4>: CDS_PINID='GND(4)';
NODE_NAME     T1D14 8
 '@BASEBOARD_FAB2_LIB.BASEBOARD_FAB2(SCH_1):PAGE272_I22@W_HDL.TEST-PAD-12P-1-GP-U(CHIPS)':
 'GND'<5>: CDS_PINID='GND(5)';
NODE_NAME     T1D14 9
 '@BASEBOARD_FAB2_LIB.BASEBOARD_FAB2(SCH_1):PAGE272_I22@W_HDL.TEST-PAD-12P-1-GP-U(CHIPS)':
 'GND'<6>: CDS_PINID='GND(6)';
NODE_NAME     T1D14 10
 '@BASEBOARD_FAB2_LIB.BASEBOARD_FAB2(SCH_1):PAGE272_I22@W_HDL.TEST-PAD-12P-1-GP-U(CHIPS)':
 'GND'<7>: CDS_PINID='GND(7)';
NODE_NAME     T1D14 11
 '@BASEBOARD_FAB2_LIB.BASEBOARD_FAB2(SCH_1):PAGE272_I22@W_HDL.TEST-PAD-12P-1-GP-U(CHIPS)':
 'GND'<8>: CDS_PINID='GND(8)';
NODE_NAME     T1D14 12
 '@BASEBOARD_FAB2_LIB.BASEBOARD_FAB2(SCH_1):PAGE272_I22@W_HDL.TEST-PAD-12P-1-GP-U(CHIPS)':
 'GND'<9>: CDS_PINID='GND(9)';
NODE_NAME     T1D19 3
 '@BASEBOARD_FAB2_LIB.BASEBOARD_FAB2(SCH_1):PAGE272_I23@W_HDL.TEST-PAD-12P-1-GP-U(CHIPS)':
 'GND'<0>: CDS_PINID='GND(0)';
NODE_NAME     T1D19 4
 '@BASEBOARD_FAB2_LIB.BASEBOARD_FAB2(SCH_1):PAGE272_I23@W_HDL.TEST-PAD-12P-1-GP-U(CHIPS)':
 'GND'<1>: CDS_PINID='GND(1)';
NODE_NAME     T1D19 5
 '@BASEBOARD_FAB2_LIB.BASEBOARD_FAB2(SCH_1):PAGE272_I23@W_HDL.TEST-PAD-12P-1-GP-U(CHIPS)':
 'GND'<2>: CDS_PINID='GND(2)';
NODE_NAME     T1D19 6
 '@BASEBOARD_FAB2_LIB.BASEBOARD_FAB2(SCH_1):PAGE272_I23@W_HDL.TEST-PAD-12P-1-GP-U(CHIPS)':
 'GND'<3>: CDS_PINID='GND(3)';
NODE_NAME     T1D19 7
 '@BASEBOARD_FAB2_LIB.BASEBOARD_FAB2(SCH_1):PAGE272_I23@W_HDL.TEST-PAD-12P-1-GP-U(CHIPS)':
 'GND'<4>: CDS_PINID='GND(4)';
NODE_NAME     T1D19 8
 '@BASEBOARD_FAB2_LIB.BASEBOARD_FAB2(SCH_1):PAGE272_I23@W_HDL.TEST-PAD-12P-1-GP-U(CHIPS)':
 'GND'<5>: CDS_PINID='GND(5)';
NODE_NAME     T1D19 9
 '@BASEBOARD_FAB2_LIB.BASEBOARD_FAB2(SCH_1):PAGE272_I23@W_HDL.TEST-PAD-12P-1-GP-U(CHIPS)':
 'GND'<6>: CDS_PINID='GND(6)';
NODE_NAME     T1D19 10
 '@BASEBOARD_FAB2_LIB.BASEBOARD_FAB2(SCH_1):PAGE272_I23@W_HDL.TEST-PAD-12P-1-GP-U(CHIPS)':
 'GND'<7>: CDS_PINID='GND(7)';
NODE_NAME     T1D19 11
 '@BASEBOARD_FAB2_LIB.BASEBOARD_FAB2(SCH_1):PAGE272_I23@W_HDL.TEST-PAD-12P-1-GP-U(CHIPS)':
 'GND'<8>: CDS_PINID='GND(8)';
NODE_NAME     T1D19 12
 '@BASEBOARD_FAB2_LIB.BASEBOARD_FAB2(SCH_1):PAGE272_I23@W_HDL.TEST-PAD-12P-1-GP-U(CHIPS)':
 'GND'<9>: CDS_PINID='GND(9)';
NODE_NAME     T1D20 3
 '@BASEBOARD_FAB2_LIB.BASEBOARD_FAB2(SCH_1):PAGE272_I24@W_HDL.TEST-PAD-12P-1-GP-U(CHIPS)':
 'GND'<0>: CDS_PINID='GND(0)';
NODE_NAME     T1D20 4
 '@BASEBOARD_FAB2_LIB.BASEBOARD_FAB2(SCH_1):PAGE272_I24@W_HDL.TEST-PAD-12P-1-GP-U(CHIPS)':
 'GND'<1>: CDS_PINID='GND(1)';
NODE_NAME     T1D20 5
 '@BASEBOARD_FAB2_LIB.BASEBOARD_FAB2(SCH_1):PAGE272_I24@W_HDL.TEST-PAD-12P-1-GP-U(CHIPS)':
 'GND'<2>: CDS_PINID='GND(2)';
NODE_NAME     T1D20 6
 '@BASEBOARD_FAB2_LIB.BASEBOARD_FAB2(SCH_1):PAGE272_I24@W_HDL.TEST-PAD-12P-1-GP-U(CHIPS)':
 'GND'<3>: CDS_PINID='GND(3)';
NODE_NAME     T1D20 7
 '@BASEBOARD_FAB2_LIB.BASEBOARD_FAB2(SCH_1):PAGE272_I24@W_HDL.TEST-PAD-12P-1-GP-U(CHIPS)':
 'GND'<4>: CDS_PINID='GND(4)';
NODE_NAME     T1D20 8
 '@BASEBOARD_FAB2_LIB.BASEBOARD_FAB2(SCH_1):PAGE272_I24@W_HDL.TEST-PAD-12P-1-GP-U(CHIPS)':
 'GND'<5>: CDS_PINID='GND(5)';
NODE_NAME     T1D20 9
 '@BASEBOARD_FAB2_LIB.BASEBOARD_FAB2(SCH_1):PAGE272_I24@W_HDL.TEST-PAD-12P-1-GP-U(CHIPS)':
 'GND'<6>: CDS_PINID='GND(6)';
NODE_NAME     T1D20 10
 '@BASEBOARD_FAB2_LIB.BASEBOARD_FAB2(SCH_1):PAGE272_I24@W_HDL.TEST-PAD-12P-1-GP-U(CHIPS)':
 'GND'<7>: CDS_PINID='GND(7)';
NODE_NAME     T1D20 11
 '@BASEBOARD_FAB2_LIB.BASEBOARD_FAB2(SCH_1):PAGE272_I24@W_HDL.TEST-PAD-12P-1-GP-U(CHIPS)':
 'GND'<8>: CDS_PINID='GND(8)';
NODE_NAME     T1D20 12
 '@BASEBOARD_FAB2_LIB.BASEBOARD_FAB2(SCH_1):PAGE272_I24@W_HDL.TEST-PAD-12P-1-GP-U(CHIPS)':
 'GND'<9>: CDS_PINID='GND(9)';
NODE_NAME     T1P2 GND1
 '@BASEBOARD_FAB2_LIB.BASEBOARD_FAB2(SCH_1):PAGE271_I5@W_HDL.TPAD-DIFF-4P-GP(CHIPS)':
 'GND1': CDS_PINID='GND1';
NODE_NAME     T1P2 GND2
 '@BASEBOARD_FAB2_LIB.BASEBOARD_FAB2(SCH_1):PAGE271_I5@W_HDL.TPAD-DIFF-4P-GP(CHIPS)':
 'GND2': CDS_PINID='GND2';
NODE_NAME     T1P4 GND1
 '@BASEBOARD_FAB2_LIB.BASEBOARD_FAB2(SCH_1):PAGE271_I7@W_HDL.TPAD-DIFF-4P-GP(CHIPS)':
 'GND1': CDS_PINID='GND1';
NODE_NAME     T1P4 GND2
 '@BASEBOARD_FAB2_LIB.BASEBOARD_FAB2(SCH_1):PAGE271_I7@W_HDL.TPAD-DIFF-4P-GP(CHIPS)':
 'GND2': CDS_PINID='GND2';
NODE_NAME     T1P3 GND1
 '@BASEBOARD_FAB2_LIB.BASEBOARD_FAB2(SCH_1):PAGE271_I8@W_HDL.TPAD-DIFF-4P-GP(CHIPS)':
 'GND1': CDS_PINID='GND1';
NODE_NAME     T1P3 GND2
 '@BASEBOARD_FAB2_LIB.BASEBOARD_FAB2(SCH_1):PAGE271_I8@W_HDL.TPAD-DIFF-4P-GP(CHIPS)':
 'GND2': CDS_PINID='GND2';
NODE_NAME     T1P5 GND1
 '@BASEBOARD_FAB2_LIB.BASEBOARD_FAB2(SCH_1):PAGE271_I11@W_HDL.TPAD-DIFF-4P-GP(CHIPS)':
 'GND1': CDS_PINID='GND1';
NODE_NAME     T1P5 GND2
 '@BASEBOARD_FAB2_LIB.BASEBOARD_FAB2(SCH_1):PAGE271_I11@W_HDL.TPAD-DIFF-4P-GP(CHIPS)':
 'GND2': CDS_PINID='GND2';
NODE_NAME     T1P6 GND1
 '@BASEBOARD_FAB2_LIB.BASEBOARD_FAB2(SCH_1):PAGE271_I13@W_HDL.TPAD-DIFF-4P-GP(CHIPS)':
 'GND1': CDS_PINID='GND1';
NODE_NAME     T1P6 GND2
 '@BASEBOARD_FAB2_LIB.BASEBOARD_FAB2(SCH_1):PAGE271_I13@W_HDL.TPAD-DIFF-4P-GP(CHIPS)':
 'GND2': CDS_PINID='GND2';
NODE_NAME     T1P10 GND1
 '@BASEBOARD_FAB2_LIB.BASEBOARD_FAB2(SCH_1):PAGE271_I15@W_HDL.TPAD-DIFF-4P-GP(CHIPS)':
 'GND1': CDS_PINID='GND1';
NODE_NAME     T1P10 GND2
 '@BASEBOARD_FAB2_LIB.BASEBOARD_FAB2(SCH_1):PAGE271_I15@W_HDL.TPAD-DIFF-4P-GP(CHIPS)':
 'GND2': CDS_PINID='GND2';
NODE_NAME     T1P8 GND1
 '@BASEBOARD_FAB2_LIB.BASEBOARD_FAB2(SCH_1):PAGE271_I16@W_HDL.TPAD-DIFF-4P-GP(CHIPS)':
 'GND1': CDS_PINID='GND1';
NODE_NAME     T1P8 GND2
 '@BASEBOARD_FAB2_LIB.BASEBOARD_FAB2(SCH_1):PAGE271_I16@W_HDL.TPAD-DIFF-4P-GP(CHIPS)':
 'GND2': CDS_PINID='GND2';
NODE_NAME     T1P7 GND1
 '@BASEBOARD_FAB2_LIB.BASEBOARD_FAB2(SCH_1):PAGE271_I17@W_HDL.TPAD-DIFF-4P-GP(CHIPS)':
 'GND1': CDS_PINID='GND1';
NODE_NAME     T1P7 GND2
 '@BASEBOARD_FAB2_LIB.BASEBOARD_FAB2(SCH_1):PAGE271_I17@W_HDL.TPAD-DIFF-4P-GP(CHIPS)':
 'GND2': CDS_PINID='GND2';
NODE_NAME     T1P9 GND1
 '@BASEBOARD_FAB2_LIB.BASEBOARD_FAB2(SCH_1):PAGE271_I19@W_HDL.TPAD-DIFF-4P-GP(CHIPS)':
 'GND1': CDS_PINID='GND1';
NODE_NAME     T1P9 GND2
 '@BASEBOARD_FAB2_LIB.BASEBOARD_FAB2(SCH_1):PAGE271_I19@W_HDL.TPAD-DIFF-4P-GP(CHIPS)':
 'GND2': CDS_PINID='GND2';
NODE_NAME     T1P11 GND1
 '@BASEBOARD_FAB2_LIB.BASEBOARD_FAB2(SCH_1):PAGE271_I23@W_HDL.TPAD-DIFF-4P-GP(CHIPS)':
 'GND1': CDS_PINID='GND1';
NODE_NAME     T1P11 GND2
 '@BASEBOARD_FAB2_LIB.BASEBOARD_FAB2(SCH_1):PAGE271_I23@W_HDL.TPAD-DIFF-4P-GP(CHIPS)':
 'GND2': CDS_PINID='GND2';
NODE_NAME     T1P12 GND1
 '@BASEBOARD_FAB2_LIB.BASEBOARD_FAB2(SCH_1):PAGE271_I24@W_HDL.TPAD-DIFF-4P-GP(CHIPS)':
 'GND1': CDS_PINID='GND1';
NODE_NAME     T1P12 GND2
 '@BASEBOARD_FAB2_LIB.BASEBOARD_FAB2(SCH_1):PAGE271_I24@W_HDL.TPAD-DIFF-4P-GP(CHIPS)':
 'GND2': CDS_PINID='GND2';
NODE_NAME     T1P14 GND1
 '@BASEBOARD_FAB2_LIB.BASEBOARD_FAB2(SCH_1):PAGE271_I30@W_HDL.TPAD-DIFF-4P-GP(CHIPS)':
 'GND1': CDS_PINID='GND1';
NODE_NAME     T1P14 GND2
 '@BASEBOARD_FAB2_LIB.BASEBOARD_FAB2(SCH_1):PAGE271_I30@W_HDL.TPAD-DIFF-4P-GP(CHIPS)':
 'GND2': CDS_PINID='GND2';
NODE_NAME     T1P17 GND1
 '@BASEBOARD_FAB2_LIB.BASEBOARD_FAB2(SCH_1):PAGE271_I36@W_HDL.TPAD-DIFF-4P-GP(CHIPS)':
 'GND1': CDS_PINID='GND1';
NODE_NAME     T1P17 GND2
 '@BASEBOARD_FAB2_LIB.BASEBOARD_FAB2(SCH_1):PAGE271_I36@W_HDL.TPAD-DIFF-4P-GP(CHIPS)':
 'GND2': CDS_PINID='GND2';
NODE_NAME     T1P24 GND1
 '@BASEBOARD_FAB2_LIB.BASEBOARD_FAB2(SCH_1):PAGE271_I38@W_HDL.TPAD-DIFF-4P-GP(CHIPS)':
 'GND1': CDS_PINID='GND1';
NODE_NAME     T1P24 GND2
 '@BASEBOARD_FAB2_LIB.BASEBOARD_FAB2(SCH_1):PAGE271_I38@W_HDL.TPAD-DIFF-4P-GP(CHIPS)':
 'GND2': CDS_PINID='GND2';
NODE_NAME     T1P19 GND1
 '@BASEBOARD_FAB2_LIB.BASEBOARD_FAB2(SCH_1):PAGE271_I39@W_HDL.TPAD-DIFF-4P-GP(CHIPS)':
 'GND1': CDS_PINID='GND1';
NODE_NAME     T1P19 GND2
 '@BASEBOARD_FAB2_LIB.BASEBOARD_FAB2(SCH_1):PAGE271_I39@W_HDL.TPAD-DIFF-4P-GP(CHIPS)':
 'GND2': CDS_PINID='GND2';
NODE_NAME     T1P22 GND1
 '@BASEBOARD_FAB2_LIB.BASEBOARD_FAB2(SCH_1):PAGE271_I45@W_HDL.TPAD-DIFF-4P-GP(CHIPS)':
 'GND1': CDS_PINID='GND1';
NODE_NAME     T1P22 GND2
 '@BASEBOARD_FAB2_LIB.BASEBOARD_FAB2(SCH_1):PAGE271_I45@W_HDL.TPAD-DIFF-4P-GP(CHIPS)':
 'GND2': CDS_PINID='GND2';
NODE_NAME     T1P23 GND1
 '@BASEBOARD_FAB2_LIB.BASEBOARD_FAB2(SCH_1):PAGE271_I47@W_HDL.TPAD-DIFF-4P-GP(CHIPS)':
 'GND1': CDS_PINID='GND1';
NODE_NAME     T1P23 GND2
 '@BASEBOARD_FAB2_LIB.BASEBOARD_FAB2(SCH_1):PAGE271_I47@W_HDL.TPAD-DIFF-4P-GP(CHIPS)':
 'GND2': CDS_PINID='GND2';
NODE_NAME     T1P25 GND1
 '@BASEBOARD_FAB2_LIB.BASEBOARD_FAB2(SCH_1):PAGE271_I50@W_HDL.TPAD-SE-2P-GP(CHIPS)':
 'GND1': CDS_PINID='GND1';
NODE_NAME     T1P26 GND1
 '@BASEBOARD_FAB2_LIB.BASEBOARD_FAB2(SCH_1):PAGE271_I52@W_HDL.TPAD-SE-2P-GP(CHIPS)':
 'GND1': CDS_PINID='GND1';
NODE_NAME     T1P27 GND1
 '@BASEBOARD_FAB2_LIB.BASEBOARD_FAB2(SCH_1):PAGE271_I54@W_HDL.TPAD-SE-2P-GP(CHIPS)':
 'GND1': CDS_PINID='GND1';
NODE_NAME     T1P29 GND1
 '@BASEBOARD_FAB2_LIB.BASEBOARD_FAB2(SCH_1):PAGE271_I56@W_HDL.TPAD-SE-2P-GP(CHIPS)':
 'GND1': CDS_PINID='GND1';
NODE_NAME     T1P28 GND1
 '@BASEBOARD_FAB2_LIB.BASEBOARD_FAB2(SCH_1):PAGE271_I60@W_HDL.TPAD-SE-2P-GP(CHIPS)':
 'GND1': CDS_PINID='GND1';
NODE_NAME     T1P30 GND1
 '@BASEBOARD_FAB2_LIB.BASEBOARD_FAB2(SCH_1):PAGE271_I61@W_HDL.TPAD-SE-2P-GP(CHIPS)':
 'GND1': CDS_PINID='GND1';
NODE_NAME     T1P34 GND1
 '@BASEBOARD_FAB2_LIB.BASEBOARD_FAB2(SCH_1):PAGE271_I62@W_HDL.TPAD-SE-2P-GP(CHIPS)':
 'GND1': CDS_PINID='GND1';
NODE_NAME     T1P36 GND1
 '@BASEBOARD_FAB2_LIB.BASEBOARD_FAB2(SCH_1):PAGE271_I63@W_HDL.TPAD-SE-2P-GP(CHIPS)':
 'GND1': CDS_PINID='GND1';
NODE_NAME     T1P35 GND1
 '@BASEBOARD_FAB2_LIB.BASEBOARD_FAB2(SCH_1):PAGE271_I67@W_HDL.TPAD-SE-2P-GP(CHIPS)':
 'GND1': CDS_PINID='GND1';
NODE_NAME     T1P31 GND1
 '@BASEBOARD_FAB2_LIB.BASEBOARD_FAB2(SCH_1):PAGE271_I71@W_HDL.TPAD-SE-2P-GP(CHIPS)':
 'GND1': CDS_PINID='GND1';
NODE_NAME     T1P32 GND1
 '@BASEBOARD_FAB2_LIB.BASEBOARD_FAB2(SCH_1):PAGE271_I72@W_HDL.TPAD-SE-2P-GP(CHIPS)':
 'GND1': CDS_PINID='GND1';
NODE_NAME     T1P33 GND1
 '@BASEBOARD_FAB2_LIB.BASEBOARD_FAB2(SCH_1):PAGE271_I73@W_HDL.TPAD-SE-2P-GP(CHIPS)':
 'GND1': CDS_PINID='GND1';
NODE_NAME     R1W41 1
 '@BASEBOARD_FAB2_LIB.BASEBOARD_FAB2(SCH_1):PAGE188_I129@MSTR_DISCRETE.RES(CHIPS)':
 'A': CDS_PINID='A';
NODE_NAME     R8C21 2
 '@BASEBOARD_FAB2_LIB.BASEBOARD_FAB2(SCH_1):PAGE120_I275@MSTR_DISCRETE.RES(CHIPS)':
 'B': CDS_PINID='B';
NODE_NAME     R8D40 2
 '@BASEBOARD_FAB2_LIB.BASEBOARD_FAB2(SCH_1):PAGE196_I130@MSTR_DISCRETE.RES(CHIPS)':
 'B': CDS_PINID='B';
NODE_NAME     C8C1 2
 '@BASEBOARD_FAB2_LIB.BASEBOARD_FAB2(SCH_1):PAGE118_I178@MSTR_DISCRETE.CAP(CHIPS)':
 'B': CDS_PINID='B';
NODE_NAME     C8C2 2
 '@BASEBOARD_FAB2_LIB.BASEBOARD_FAB2(SCH_1):PAGE118_I179@MSTR_DISCRETE.CAP(CHIPS)':
 'B': CDS_PINID='B';
NODE_NAME     R9T8 2
 '@BASEBOARD_FAB2_LIB.BASEBOARD_FAB2(SCH_1):PAGE181_I137@MSTR_DISCRETE.RES(CHIPS)':
 'B': CDS_PINID='B';
NODE_NAME     C25W101 2
 '@BASEBOARD_FAB2_LIB.BASEBOARD_FAB2(SCH_1):PAGE269_I79@DEV_DISCRETE.CAP_A(CHIPS)':
 'B': CDS_PINID='B';
NODE_NAME     U8W2 2
 '@BASEBOARD_FAB2_LIB.BASEBOARD_FAB2(SCH_1):PAGE245_I66@MSTR_ANALOG.NC7SB3157(CHIPS)':
 'GND': CDS_PINID='GND';
NODE_NAME     C8W6 2
 '@BASEBOARD_FAB2_LIB.BASEBOARD_FAB2(SCH_1):PAGE245_I71@DEV_DISCRETE.CAP_A(CHIPS)':
 'B': CDS_PINID='B';
NODE_NAME     C8W5 2
 '@BASEBOARD_FAB2_LIB.BASEBOARD_FAB2(SCH_1):PAGE245_I74@DEV_DISCRETE.CAP_A(CHIPS)':
 'B': CDS_PINID='B';
NODE_NAME     R1T10 2
 '@BASEBOARD_FAB2_LIB.BASEBOARD_FAB2(SCH_1):PAGE164_I101@MSTR_DISCRETE.RES(CHIPS)':
 'B': CDS_PINID='B';
NODE_NAME     U6W12 2
 '@BASEBOARD_FAB2_LIB.BASEBOARD_FAB2(SCH_1):PAGE176_I182@MSTR_ANALOG.NC7SB3157(CHIPS)':
 'GND': CDS_PINID='GND';
NET_NAME
'GND_LAN_TRCT1234_C'
 '@BASEBOARD_FAB2_LIB.BASEBOARD_FAB2(SCH_1):GND_LAN_TRCT1234_C':
 C_SIGNAL='@baseboard_fab2_lib.baseboard_fab2(sch_1):gnd_lan_trct1234_c';
NODE_NAME     C9G4 1
 '@BASEBOARD_FAB2_LIB.BASEBOARD_FAB2(SCH_1):PAGE141_I46@DEV_DISCRETE.CAP_A(CHIPS)':
 'A': CDS_PINID='A';
NODE_NAME     C9G6 1
 '@BASEBOARD_FAB2_LIB.BASEBOARD_FAB2(SCH_1):PAGE141_I47@DEV_DISCRETE.CAP_A(CHIPS)':
 'A': CDS_PINID='A';
NODE_NAME     C9G5 1
 '@BASEBOARD_FAB2_LIB.BASEBOARD_FAB2(SCH_1):PAGE141_I48@MSTR_DISCRETE.CAP(CHIPS)':
 'A': CDS_PINID='A';
NODE_NAME     JA9G1 R1
 '@BASEBOARD_FAB2_LIB.BASEBOARD_FAB2(SCH_1):PAGE141_I129@W_HDL.SKT-RJ45-LED-XFOR-1-GP(CHIPS)':
 'R1': CDS_PINID='R1';
NODE_NAME     JA9G1 R11
 '@BASEBOARD_FAB2_LIB.BASEBOARD_FAB2(SCH_1):PAGE141_I129@W_HDL.SKT-RJ45-LED-XFOR-1-GP(CHIPS)':
 'R11': CDS_PINID='R11';
NET_NAME
'GPIOS7'
 '@BASEBOARD_FAB2_LIB.BASEBOARD_FAB2(SCH_1):GPIOS7':
 C_SIGNAL='@baseboard_fab2_lib.baseboard_fab2(sch_1):gpios7';
NODE_NAME     U25W4 AA20
 '@BASEBOARD_FAB2_LIB.BASEBOARD_FAB2(SCH_1):PAGE146_I104@W_HDL.AST2520A1-GP-GP(CHIPS)':
 'GPIOS7_VPOB9': CDS_PINID='GPIOS7_VPOB9';
NODE_NAME     R25W100 2
 '@BASEBOARD_FAB2_LIB.BASEBOARD_FAB2(SCH_1):PAGE150_I211@MSTR_DISCRETE.RES(CHIPS)':
 'B': CDS_PINID='B';
NET_NAME
'HSC_SMBUS_SWITCH_EN'
 '@BASEBOARD_FAB2_LIB.BASEBOARD_FAB2(SCH_1):HSC_SMBUS_SWITCH_EN':
 C_SIGNAL='@baseboard_fab2_lib.baseboard_fab2(sch_1):hsc_smbus_switch_en';
NODE_NAME     U25W4 P18
 '@BASEBOARD_FAB2_LIB.BASEBOARD_FAB2(SCH_1):PAGE146_I104@W_HDL.AST2520A1-GP-GP(CHIPS)':
 'GPIOS3_VPOB5_SALT6': CDS_PINID='GPIOS3_VPOB5_SALT6';
NODE_NAME     R6W28 2
 '@BASEBOARD_FAB2_LIB.BASEBOARD_FAB2(SCH_1):PAGE247_I112@MSTR_DISCRETE.RES(CHIPS)':
 'B': CDS_PINID='B';
NODE_NAME     U6W2 5
 '@BASEBOARD_FAB2_LIB.BASEBOARD_FAB2(SCH_1):PAGE247_I118@W_HDL.TCA9517DGKR-GP(CHIPS)':
 'EN': CDS_PINID='EN';
NET_NAME
'H_CPU0_ABC_MEMHOT_LVT3_R_N'
 '@BASEBOARD_FAB2_LIB.BASEBOARD_FAB2(SCH_1):H_CPU0_ABC_MEMHOT_LVT3_R_N':
 C_SIGNAL='@baseboard_fab2_lib.baseboard_fab2(sch_1):h_cpu0_abc_memhot_lvt3_r_n';
NODE_NAME     U9G1 9
 '@BASEBOARD_FAB2_LIB.BASEBOARD_FAB2(SCH_1):PAGE152_I1@MSTR_DIGITAL.GTL2014(CHIPS)':
 'A3': CDS_PINID='A3';
NODE_NAME     R1U59 1
 '@BASEBOARD_FAB2_LIB.BASEBOARD_FAB2(SCH_1):PAGE152_I74@MSTR_DISCRETE.RES(CHIPS)':
 'A': CDS_PINID='A';
NET_NAME
'H_CPU0_BMCINIT'
 '@BASEBOARD_FAB2_LIB.BASEBOARD_FAB2(SCH_1):H_CPU0_BMCINIT':
 C_SIGNAL='@baseboard_fab2_lib.baseboard_fab2(sch_1):h_cpu0_bmcinit';
NODE_NAME     U5D1 BD23
 '@BASEBOARD_FAB2_LIB.BASEBOARD_FAB2(SCH_1):PAGE21_I259@CHPSET_LIB.SKX_EXT_B(CHIPS)':
 'BMCINIT': CDS_PINID='BMCINIT';
NODE_NAME     R6D7 2
 '@BASEBOARD_FAB2_LIB.BASEBOARD_FAB2(SCH_1):PAGE90_I31@MSTR_DISCRETE.RES(CHIPS)':
 'B': CDS_PINID='B';
NODE_NAME     R6D16 2
 '@BASEBOARD_FAB2_LIB.BASEBOARD_FAB2(SCH_1):PAGE156_I299@MSTR_DISCRETE.RES(CHIPS)':
 'B': CDS_PINID='B';
NET_NAME
'H_CPU0_CATERR_G_N'
 '@BASEBOARD_FAB2_LIB.BASEBOARD_FAB2(SCH_1):H_CPU0_CATERR_G_N':
 C_SIGNAL='@baseboard_fab2_lib.baseboard_fab2(sch_1):h_cpu0_caterr_g_n';
NODE_NAME     U5D1 AL14
 '@BASEBOARD_FAB2_LIB.BASEBOARD_FAB2(SCH_1):PAGE21_I259@CHPSET_LIB.SKX_EXT_B(CHIPS)':
 'CATERR_N': CDS_PINID='CATERR_N';
NODE_NAME     R3P59 1
 '@BASEBOARD_FAB2_LIB.BASEBOARD_FAB2(SCH_1):PAGE92_I97@MSTR_DISCRETE.RES(CHIPS)':
 'A': CDS_PINID='A';
NODE_NAME     R4R2 2
 '@BASEBOARD_FAB2_LIB.BASEBOARD_FAB2(SCH_1):PAGE92_I101@MSTR_DISCRETE.RES(CHIPS)':
 'B': CDS_PINID='B';
NET_NAME
'H_CPU0_DEF_MEMHOT_LVT3_R_N'
 '@BASEBOARD_FAB2_LIB.BASEBOARD_FAB2(SCH_1):H_CPU0_DEF_MEMHOT_LVT3_R_N':
 C_SIGNAL='@baseboard_fab2_lib.baseboard_fab2(sch_1):h_cpu0_def_memhot_lvt3_r_n';
NODE_NAME     U9G1 10
 '@BASEBOARD_FAB2_LIB.BASEBOARD_FAB2(SCH_1):PAGE152_I1@MSTR_DIGITAL.GTL2014(CHIPS)':
 'A2': CDS_PINID='A2';
NODE_NAME     R9G33 1
 '@BASEBOARD_FAB2_LIB.BASEBOARD_FAB2(SCH_1):PAGE152_I73@MSTR_DISCRETE.RES(CHIPS)':
 'A': CDS_PINID='A';
NET_NAME
'H_CPU0_ERR0_G_N'
 '@BASEBOARD_FAB2_LIB.BASEBOARD_FAB2(SCH_1):H_CPU0_ERR0_G_N':
 C_SIGNAL='@baseboard_fab2_lib.baseboard_fab2(sch_1):h_cpu0_err0_g_n';
NODE_NAME     U5D1 AJ12
 '@BASEBOARD_FAB2_LIB.BASEBOARD_FAB2(SCH_1):PAGE21_I259@CHPSET_LIB.SKX_EXT_B(CHIPS)':
 'ERROR_N'<0>: CDS_PINID='ERROR_N(0)';
NODE_NAME     R2T17 1
 '@BASEBOARD_FAB2_LIB.BASEBOARD_FAB2(SCH_1):PAGE93_I23@MSTR_DISCRETE.RES(CHIPS)':
 'A': CDS_PINID='A';
NET_NAME
'H_CPU0_ERR1_G_N'
 '@BASEBOARD_FAB2_LIB.BASEBOARD_FAB2(SCH_1):H_CPU0_ERR1_G_N':
 C_SIGNAL='@baseboard_fab2_lib.baseboard_fab2(sch_1):h_cpu0_err1_g_n';
NODE_NAME     U5D1 AK11
 '@BASEBOARD_FAB2_LIB.BASEBOARD_FAB2(SCH_1):PAGE21_I259@CHPSET_LIB.SKX_EXT_B(CHIPS)':
 'ERROR_N'<1>: CDS_PINID='ERROR_N(1)';
NODE_NAME     R2T32 1
 '@BASEBOARD_FAB2_LIB.BASEBOARD_FAB2(SCH_1):PAGE93_I15@MSTR_DISCRETE.RES(CHIPS)':
 'A': CDS_PINID='A';
NET_NAME
'H_CPU0_ERR2_G_N'
 '@BASEBOARD_FAB2_LIB.BASEBOARD_FAB2(SCH_1):H_CPU0_ERR2_G_N':
 C_SIGNAL='@baseboard_fab2_lib.baseboard_fab2(sch_1):h_cpu0_err2_g_n';
NODE_NAME     U5D1 AL12
 '@BASEBOARD_FAB2_LIB.BASEBOARD_FAB2(SCH_1):PAGE21_I259@CHPSET_LIB.SKX_EXT_B(CHIPS)':
 'ERROR_N'<2>: CDS_PINID='ERROR_N(2)';
NODE_NAME     R2T40 1
 '@BASEBOARD_FAB2_LIB.BASEBOARD_FAB2(SCH_1):PAGE92_I93@MSTR_DISCRETE.RES(CHIPS)':
 'A': CDS_PINID='A';
NET_NAME
'H_CPU0_FAST_WAKE'
 '@BASEBOARD_FAB2_LIB.BASEBOARD_FAB2(SCH_1):H_CPU0_FAST_WAKE':
 C_SIGNAL='@baseboard_fab2_lib.baseboard_fab2(sch_1):h_cpu0_fast_wake';
NODE_NAME     R2T5 2
 '@BASEBOARD_FAB2_LIB.BASEBOARD_FAB2(SCH_1):PAGE157_I326@MSTR_DISCRETE.RES(CHIPS)':
 'B': CDS_PINID='B';
NODE_NAME     Q2T1 3
 '@BASEBOARD_FAB2_LIB.BASEBOARD_FAB2(SCH_1):PAGE157_I330@MSTR_DISCRETE.NPN(CHIPS)':
 'C': CDS_PINID='C';
NODE_NAME     Q2T2 1
 '@BASEBOARD_FAB2_LIB.BASEBOARD_FAB2(SCH_1):PAGE157_I340@MSTR_DISCRETE.FET_N(CHIPS)':
 'GATE': CDS_PINID='GATE';
NET_NAME
'H_CPU0_FAST_WAKE_B_N'
 '@BASEBOARD_FAB2_LIB.BASEBOARD_FAB2(SCH_1):H_CPU0_FAST_WAKE_B_N':
 C_SIGNAL='@baseboard_fab2_lib.baseboard_fab2(sch_1):h_cpu0_fast_wake_b_n';
NODE_NAME     Q2T1 1
 '@BASEBOARD_FAB2_LIB.BASEBOARD_FAB2(SCH_1):PAGE157_I330@MSTR_DISCRETE.NPN(CHIPS)':
 'B': CDS_PINID='B';
NODE_NAME     R4R1 2
 '@BASEBOARD_FAB2_LIB.BASEBOARD_FAB2(SCH_1):PAGE157_I368@MSTR_DISCRETE.RES(CHIPS)':
 'B': CDS_PINID='B';
NET_NAME
'H_CPU0_FAST_WAKE_LVT3_N'
 '@BASEBOARD_FAB2_LIB.BASEBOARD_FAB2(SCH_1):H_CPU0_FAST_WAKE_LVT3_N':
 C_SIGNAL='@baseboard_fab2_lib.baseboard_fab2(sch_1):h_cpu0_fast_wake_lvt3_n',
 PHYS_NET_NAME='H_CPU0_FAST_WAKE_LVT3_N';
NODE_NAME     U7C1 BV47
 '@BASEBOARD_FAB2_LIB.BASEBOARD_FAB2(SCH_1):PAGE119_I115@MSTR_U_PROC.LBG_CORE_QAT_EXT_D(CHIPS)':
 'GPP_D10_SSATA_DEVSLP4': CDS_PINID='GPP_D10_SSATA_DEVSLP4';
NODE_NAME     R2T7 2
 '@BASEBOARD_FAB2_LIB.BASEBOARD_FAB2(SCH_1):PAGE157_I327@MSTR_DISCRETE.RES(CHIPS)':
 'B': CDS_PINID='B';
NODE_NAME     Q2T2 3
 '@BASEBOARD_FAB2_LIB.BASEBOARD_FAB2(SCH_1):PAGE157_I340@MSTR_DISCRETE.FET_N(CHIPS)':
 'DRN': CDS_PINID='DRN';
NODE_NAME     U25W4 K18
 '@BASEBOARD_FAB2_LIB.BASEBOARD_FAB2(SCH_1):PAGE144_I95@W_HDL.AST2520A1-GP-GP(CHIPS)':
 'GPIOB3': CDS_PINID='GPIOB3';
NET_NAME
'H_CPU0_FAST_WAKE_N'
 '@BASEBOARD_FAB2_LIB.BASEBOARD_FAB2(SCH_1):H_CPU0_FAST_WAKE_N':
 C_SIGNAL='@baseboard_fab2_lib.baseboard_fab2(sch_1):h_cpu0_fast_wake_n';
NODE_NAME     U5D1 AF15
 '@BASEBOARD_FAB2_LIB.BASEBOARD_FAB2(SCH_1):PAGE21_I259@CHPSET_LIB.SKX_EXT_B(CHIPS)':
 'PM_FAST_WAKE_N': CDS_PINID='PM_FAST_WAKE_N';
NODE_NAME     R3D18 1
 '@BASEBOARD_FAB2_LIB.BASEBOARD_FAB2(SCH_1):PAGE97_I33@MSTR_DISCRETE.RES(CHIPS)':
 'A': CDS_PINID='A';
NODE_NAME     R4R4 2
 '@BASEBOARD_FAB2_LIB.BASEBOARD_FAB2(SCH_1):PAGE97_I42@MSTR_DISCRETE.RES(CHIPS)':
 'B': CDS_PINID='B';
NODE_NAME     R4R1 1
 '@BASEBOARD_FAB2_LIB.BASEBOARD_FAB2(SCH_1):PAGE157_I368@MSTR_DISCRETE.RES(CHIPS)':
 'A': CDS_PINID='A';
NET_NAME
'H_CPU0_FIVR_FAULT_G'
 '@BASEBOARD_FAB2_LIB.BASEBOARD_FAB2(SCH_1):H_CPU0_FIVR_FAULT_G':
 C_SIGNAL='@baseboard_fab2_lib.baseboard_fab2(sch_1):h_cpu0_fivr_fault_g';
NODE_NAME     U5D1 AU14
 '@BASEBOARD_FAB2_LIB.BASEBOARD_FAB2(SCH_1):PAGE22_I204@CHPSET_LIB.SKX_EXT_B(CHIPS)':
 'FIVR_FAULT': CDS_PINID='FIVR_FAULT';
NODE_NAME     U7D2 3
 '@BASEBOARD_FAB2_LIB.BASEBOARD_FAB2(SCH_1):PAGE92_I32@MSTR_DIGITAL.GTL2014(CHIPS)':
 'B1': CDS_PINID='B1';
NET_NAME
'H_CPU0_MEMABC_MEMHOT'
 '@BASEBOARD_FAB2_LIB.BASEBOARD_FAB2(SCH_1):H_CPU0_MEMABC_MEMHOT':
 C_SIGNAL='@baseboard_fab2_lib.baseboard_fab2(sch_1):h_cpu0_memabc_memhot';
NODE_NAME     Q3U1 6
 '@BASEBOARD_FAB2_LIB.BASEBOARD_FAB2(SCH_1):PAGE94_I49@MSTR_DISCRETE.FET_N_DUAL(CHIPS)':
 'DRAIN'<0>: CDS_PINID='DRAIN(0)';
NODE_NAME     R7G7 2
 '@BASEBOARD_FAB2_LIB.BASEBOARD_FAB2(SCH_1):PAGE94_I51@MSTR_DISCRETE.RES(CHIPS)':
 'B': CDS_PINID='B';
NODE_NAME     Q3U1 5
 '@BASEBOARD_FAB2_LIB.BASEBOARD_FAB2(SCH_1):PAGE94_I89@MSTR_DISCRETE.FET_N_DUAL(CHIPS)':
 'GATE'<0>: CDS_PINID='GATE(0)';
NET_NAME
'H_CPU0_MEMABC_MEMHOT_G_N'
 '@BASEBOARD_FAB2_LIB.BASEBOARD_FAB2(SCH_1):H_CPU0_MEMABC_MEMHOT_G_N':
 C_SIGNAL='@baseboard_fab2_lib.baseboard_fab2(sch_1):h_cpu0_memabc_memhot_g_n';
NODE_NAME     U5D1 AH13
 '@BASEBOARD_FAB2_LIB.BASEBOARD_FAB2(SCH_1):PAGE21_I259@CHPSET_LIB.SKX_EXT_B(CHIPS)':
 'MEM_HOT_C012_N': CDS_PINID='MEM_HOT_C012_N';
NODE_NAME     Q3U1 3
 '@BASEBOARD_FAB2_LIB.BASEBOARD_FAB2(SCH_1):PAGE94_I89@MSTR_DISCRETE.FET_N_DUAL(CHIPS)':
 'DRAIN'<0>: CDS_PINID='DRAIN(0)';
NODE_NAME     Q2U1 6
 '@BASEBOARD_FAB2_LIB.BASEBOARD_FAB2(SCH_1):PAGE95_I28@MSTR_DISCRETE.FET_N_DUAL(CHIPS)':
 'DRAIN'<0>: CDS_PINID='DRAIN(0)';
NODE_NAME     R9G34 1
 '@BASEBOARD_FAB2_LIB.BASEBOARD_FAB2(SCH_1):PAGE152_I45@MSTR_DISCRETE.RES(CHIPS)':
 'A': CDS_PINID='A';
NODE_NAME     R2U51 2
 '@BASEBOARD_FAB2_LIB.BASEBOARD_FAB2(SCH_1):PAGE152_I51@MSTR_DISCRETE.RES(CHIPS)':
 'B': CDS_PINID='B';
NODE_NAME     R2U40 2
 '@BASEBOARD_FAB2_LIB.BASEBOARD_FAB2(SCH_1):PAGE152_I53@MSTR_DISCRETE.RES(CHIPS)':
 'B': CDS_PINID='B';
NODE_NAME     R4P17 1
 '@BASEBOARD_FAB2_LIB.BASEBOARD_FAB2(SCH_1):PAGE152_I58@MSTR_DISCRETE.RES(CHIPS)':
 'A': CDS_PINID='A';
NET_NAME
'H_CPU0_MEMABC_MEMHOT_G_PCH_N'
 '@BASEBOARD_FAB2_LIB.BASEBOARD_FAB2(SCH_1):H_CPU0_MEMABC_MEMHOT_G_PCH_N':
 C_SIGNAL='@baseboard_fab2_lib.baseboard_fab2(sch_1):h_cpu0_memabc_memhot_g_pch_~
n';
NODE_NAME     R2U51 1
 '@BASEBOARD_FAB2_LIB.BASEBOARD_FAB2(SCH_1):PAGE152_I51@MSTR_DISCRETE.RES(CHIPS)':
 'A': CDS_PINID='A';
NODE_NAME     R2U49 1
 '@BASEBOARD_FAB2_LIB.BASEBOARD_FAB2(SCH_1):PAGE152_I66@MSTR_DISCRETE.RES(CHIPS)':
 'A': CDS_PINID='A';
NET_NAME
'H_CPU0_MEMABC_MEMHOT_G_R_N'
 '@BASEBOARD_FAB2_LIB.BASEBOARD_FAB2(SCH_1):H_CPU0_MEMABC_MEMHOT_G_R_N':
 C_SIGNAL='@baseboard_fab2_lib.baseboard_fab2(sch_1):h_cpu0_memabc_memhot_g_r_n';
NODE_NAME     U9G1 6
 '@BASEBOARD_FAB2_LIB.BASEBOARD_FAB2(SCH_1):PAGE152_I1@MSTR_DIGITAL.GTL2014(CHIPS)':
 'B3': CDS_PINID='B3';
NODE_NAME     R9G34 2
 '@BASEBOARD_FAB2_LIB.BASEBOARD_FAB2(SCH_1):PAGE152_I45@MSTR_DISCRETE.RES(CHIPS)':
 'B': CDS_PINID='B';
NET_NAME
'H_CPU0_MEMABC_MEMHOT_LVT3_BMC_N'
 '@BASEBOARD_FAB2_LIB.BASEBOARD_FAB2(SCH_1):H_CPU0_MEMABC_MEMHOT_LVT3_BMC_N':
 C_SIGNAL='@baseboard_fab2_lib.baseboard_fab2(sch_1):h_cpu0_memabc_memhot_lvt3_b~
mc_n';
NODE_NAME     R2U47 2
 '@BASEBOARD_FAB2_LIB.BASEBOARD_FAB2(SCH_1):PAGE152_I79@MSTR_DISCRETE.RES(CHIPS)':
 'B': CDS_PINID='B';
NODE_NAME     U25W4 H5
 '@BASEBOARD_FAB2_LIB.BASEBOARD_FAB2(SCH_1):PAGE147_I106@W_HDL.AST2520A1-GP-GP(CHIPS)':
 'ADC12_GPIX4': CDS_PINID='ADC12_GPIX4';
NET_NAME
'H_CPU0_MEMABC_MEMHOT_LVT3_K_N'
 '@BASEBOARD_FAB2_LIB.BASEBOARD_FAB2(SCH_1):H_CPU0_MEMABC_MEMHOT_LVT3_K_N':
 C_SIGNAL='@baseboard_fab2_lib.baseboard_fab2(sch_1):h_cpu0_memabc_memhot_lvt3_k~
_n';
NODE_NAME     R1U46 1
 '@BASEBOARD_FAB2_LIB.BASEBOARD_FAB2(SCH_1):PAGE152_I6@MSTR_DISCRETE.RES(CHIPS)':
 'A': CDS_PINID='A';
NODE_NAME     R2U49 2
 '@BASEBOARD_FAB2_LIB.BASEBOARD_FAB2(SCH_1):PAGE152_I66@MSTR_DISCRETE.RES(CHIPS)':
 'B': CDS_PINID='B';
NODE_NAME     R1U59 2
 '@BASEBOARD_FAB2_LIB.BASEBOARD_FAB2(SCH_1):PAGE152_I74@MSTR_DISCRETE.RES(CHIPS)':
 'B': CDS_PINID='B';
NET_NAME
'H_CPU0_MEMABC_MEMHOT_LVT3_N'
 '@BASEBOARD_FAB2_LIB.BASEBOARD_FAB2(SCH_1):H_CPU0_MEMABC_MEMHOT_LVT3_N':
 C_SIGNAL='@baseboard_fab2_lib.baseboard_fab2(sch_1):h_cpu0_memabc_memhot_lvt3_n~
';
NODE_NAME     R1U46 2
 '@BASEBOARD_FAB2_LIB.BASEBOARD_FAB2(SCH_1):PAGE152_I6@MSTR_DISCRETE.RES(CHIPS)':
 'B': CDS_PINID='B';
NODE_NAME     R2U47 1
 '@BASEBOARD_FAB2_LIB.BASEBOARD_FAB2(SCH_1):PAGE152_I79@MSTR_DISCRETE.RES(CHIPS)':
 'A': CDS_PINID='A';
NODE_NAME     R3N30 1
 '@BASEBOARD_FAB2_LIB.BASEBOARD_FAB2(SCH_1):PAGE152_I95@MSTR_DISCRETE.RES(CHIPS)':
 'A': CDS_PINID='A';
NET_NAME
'H_CPU0_MEMABC_MEMHOT_PCH_N'
 '@BASEBOARD_FAB2_LIB.BASEBOARD_FAB2(SCH_1):H_CPU0_MEMABC_MEMHOT_PCH_N':
 C_SIGNAL='@baseboard_fab2_lib.baseboard_fab2(sch_1):h_cpu0_memabc_memhot_pch_n';
NODE_NAME     U7C1 Y15
 '@BASEBOARD_FAB2_LIB.BASEBOARD_FAB2(SCH_1):PAGE121_I34@MSTR_U_PROC.LBG_CORE_QAT_EXT_D(CHIPS)':
 'GPP_L12_TESTCH1_D1': CDS_PINID='GPP_L12_TESTCH1_D1';
NODE_NAME     R3N30 2
 '@BASEBOARD_FAB2_LIB.BASEBOARD_FAB2(SCH_1):PAGE152_I95@MSTR_DISCRETE.RES(CHIPS)':
 'B': CDS_PINID='B';
NET_NAME
'H_CPU0_MEMDEF_MEMHOT'
 '@BASEBOARD_FAB2_LIB.BASEBOARD_FAB2(SCH_1):H_CPU0_MEMDEF_MEMHOT':
 C_SIGNAL='@baseboard_fab2_lib.baseboard_fab2(sch_1):h_cpu0_memdef_memhot';
NODE_NAME     Q7E1 6
 '@BASEBOARD_FAB2_LIB.BASEBOARD_FAB2(SCH_1):PAGE94_I60@MSTR_DISCRETE.FET_N_DUAL(CHIPS)':
 'DRAIN'<0>: CDS_PINID='DRAIN(0)';
NODE_NAME     Q7E1 5
 '@BASEBOARD_FAB2_LIB.BASEBOARD_FAB2(SCH_1):PAGE94_I64@MSTR_DISCRETE.FET_N_DUAL(CHIPS)':
 'GATE'<0>: CDS_PINID='GATE(0)';
NODE_NAME     R3R4 2
 '@BASEBOARD_FAB2_LIB.BASEBOARD_FAB2(SCH_1):PAGE94_I66@MSTR_DISCRETE.RES(CHIPS)':
 'B': CDS_PINID='B';
NET_NAME
'H_CPU0_MEMDEF_MEMHOT_G_N'
 '@BASEBOARD_FAB2_LIB.BASEBOARD_FAB2(SCH_1):H_CPU0_MEMDEF_MEMHOT_G_N':
 C_SIGNAL='@baseboard_fab2_lib.baseboard_fab2(sch_1):h_cpu0_memdef_memhot_g_n';
NODE_NAME     U5D1 AF13
 '@BASEBOARD_FAB2_LIB.BASEBOARD_FAB2(SCH_1):PAGE21_I259@CHPSET_LIB.SKX_EXT_B(CHIPS)':
 'MEM_HOT_C345_N': CDS_PINID='MEM_HOT_C345_N';
NODE_NAME     Q7E1 3
 '@BASEBOARD_FAB2_LIB.BASEBOARD_FAB2(SCH_1):PAGE94_I64@MSTR_DISCRETE.FET_N_DUAL(CHIPS)':
 'DRAIN'<0>: CDS_PINID='DRAIN(0)';
NODE_NAME     Q2U1 3
 '@BASEBOARD_FAB2_LIB.BASEBOARD_FAB2(SCH_1):PAGE95_I113@MSTR_DISCRETE.FET_N_DUAL(CHIPS)':
 'DRAIN'<0>: CDS_PINID='DRAIN(0)';
NODE_NAME     R1U58 1
 '@BASEBOARD_FAB2_LIB.BASEBOARD_FAB2(SCH_1):PAGE152_I49@MSTR_DISCRETE.RES(CHIPS)':
 'A': CDS_PINID='A';
NODE_NAME     R1U56 2
 '@BASEBOARD_FAB2_LIB.BASEBOARD_FAB2(SCH_1):PAGE152_I50@MSTR_DISCRETE.RES(CHIPS)':
 'B': CDS_PINID='B';
NODE_NAME     R2U41 2
 '@BASEBOARD_FAB2_LIB.BASEBOARD_FAB2(SCH_1):PAGE152_I54@MSTR_DISCRETE.RES(CHIPS)':
 'B': CDS_PINID='B';
NODE_NAME     R4P20 1
 '@BASEBOARD_FAB2_LIB.BASEBOARD_FAB2(SCH_1):PAGE152_I59@MSTR_DISCRETE.RES(CHIPS)':
 'A': CDS_PINID='A';
NET_NAME
'H_CPU0_MEMDEF_MEMHOT_G_PCH_N'
 '@BASEBOARD_FAB2_LIB.BASEBOARD_FAB2(SCH_1):H_CPU0_MEMDEF_MEMHOT_G_PCH_N':
 C_SIGNAL='@baseboard_fab2_lib.baseboard_fab2(sch_1):h_cpu0_memdef_memhot_g_pch_~
n';
NODE_NAME     R9G27 1
 '@BASEBOARD_FAB2_LIB.BASEBOARD_FAB2(SCH_1):PAGE152_I47@MSTR_DISCRETE.RES(CHIPS)':
 'A': CDS_PINID='A';
NODE_NAME     R1U56 1
 '@BASEBOARD_FAB2_LIB.BASEBOARD_FAB2(SCH_1):PAGE152_I50@MSTR_DISCRETE.RES(CHIPS)':
 'A': CDS_PINID='A';
NET_NAME
'H_CPU0_MEMDEF_MEMHOT_G_R_N'
 '@BASEBOARD_FAB2_LIB.BASEBOARD_FAB2(SCH_1):H_CPU0_MEMDEF_MEMHOT_G_R_N':
 C_SIGNAL='@baseboard_fab2_lib.baseboard_fab2(sch_1):h_cpu0_memdef_memhot_g_r_n';
NODE_NAME     U9G1 5
 '@BASEBOARD_FAB2_LIB.BASEBOARD_FAB2(SCH_1):PAGE152_I1@MSTR_DIGITAL.GTL2014(CHIPS)':
 'B2': CDS_PINID='B2';
NODE_NAME     R1U58 2
 '@BASEBOARD_FAB2_LIB.BASEBOARD_FAB2(SCH_1):PAGE152_I49@MSTR_DISCRETE.RES(CHIPS)':
 'B': CDS_PINID='B';
NET_NAME
'H_CPU0_MEMDEF_MEMHOT_LVT3_BMC_N'
 '@BASEBOARD_FAB2_LIB.BASEBOARD_FAB2(SCH_1):H_CPU0_MEMDEF_MEMHOT_LVT3_BMC_N':
 C_SIGNAL='@baseboard_fab2_lib.baseboard_fab2(sch_1):h_cpu0_memdef_memhot_lvt3_b~
mc_n';
NODE_NAME     R9G29 2
 '@BASEBOARD_FAB2_LIB.BASEBOARD_FAB2(SCH_1):PAGE152_I92@MSTR_DISCRETE.RES(CHIPS)':
 'B': CDS_PINID='B';
NODE_NAME     U25W4 G1
 '@BASEBOARD_FAB2_LIB.BASEBOARD_FAB2(SCH_1):PAGE147_I106@W_HDL.AST2520A1-GP-GP(CHIPS)':
 'ADC13_GPIX5': CDS_PINID='ADC13_GPIX5';
NET_NAME
'H_CPU0_MEMDEF_MEMHOT_LVT3_K_N'
 '@BASEBOARD_FAB2_LIB.BASEBOARD_FAB2(SCH_1):H_CPU0_MEMDEF_MEMHOT_LVT3_K_N':
 C_SIGNAL='@baseboard_fab2_lib.baseboard_fab2(sch_1):h_cpu0_memdef_memhot_lvt3_k~
_n';
NODE_NAME     R9G31 1
 '@BASEBOARD_FAB2_LIB.BASEBOARD_FAB2(SCH_1):PAGE152_I14@MSTR_DISCRETE.RES(CHIPS)':
 'A': CDS_PINID='A';
NODE_NAME     R9G27 2
 '@BASEBOARD_FAB2_LIB.BASEBOARD_FAB2(SCH_1):PAGE152_I47@MSTR_DISCRETE.RES(CHIPS)':
 'B': CDS_PINID='B';
NODE_NAME     R9G33 2
 '@BASEBOARD_FAB2_LIB.BASEBOARD_FAB2(SCH_1):PAGE152_I73@MSTR_DISCRETE.RES(CHIPS)':
 'B': CDS_PINID='B';
NET_NAME
'H_CPU0_MEMDEF_MEMHOT_LVT3_N'
 '@BASEBOARD_FAB2_LIB.BASEBOARD_FAB2(SCH_1):H_CPU0_MEMDEF_MEMHOT_LVT3_N':
 C_SIGNAL='@baseboard_fab2_lib.baseboard_fab2(sch_1):h_cpu0_memdef_memhot_lvt3_n~
';
NODE_NAME     R9G31 2
 '@BASEBOARD_FAB2_LIB.BASEBOARD_FAB2(SCH_1):PAGE152_I14@MSTR_DISCRETE.RES(CHIPS)':
 'B': CDS_PINID='B';
NODE_NAME     R9G29 1
 '@BASEBOARD_FAB2_LIB.BASEBOARD_FAB2(SCH_1):PAGE152_I92@MSTR_DISCRETE.RES(CHIPS)':
 'A': CDS_PINID='A';
NODE_NAME     R9G30 1
 '@BASEBOARD_FAB2_LIB.BASEBOARD_FAB2(SCH_1):PAGE152_I98@MSTR_DISCRETE.RES(CHIPS)':
 'A': CDS_PINID='A';
NET_NAME
'H_CPU0_MEMDEF_MEMHOT_PCH_N'
 '@BASEBOARD_FAB2_LIB.BASEBOARD_FAB2(SCH_1):H_CPU0_MEMDEF_MEMHOT_PCH_N':
 C_SIGNAL='@baseboard_fab2_lib.baseboard_fab2(sch_1):h_cpu0_memdef_memhot_pch_n';
NODE_NAME     U7C1 AD13
 '@BASEBOARD_FAB2_LIB.BASEBOARD_FAB2(SCH_1):PAGE121_I34@MSTR_U_PROC.LBG_CORE_QAT_EXT_D(CHIPS)':
 'GPP_L13_TESTCH1_D2': CDS_PINID='GPP_L13_TESTCH1_D2';
NODE_NAME     R9G30 2
 '@BASEBOARD_FAB2_LIB.BASEBOARD_FAB2(SCH_1):PAGE152_I98@MSTR_DISCRETE.RES(CHIPS)':
 'B': CDS_PINID='B';
NET_NAME
'H_CPU0_MSMI_G_N'
 '@BASEBOARD_FAB2_LIB.BASEBOARD_FAB2(SCH_1):H_CPU0_MSMI_G_N':
 C_SIGNAL='@baseboard_fab2_lib.baseboard_fab2(sch_1):h_cpu0_msmi_g_n';
NODE_NAME     U5D1 AN20
 '@BASEBOARD_FAB2_LIB.BASEBOARD_FAB2(SCH_1):PAGE21_I259@CHPSET_LIB.SKX_EXT_B(CHIPS)':
 'MSMI_N': CDS_PINID='MSMI_N';
NODE_NAME     R6D9 2
 '@BASEBOARD_FAB2_LIB.BASEBOARD_FAB2(SCH_1):PAGE92_I64@MSTR_DISCRETE.RES(CHIPS)':
 'B': CDS_PINID='B';
NODE_NAME     R7D27 1
 '@BASEBOARD_FAB2_LIB.BASEBOARD_FAB2(SCH_1):PAGE92_I68@MSTR_DISCRETE.RES(CHIPS)':
 'A': CDS_PINID='A';
NET_NAME
'H_CPU0_PROCHOT_G_N'
 '@BASEBOARD_FAB2_LIB.BASEBOARD_FAB2(SCH_1):H_CPU0_PROCHOT_G_N':
 C_SIGNAL='@baseboard_fab2_lib.baseboard_fab2(sch_1):h_cpu0_prochot_g_n';
NODE_NAME     U5D1 AC16
 '@BASEBOARD_FAB2_LIB.BASEBOARD_FAB2(SCH_1):PAGE21_I259@CHPSET_LIB.SKX_EXT_B(CHIPS)':
 'PROCHOT_N': CDS_PINID='PROCHOT_N';
NODE_NAME     R4R3 2
 '@BASEBOARD_FAB2_LIB.BASEBOARD_FAB2(SCH_1):PAGE93_I79@MSTR_DISCRETE.RES(CHIPS)':
 'B': CDS_PINID='B';
NODE_NAME     R2T60 1
 '@BASEBOARD_FAB2_LIB.BASEBOARD_FAB2(SCH_1):PAGE93_I103@MSTR_DISCRETE.RES(CHIPS)':
 'A': CDS_PINID='A';
NODE_NAME     R2T59 1
 '@BASEBOARD_FAB2_LIB.BASEBOARD_FAB2(SCH_1):PAGE93_I107@MSTR_DISCRETE.RES(CHIPS)':
 'A': CDS_PINID='A';
NODE_NAME     R2T72 2
 '@BASEBOARD_FAB2_LIB.BASEBOARD_FAB2(SCH_1):PAGE93_I143@MSTR_DISCRETE.RES(CHIPS)':
 'B': CDS_PINID='B';
NODE_NAME     Q7E3 6
 '@BASEBOARD_FAB2_LIB.BASEBOARD_FAB2(SCH_1):PAGE95_I52@MSTR_DISCRETE.FET_N_DUAL(CHIPS)':
 'DRAIN'<0>: CDS_PINID='DRAIN(0)';
NODE_NAME     Q7E5 3
 '@BASEBOARD_FAB2_LIB.BASEBOARD_FAB2(SCH_1):PAGE95_I59@MSTR_DISCRETE.FET_N_DUAL(CHIPS)':
 'DRAIN'<0>: CDS_PINID='DRAIN(0)';
NET_NAME
'H_CPU0_PROCHOT_G_PCH_N'
 '@BASEBOARD_FAB2_LIB.BASEBOARD_FAB2(SCH_1):H_CPU0_PROCHOT_G_PCH_N':
 C_SIGNAL='@baseboard_fab2_lib.baseboard_fab2(sch_1):h_cpu0_prochot_g_pch_n';
NODE_NAME     R2T59 2
 '@BASEBOARD_FAB2_LIB.BASEBOARD_FAB2(SCH_1):PAGE93_I107@MSTR_DISCRETE.RES(CHIPS)':
 'B': CDS_PINID='B';
NODE_NAME     R2T71 2
 '@BASEBOARD_FAB2_LIB.BASEBOARD_FAB2(SCH_1):PAGE93_I109@MSTR_DISCRETE.RES(CHIPS)':
 'B': CDS_PINID='B';
NET_NAME
'H_CPU0_PROCHOT_G_R_N'
 '@BASEBOARD_FAB2_LIB.BASEBOARD_FAB2(SCH_1):H_CPU0_PROCHOT_G_R_N':
 C_SIGNAL='@baseboard_fab2_lib.baseboard_fab2(sch_1):h_cpu0_prochot_g_r_n';
NODE_NAME     U2T4 3
 '@BASEBOARD_FAB2_LIB.BASEBOARD_FAB2(SCH_1):PAGE93_I30@MSTR_DIGITAL.GTL2014(CHIPS)':
 'B1': CDS_PINID='B1';
NODE_NAME     R2T60 2
 '@BASEBOARD_FAB2_LIB.BASEBOARD_FAB2(SCH_1):PAGE93_I103@MSTR_DISCRETE.RES(CHIPS)':
 'B': CDS_PINID='B';
NET_NAME
'H_CPU0_THERMTRIP_G_N'
 '@BASEBOARD_FAB2_LIB.BASEBOARD_FAB2(SCH_1):H_CPU0_THERMTRIP_G_N':
 C_SIGNAL='@baseboard_fab2_lib.baseboard_fab2(sch_1):h_cpu0_thermtrip_g_n';
NODE_NAME     U5D1 AB15
 '@BASEBOARD_FAB2_LIB.BASEBOARD_FAB2(SCH_1):PAGE21_I259@CHPSET_LIB.SKX_EXT_B(CHIPS)':
 'THERMTRIP_N': CDS_PINID='THERMTRIP_N';
NODE_NAME     R7E2 2
 '@BASEBOARD_FAB2_LIB.BASEBOARD_FAB2(SCH_1):PAGE92_I19@MSTR_DISCRETE.RES(CHIPS)':
 'B': CDS_PINID='B';
NODE_NAME     U7D2 6
 '@BASEBOARD_FAB2_LIB.BASEBOARD_FAB2(SCH_1):PAGE92_I32@MSTR_DIGITAL.GTL2014(CHIPS)':
 'B3': CDS_PINID='B3';
NET_NAME
'H_CPU1_BMCINIT'
 '@BASEBOARD_FAB2_LIB.BASEBOARD_FAB2(SCH_1):H_CPU1_BMCINIT':
 C_SIGNAL='@baseboard_fab2_lib.baseboard_fab2(sch_1):h_cpu1_bmcinit';
NODE_NAME     U2D1 BD23
 '@BASEBOARD_FAB2_LIB.BASEBOARD_FAB2(SCH_1):PAGE55_I172@CHPSET_LIB.SKX_EXT_B(CHIPS)':
 'BMCINIT': CDS_PINID='BMCINIT';
NODE_NAME     R3D16 2
 '@BASEBOARD_FAB2_LIB.BASEBOARD_FAB2(SCH_1):PAGE90_I24@MSTR_DISCRETE.RES(CHIPS)':
 'B': CDS_PINID='B';
NODE_NAME     R3D31 2
 '@BASEBOARD_FAB2_LIB.BASEBOARD_FAB2(SCH_1):PAGE156_I300@MSTR_DISCRETE.RES(CHIPS)':
 'B': CDS_PINID='B';
NET_NAME
'H_CPU1_CATERR_G_N'
 '@BASEBOARD_FAB2_LIB.BASEBOARD_FAB2(SCH_1):H_CPU1_CATERR_G_N':
 C_SIGNAL='@baseboard_fab2_lib.baseboard_fab2(sch_1):h_cpu1_caterr_g_n';
NODE_NAME     U2D1 AL14
 '@BASEBOARD_FAB2_LIB.BASEBOARD_FAB2(SCH_1):PAGE55_I172@CHPSET_LIB.SKX_EXT_B(CHIPS)':
 'CATERR_N': CDS_PINID='CATERR_N';
NODE_NAME     R3P58 1
 '@BASEBOARD_FAB2_LIB.BASEBOARD_FAB2(SCH_1):PAGE92_I98@MSTR_DISCRETE.RES(CHIPS)':
 'A': CDS_PINID='A';
NODE_NAME     R7P18 2
 '@BASEBOARD_FAB2_LIB.BASEBOARD_FAB2(SCH_1):PAGE92_I100@MSTR_DISCRETE.RES(CHIPS)':
 'B': CDS_PINID='B';
NET_NAME
'H_CPU1_ERR0_G_N'
 '@BASEBOARD_FAB2_LIB.BASEBOARD_FAB2(SCH_1):H_CPU1_ERR0_G_N':
 C_SIGNAL='@baseboard_fab2_lib.baseboard_fab2(sch_1):h_cpu1_err0_g_n';
NODE_NAME     U2D1 AJ12
 '@BASEBOARD_FAB2_LIB.BASEBOARD_FAB2(SCH_1):PAGE55_I172@CHPSET_LIB.SKX_EXT_B(CHIPS)':
 'ERROR_N'<0>: CDS_PINID='ERROR_N(0)';
NODE_NAME     R2T20 1
 '@BASEBOARD_FAB2_LIB.BASEBOARD_FAB2(SCH_1):PAGE93_I16@MSTR_DISCRETE.RES(CHIPS)':
 'A': CDS_PINID='A';
NET_NAME
'H_CPU1_ERR1_G_N'
 '@BASEBOARD_FAB2_LIB.BASEBOARD_FAB2(SCH_1):H_CPU1_ERR1_G_N':
 C_SIGNAL='@baseboard_fab2_lib.baseboard_fab2(sch_1):h_cpu1_err1_g_n';
NODE_NAME     U2D1 AK11
 '@BASEBOARD_FAB2_LIB.BASEBOARD_FAB2(SCH_1):PAGE55_I172@CHPSET_LIB.SKX_EXT_B(CHIPS)':
 'ERROR_N'<1>: CDS_PINID='ERROR_N(1)';
NODE_NAME     R2T27 1
 '@BASEBOARD_FAB2_LIB.BASEBOARD_FAB2(SCH_1):PAGE93_I13@MSTR_DISCRETE.RES(CHIPS)':
 'A': CDS_PINID='A';
NET_NAME
'H_CPU1_ERR2_G_N'
 '@BASEBOARD_FAB2_LIB.BASEBOARD_FAB2(SCH_1):H_CPU1_ERR2_G_N':
 C_SIGNAL='@baseboard_fab2_lib.baseboard_fab2(sch_1):h_cpu1_err2_g_n';
NODE_NAME     U2D1 AL12
 '@BASEBOARD_FAB2_LIB.BASEBOARD_FAB2(SCH_1):PAGE55_I172@CHPSET_LIB.SKX_EXT_B(CHIPS)':
 'ERROR_N'<2>: CDS_PINID='ERROR_N(2)';
NODE_NAME     R2T44 1
 '@BASEBOARD_FAB2_LIB.BASEBOARD_FAB2(SCH_1):PAGE92_I92@MSTR_DISCRETE.RES(CHIPS)':
 'A': CDS_PINID='A';
NET_NAME
'H_CPU1_FAST_WAKE_N'
 '@BASEBOARD_FAB2_LIB.BASEBOARD_FAB2(SCH_1):H_CPU1_FAST_WAKE_N':
 C_SIGNAL='@baseboard_fab2_lib.baseboard_fab2(sch_1):h_cpu1_fast_wake_n';
NODE_NAME     U2D1 AF15
 '@BASEBOARD_FAB2_LIB.BASEBOARD_FAB2(SCH_1):PAGE55_I172@CHPSET_LIB.SKX_EXT_B(CHIPS)':
 'PM_FAST_WAKE_N': CDS_PINID='PM_FAST_WAKE_N';
NODE_NAME     R3D18 2
 '@BASEBOARD_FAB2_LIB.BASEBOARD_FAB2(SCH_1):PAGE97_I33@MSTR_DISCRETE.RES(CHIPS)':
 'B': CDS_PINID='B';
NODE_NAME     R7P20 2
 '@BASEBOARD_FAB2_LIB.BASEBOARD_FAB2(SCH_1):PAGE97_I44@MSTR_DISCRETE.RES(CHIPS)':
 'B': CDS_PINID='B';
NET_NAME
'H_CPU1_FIVR_FAULT_G'
 '@BASEBOARD_FAB2_LIB.BASEBOARD_FAB2(SCH_1):H_CPU1_FIVR_FAULT_G':
 C_SIGNAL='@baseboard_fab2_lib.baseboard_fab2(sch_1):h_cpu1_fivr_fault_g';
NODE_NAME     U2D1 AU14
 '@BASEBOARD_FAB2_LIB.BASEBOARD_FAB2(SCH_1):PAGE56_I169@CHPSET_LIB.SKX_EXT_B(CHIPS)':
 'FIVR_FAULT': CDS_PINID='FIVR_FAULT';
NODE_NAME     U3P2 3
 '@BASEBOARD_FAB2_LIB.BASEBOARD_FAB2(SCH_1):PAGE92_I1@MSTR_DIGITAL.GTL2014(CHIPS)':
 'B1': CDS_PINID='B1';
NODE_NAME     R3R2 1
 '@BASEBOARD_FAB2_LIB.BASEBOARD_FAB2(SCH_1):PAGE92_I75@MSTR_DISCRETE.RES(CHIPS)':
 'A': CDS_PINID='A';
NET_NAME
'H_CPU1_GHJ_MEMHOT_LVT3_R_N'
 '@BASEBOARD_FAB2_LIB.BASEBOARD_FAB2(SCH_1):H_CPU1_GHJ_MEMHOT_LVT3_R_N':
 C_SIGNAL='@baseboard_fab2_lib.baseboard_fab2(sch_1):h_cpu1_ghj_memhot_lvt3_r_n';
NODE_NAME     U9G1 12
 '@BASEBOARD_FAB2_LIB.BASEBOARD_FAB2(SCH_1):PAGE152_I1@MSTR_DIGITAL.GTL2014(CHIPS)':
 'A1': CDS_PINID='A1';
NODE_NAME     R9G32 1
 '@BASEBOARD_FAB2_LIB.BASEBOARD_FAB2(SCH_1):PAGE152_I72@MSTR_DISCRETE.RES(CHIPS)':
 'A': CDS_PINID='A';
NET_NAME
'H_CPU1_KLM_MEMHOT_LVT3_R_N'
 '@BASEBOARD_FAB2_LIB.BASEBOARD_FAB2(SCH_1):H_CPU1_KLM_MEMHOT_LVT3_R_N':
 C_SIGNAL='@baseboard_fab2_lib.baseboard_fab2(sch_1):h_cpu1_klm_memhot_lvt3_r_n';
NODE_NAME     U9G1 13
 '@BASEBOARD_FAB2_LIB.BASEBOARD_FAB2(SCH_1):PAGE152_I1@MSTR_DIGITAL.GTL2014(CHIPS)':
 'A0': CDS_PINID='A0';
NODE_NAME     R9G28 1
 '@BASEBOARD_FAB2_LIB.BASEBOARD_FAB2(SCH_1):PAGE152_I71@MSTR_DISCRETE.RES(CHIPS)':
 'A': CDS_PINID='A';
NET_NAME
'H_CPU1_MEMGHJ_MEMHOT'
 '@BASEBOARD_FAB2_LIB.BASEBOARD_FAB2(SCH_1):H_CPU1_MEMGHJ_MEMHOT':
 C_SIGNAL='@baseboard_fab2_lib.baseboard_fab2(sch_1):h_cpu1_memghj_memhot';
NODE_NAME     Q7E2 6
 '@BASEBOARD_FAB2_LIB.BASEBOARD_FAB2(SCH_1):PAGE94_I69@MSTR_DISCRETE.FET_N_DUAL(CHIPS)':
 'DRAIN'<0>: CDS_PINID='DRAIN(0)';
NODE_NAME     Q7E2 5
 '@BASEBOARD_FAB2_LIB.BASEBOARD_FAB2(SCH_1):PAGE94_I75@MSTR_DISCRETE.FET_N_DUAL(CHIPS)':
 'GATE'<0>: CDS_PINID='GATE(0)';
NODE_NAME     R3R10 2
 '@BASEBOARD_FAB2_LIB.BASEBOARD_FAB2(SCH_1):PAGE94_I79@MSTR_DISCRETE.RES(CHIPS)':
 'B': CDS_PINID='B';
NET_NAME
'H_CPU1_MEMGHJ_MEMHOT_G_N'
 '@BASEBOARD_FAB2_LIB.BASEBOARD_FAB2(SCH_1):H_CPU1_MEMGHJ_MEMHOT_G_N':
 C_SIGNAL='@baseboard_fab2_lib.baseboard_fab2(sch_1):h_cpu1_memghj_memhot_g_n';
NODE_NAME     U2D1 AH13
 '@BASEBOARD_FAB2_LIB.BASEBOARD_FAB2(SCH_1):PAGE55_I172@CHPSET_LIB.SKX_EXT_B(CHIPS)':
 'MEM_HOT_C012_N': CDS_PINID='MEM_HOT_C012_N';
NODE_NAME     Q7E2 3
 '@BASEBOARD_FAB2_LIB.BASEBOARD_FAB2(SCH_1):PAGE94_I75@MSTR_DISCRETE.FET_N_DUAL(CHIPS)':
 'DRAIN'<0>: CDS_PINID='DRAIN(0)';
NODE_NAME     Q4B2 6
 '@BASEBOARD_FAB2_LIB.BASEBOARD_FAB2(SCH_1):PAGE95_I32@MSTR_DISCRETE.FET_N_DUAL(CHIPS)':
 'DRAIN'<0>: CDS_PINID='DRAIN(0)';
NODE_NAME     R1U41 2
 '@BASEBOARD_FAB2_LIB.BASEBOARD_FAB2(SCH_1):PAGE152_I56@MSTR_DISCRETE.RES(CHIPS)':
 'B': CDS_PINID='B';
NODE_NAME     R7P5 1
 '@BASEBOARD_FAB2_LIB.BASEBOARD_FAB2(SCH_1):PAGE152_I61@MSTR_DISCRETE.RES(CHIPS)':
 'A': CDS_PINID='A';
NODE_NAME     R1U53 1
 '@BASEBOARD_FAB2_LIB.BASEBOARD_FAB2(SCH_1):PAGE152_I64@MSTR_DISCRETE.RES(CHIPS)':
 'A': CDS_PINID='A';
NODE_NAME     R1U55 1
 '@BASEBOARD_FAB2_LIB.BASEBOARD_FAB2(SCH_1):PAGE152_I67@MSTR_DISCRETE.RES(CHIPS)':
 'A': CDS_PINID='A';
NET_NAME
'H_CPU1_MEMGHJ_MEMHOT_G_PCH_N'
 '@BASEBOARD_FAB2_LIB.BASEBOARD_FAB2(SCH_1):H_CPU1_MEMGHJ_MEMHOT_G_PCH_N':
 C_SIGNAL='@baseboard_fab2_lib.baseboard_fab2(sch_1):h_cpu1_memghj_memhot_g_pch_~
n';
NODE_NAME     R1U55 2
 '@BASEBOARD_FAB2_LIB.BASEBOARD_FAB2(SCH_1):PAGE152_I67@MSTR_DISCRETE.RES(CHIPS)':
 'B': CDS_PINID='B';
NODE_NAME     R1U57 2
 '@BASEBOARD_FAB2_LIB.BASEBOARD_FAB2(SCH_1):PAGE152_I69@MSTR_DISCRETE.RES(CHIPS)':
 'B': CDS_PINID='B';
NET_NAME
'H_CPU1_MEMGHJ_MEMHOT_G_R_N'
 '@BASEBOARD_FAB2_LIB.BASEBOARD_FAB2(SCH_1):H_CPU1_MEMGHJ_MEMHOT_G_R_N':
 C_SIGNAL='@baseboard_fab2_lib.baseboard_fab2(sch_1):h_cpu1_memghj_memhot_g_r_n';
NODE_NAME     U9G1 3
 '@BASEBOARD_FAB2_LIB.BASEBOARD_FAB2(SCH_1):PAGE152_I1@MSTR_DIGITAL.GTL2014(CHIPS)':
 'B1': CDS_PINID='B1';
NODE_NAME     R1U53 2
 '@BASEBOARD_FAB2_LIB.BASEBOARD_FAB2(SCH_1):PAGE152_I64@MSTR_DISCRETE.RES(CHIPS)':
 'B': CDS_PINID='B';
NET_NAME
'H_CPU1_MEMGHJ_MEMHOT_LVT3_BMC_N'
 '@BASEBOARD_FAB2_LIB.BASEBOARD_FAB2(SCH_1):H_CPU1_MEMGHJ_MEMHOT_LVT3_BMC_N':
 C_SIGNAL='@baseboard_fab2_lib.baseboard_fab2(sch_1):h_cpu1_memghj_memhot_lvt3_b~
mc_n';
NODE_NAME     R1U54 2
 '@BASEBOARD_FAB2_LIB.BASEBOARD_FAB2(SCH_1):PAGE152_I93@MSTR_DISCRETE.RES(CHIPS)':
 'B': CDS_PINID='B';
NODE_NAME     U25W4 H3
 '@BASEBOARD_FAB2_LIB.BASEBOARD_FAB2(SCH_1):PAGE147_I106@W_HDL.AST2520A1-GP-GP(CHIPS)':
 'ADC14_GPIX6': CDS_PINID='ADC14_GPIX6';
NET_NAME
'H_CPU1_MEMGHJ_MEMHOT_LVT3_K_N'
 '@BASEBOARD_FAB2_LIB.BASEBOARD_FAB2(SCH_1):H_CPU1_MEMGHJ_MEMHOT_LVT3_K_N':
 C_SIGNAL='@baseboard_fab2_lib.baseboard_fab2(sch_1):h_cpu1_memghj_memhot_lvt3_k~
_n';
NODE_NAME     R1U36 1
 '@BASEBOARD_FAB2_LIB.BASEBOARD_FAB2(SCH_1):PAGE152_I15@MSTR_DISCRETE.RES(CHIPS)':
 'A': CDS_PINID='A';
NODE_NAME     R1U57 1
 '@BASEBOARD_FAB2_LIB.BASEBOARD_FAB2(SCH_1):PAGE152_I69@MSTR_DISCRETE.RES(CHIPS)':
 'A': CDS_PINID='A';
NODE_NAME     R9G32 2
 '@BASEBOARD_FAB2_LIB.BASEBOARD_FAB2(SCH_1):PAGE152_I72@MSTR_DISCRETE.RES(CHIPS)':
 'B': CDS_PINID='B';
NET_NAME
'H_CPU1_MEMGHJ_MEMHOT_LVT3_N'
 '@BASEBOARD_FAB2_LIB.BASEBOARD_FAB2(SCH_1):H_CPU1_MEMGHJ_MEMHOT_LVT3_N':
 C_SIGNAL='@baseboard_fab2_lib.baseboard_fab2(sch_1):h_cpu1_memghj_memhot_lvt3_n~
';
NODE_NAME     R1U36 2
 '@BASEBOARD_FAB2_LIB.BASEBOARD_FAB2(SCH_1):PAGE152_I15@MSTR_DISCRETE.RES(CHIPS)':
 'B': CDS_PINID='B';
NODE_NAME     R1U54 1
 '@BASEBOARD_FAB2_LIB.BASEBOARD_FAB2(SCH_1):PAGE152_I93@MSTR_DISCRETE.RES(CHIPS)':
 'A': CDS_PINID='A';
NODE_NAME     R3P63 1
 '@BASEBOARD_FAB2_LIB.BASEBOARD_FAB2(SCH_1):PAGE152_I100@MSTR_DISCRETE.RES(CHIPS)':
 'A': CDS_PINID='A';
NET_NAME
'H_CPU1_MEMGHJ_MEMHOT_PCH_N'
 '@BASEBOARD_FAB2_LIB.BASEBOARD_FAB2(SCH_1):H_CPU1_MEMGHJ_MEMHOT_PCH_N':
 C_SIGNAL='@baseboard_fab2_lib.baseboard_fab2(sch_1):h_cpu1_memghj_memhot_pch_n';
NODE_NAME     U7C1 AA13
 '@BASEBOARD_FAB2_LIB.BASEBOARD_FAB2(SCH_1):PAGE121_I34@MSTR_U_PROC.LBG_CORE_QAT_EXT_D(CHIPS)':
 'GPP_L14_TESTCH1_D3': CDS_PINID='GPP_L14_TESTCH1_D3';
NODE_NAME     R3P63 2
 '@BASEBOARD_FAB2_LIB.BASEBOARD_FAB2(SCH_1):PAGE152_I100@MSTR_DISCRETE.RES(CHIPS)':
 'B': CDS_PINID='B';
NET_NAME
'H_CPU1_MEMKLM_MEMHOT'
 '@BASEBOARD_FAB2_LIB.BASEBOARD_FAB2(SCH_1):H_CPU1_MEMKLM_MEMHOT':
 C_SIGNAL='@baseboard_fab2_lib.baseboard_fab2(sch_1):h_cpu1_memklm_memhot';
NODE_NAME     Q4B1 5
 '@BASEBOARD_FAB2_LIB.BASEBOARD_FAB2(SCH_1):PAGE94_I77@MSTR_DISCRETE.FET_N_DUAL(CHIPS)':
 'GATE'<0>: CDS_PINID='GATE(0)';
NODE_NAME     R6M4 2
 '@BASEBOARD_FAB2_LIB.BASEBOARD_FAB2(SCH_1):PAGE94_I82@MSTR_DISCRETE.RES(CHIPS)':
 'B': CDS_PINID='B';
NODE_NAME     Q4B1 6
 '@BASEBOARD_FAB2_LIB.BASEBOARD_FAB2(SCH_1):PAGE94_I84@MSTR_DISCRETE.FET_N_DUAL(CHIPS)':
 'DRAIN'<0>: CDS_PINID='DRAIN(0)';
NET_NAME
'H_CPU1_MEMKLM_MEMHOT_G_N'
 '@BASEBOARD_FAB2_LIB.BASEBOARD_FAB2(SCH_1):H_CPU1_MEMKLM_MEMHOT_G_N':
 C_SIGNAL='@baseboard_fab2_lib.baseboard_fab2(sch_1):h_cpu1_memklm_memhot_g_n';
NODE_NAME     U2D1 AF13
 '@BASEBOARD_FAB2_LIB.BASEBOARD_FAB2(SCH_1):PAGE55_I172@CHPSET_LIB.SKX_EXT_B(CHIPS)':
 'MEM_HOT_C345_N': CDS_PINID='MEM_HOT_C345_N';
NODE_NAME     Q4B1 3
 '@BASEBOARD_FAB2_LIB.BASEBOARD_FAB2(SCH_1):PAGE94_I77@MSTR_DISCRETE.FET_N_DUAL(CHIPS)':
 'DRAIN'<0>: CDS_PINID='DRAIN(0)';
NODE_NAME     Q4B2 3
 '@BASEBOARD_FAB2_LIB.BASEBOARD_FAB2(SCH_1):PAGE95_I33@MSTR_DISCRETE.FET_N_DUAL(CHIPS)':
 'DRAIN'<0>: CDS_PINID='DRAIN(0)';
NODE_NAME     R1U35 2
 '@BASEBOARD_FAB2_LIB.BASEBOARD_FAB2(SCH_1):PAGE152_I57@MSTR_DISCRETE.RES(CHIPS)':
 'B': CDS_PINID='B';
NODE_NAME     R7P21 1
 '@BASEBOARD_FAB2_LIB.BASEBOARD_FAB2(SCH_1):PAGE152_I62@MSTR_DISCRETE.RES(CHIPS)':
 'A': CDS_PINID='A';
NODE_NAME     R1U60 1
 '@BASEBOARD_FAB2_LIB.BASEBOARD_FAB2(SCH_1):PAGE152_I65@MSTR_DISCRETE.RES(CHIPS)':
 'A': CDS_PINID='A';
NODE_NAME     R1U62 1
 '@BASEBOARD_FAB2_LIB.BASEBOARD_FAB2(SCH_1):PAGE152_I68@MSTR_DISCRETE.RES(CHIPS)':
 'A': CDS_PINID='A';
NET_NAME
'H_CPU1_MEMKLM_MEMHOT_G_PCH_N'
 '@BASEBOARD_FAB2_LIB.BASEBOARD_FAB2(SCH_1):H_CPU1_MEMKLM_MEMHOT_G_PCH_N':
 C_SIGNAL='@baseboard_fab2_lib.baseboard_fab2(sch_1):h_cpu1_memklm_memhot_g_pch_~
n';
NODE_NAME     R1U62 2
 '@BASEBOARD_FAB2_LIB.BASEBOARD_FAB2(SCH_1):PAGE152_I68@MSTR_DISCRETE.RES(CHIPS)':
 'B': CDS_PINID='B';
NODE_NAME     R1U61 2
 '@BASEBOARD_FAB2_LIB.BASEBOARD_FAB2(SCH_1):PAGE152_I70@MSTR_DISCRETE.RES(CHIPS)':
 'B': CDS_PINID='B';
NET_NAME
'H_CPU1_MEMKLM_MEMHOT_G_R_N'
 '@BASEBOARD_FAB2_LIB.BASEBOARD_FAB2(SCH_1):H_CPU1_MEMKLM_MEMHOT_G_R_N':
 C_SIGNAL='@baseboard_fab2_lib.baseboard_fab2(sch_1):h_cpu1_memklm_memhot_g_r_n';
NODE_NAME     U9G1 2
 '@BASEBOARD_FAB2_LIB.BASEBOARD_FAB2(SCH_1):PAGE152_I1@MSTR_DIGITAL.GTL2014(CHIPS)':
 'B0': CDS_PINID='B0';
NODE_NAME     R1U60 2
 '@BASEBOARD_FAB2_LIB.BASEBOARD_FAB2(SCH_1):PAGE152_I65@MSTR_DISCRETE.RES(CHIPS)':
 'B': CDS_PINID='B';
NET_NAME
'H_CPU1_MEMKLM_MEMHOT_LVT3_BMC_N'
 '@BASEBOARD_FAB2_LIB.BASEBOARD_FAB2(SCH_1):H_CPU1_MEMKLM_MEMHOT_LVT3_BMC_N':
 C_SIGNAL='@baseboard_fab2_lib.baseboard_fab2(sch_1):h_cpu1_memklm_memhot_lvt3_b~
mc_n';
NODE_NAME     R2U46 2
 '@BASEBOARD_FAB2_LIB.BASEBOARD_FAB2(SCH_1):PAGE152_I94@MSTR_DISCRETE.RES(CHIPS)':
 'B': CDS_PINID='B';
NODE_NAME     U25W4 H4
 '@BASEBOARD_FAB2_LIB.BASEBOARD_FAB2(SCH_1):PAGE147_I106@W_HDL.AST2520A1-GP-GP(CHIPS)':
 'ADC15_GPIX7': CDS_PINID='ADC15_GPIX7';
NET_NAME
'H_CPU1_MEMKLM_MEMHOT_LVT3_K_N'
 '@BASEBOARD_FAB2_LIB.BASEBOARD_FAB2(SCH_1):H_CPU1_MEMKLM_MEMHOT_LVT3_K_N':
 C_SIGNAL='@baseboard_fab2_lib.baseboard_fab2(sch_1):h_cpu1_memklm_memhot_lvt3_k~
_n';
NODE_NAME     R1U34 1
 '@BASEBOARD_FAB2_LIB.BASEBOARD_FAB2(SCH_1):PAGE152_I16@MSTR_DISCRETE.RES(CHIPS)':
 'A': CDS_PINID='A';
NODE_NAME     R1U61 1
 '@BASEBOARD_FAB2_LIB.BASEBOARD_FAB2(SCH_1):PAGE152_I70@MSTR_DISCRETE.RES(CHIPS)':
 'A': CDS_PINID='A';
NODE_NAME     R9G28 2
 '@BASEBOARD_FAB2_LIB.BASEBOARD_FAB2(SCH_1):PAGE152_I71@MSTR_DISCRETE.RES(CHIPS)':
 'B': CDS_PINID='B';
NET_NAME
'H_CPU1_MEMKLM_MEMHOT_LVT3_N'
 '@BASEBOARD_FAB2_LIB.BASEBOARD_FAB2(SCH_1):H_CPU1_MEMKLM_MEMHOT_LVT3_N':
 C_SIGNAL='@baseboard_fab2_lib.baseboard_fab2(sch_1):h_cpu1_memklm_memhot_lvt3_n~
';
NODE_NAME     R1U34 2
 '@BASEBOARD_FAB2_LIB.BASEBOARD_FAB2(SCH_1):PAGE152_I16@MSTR_DISCRETE.RES(CHIPS)':
 'B': CDS_PINID='B';
NODE_NAME     R2U46 1
 '@BASEBOARD_FAB2_LIB.BASEBOARD_FAB2(SCH_1):PAGE152_I94@MSTR_DISCRETE.RES(CHIPS)':
 'A': CDS_PINID='A';
NODE_NAME     R2U45 1
 '@BASEBOARD_FAB2_LIB.BASEBOARD_FAB2(SCH_1):PAGE152_I102@MSTR_DISCRETE.RES(CHIPS)':
 'A': CDS_PINID='A';
NET_NAME
'H_CPU1_MEMKLM_MEMHOT_PCH_N'
 '@BASEBOARD_FAB2_LIB.BASEBOARD_FAB2(SCH_1):H_CPU1_MEMKLM_MEMHOT_PCH_N':
 C_SIGNAL='@baseboard_fab2_lib.baseboard_fab2(sch_1):h_cpu1_memklm_memhot_pch_n';
NODE_NAME     U7C1 Y11
 '@BASEBOARD_FAB2_LIB.BASEBOARD_FAB2(SCH_1):PAGE121_I34@MSTR_U_PROC.LBG_CORE_QAT_EXT_D(CHIPS)':
 'GPP_L15_TESTCH1_D4': CDS_PINID='GPP_L15_TESTCH1_D4';
NODE_NAME     R2U45 2
 '@BASEBOARD_FAB2_LIB.BASEBOARD_FAB2(SCH_1):PAGE152_I102@MSTR_DISCRETE.RES(CHIPS)':
 'B': CDS_PINID='B';
NET_NAME
'H_CPU1_MSMI_G_N'
 '@BASEBOARD_FAB2_LIB.BASEBOARD_FAB2(SCH_1):H_CPU1_MSMI_G_N':
 C_SIGNAL='@baseboard_fab2_lib.baseboard_fab2(sch_1):h_cpu1_msmi_g_n';
NODE_NAME     U2D1 AN20
 '@BASEBOARD_FAB2_LIB.BASEBOARD_FAB2(SCH_1):PAGE55_I172@CHPSET_LIB.SKX_EXT_B(CHIPS)':
 'MSMI_N': CDS_PINID='MSMI_N';
NODE_NAME     R7P27 2
 '@BASEBOARD_FAB2_LIB.BASEBOARD_FAB2(SCH_1):PAGE92_I65@MSTR_DISCRETE.RES(CHIPS)':
 'B': CDS_PINID='B';
NODE_NAME     R7D28 1
 '@BASEBOARD_FAB2_LIB.BASEBOARD_FAB2(SCH_1):PAGE92_I67@MSTR_DISCRETE.RES(CHIPS)':
 'A': CDS_PINID='A';
NET_NAME
'H_CPU1_PROCHOT_G_N'
 '@BASEBOARD_FAB2_LIB.BASEBOARD_FAB2(SCH_1):H_CPU1_PROCHOT_G_N':
 C_SIGNAL='@baseboard_fab2_lib.baseboard_fab2(sch_1):h_cpu1_prochot_g_n';
NODE_NAME     U2D1 AC16
 '@BASEBOARD_FAB2_LIB.BASEBOARD_FAB2(SCH_1):PAGE55_I172@CHPSET_LIB.SKX_EXT_B(CHIPS)':
 'PROCHOT_N': CDS_PINID='PROCHOT_N';
NODE_NAME     R2T68 1
 '@BASEBOARD_FAB2_LIB.BASEBOARD_FAB2(SCH_1):PAGE93_I102@MSTR_DISCRETE.RES(CHIPS)':
 'A': CDS_PINID='A';
NODE_NAME     R7P28 2
 '@BASEBOARD_FAB2_LIB.BASEBOARD_FAB2(SCH_1):PAGE93_I106@MSTR_DISCRETE.RES(CHIPS)':
 'B': CDS_PINID='B';
NODE_NAME     R2T69 1
 '@BASEBOARD_FAB2_LIB.BASEBOARD_FAB2(SCH_1):PAGE93_I108@MSTR_DISCRETE.RES(CHIPS)':
 'A': CDS_PINID='A';
NODE_NAME     R2T73 2
 '@BASEBOARD_FAB2_LIB.BASEBOARD_FAB2(SCH_1):PAGE93_I144@MSTR_DISCRETE.RES(CHIPS)':
 'B': CDS_PINID='B';
NODE_NAME     Q7E3 3
 '@BASEBOARD_FAB2_LIB.BASEBOARD_FAB2(SCH_1):PAGE95_I51@MSTR_DISCRETE.FET_N_DUAL(CHIPS)':
 'DRAIN'<0>: CDS_PINID='DRAIN(0)';
NODE_NAME     Q7E6 3
 '@BASEBOARD_FAB2_LIB.BASEBOARD_FAB2(SCH_1):PAGE95_I69@MSTR_DISCRETE.FET_N_DUAL(CHIPS)':
 'DRAIN'<0>: CDS_PINID='DRAIN(0)';
NET_NAME
'H_CPU1_PROCHOT_G_PCH_N'
 '@BASEBOARD_FAB2_LIB.BASEBOARD_FAB2(SCH_1):H_CPU1_PROCHOT_G_PCH_N':
 C_SIGNAL='@baseboard_fab2_lib.baseboard_fab2(sch_1):h_cpu1_prochot_g_pch_n';
NODE_NAME     R2T69 2
 '@BASEBOARD_FAB2_LIB.BASEBOARD_FAB2(SCH_1):PAGE93_I108@MSTR_DISCRETE.RES(CHIPS)':
 'B': CDS_PINID='B';
NODE_NAME     R7D43 2
 '@BASEBOARD_FAB2_LIB.BASEBOARD_FAB2(SCH_1):PAGE93_I110@MSTR_DISCRETE.RES(CHIPS)':
 'B': CDS_PINID='B';
NET_NAME
'H_CPU1_PROCHOT_G_R_N'
 '@BASEBOARD_FAB2_LIB.BASEBOARD_FAB2(SCH_1):H_CPU1_PROCHOT_G_R_N':
 C_SIGNAL='@baseboard_fab2_lib.baseboard_fab2(sch_1):h_cpu1_prochot_g_r_n';
NODE_NAME     U2T4 2
 '@BASEBOARD_FAB2_LIB.BASEBOARD_FAB2(SCH_1):PAGE93_I30@MSTR_DIGITAL.GTL2014(CHIPS)':
 'B0': CDS_PINID='B0';
NODE_NAME     R2T68 2
 '@BASEBOARD_FAB2_LIB.BASEBOARD_FAB2(SCH_1):PAGE93_I102@MSTR_DISCRETE.RES(CHIPS)':
 'B': CDS_PINID='B';
NET_NAME
'H_CPU1_THERMTRIP_G_N'
 '@BASEBOARD_FAB2_LIB.BASEBOARD_FAB2(SCH_1):H_CPU1_THERMTRIP_G_N':
 C_SIGNAL='@baseboard_fab2_lib.baseboard_fab2(sch_1):h_cpu1_thermtrip_g_n';
NODE_NAME     U2D1 AB15
 '@BASEBOARD_FAB2_LIB.BASEBOARD_FAB2(SCH_1):PAGE55_I172@CHPSET_LIB.SKX_EXT_B(CHIPS)':
 'THERMTRIP_N': CDS_PINID='THERMTRIP_N';
NODE_NAME     U3P2 6
 '@BASEBOARD_FAB2_LIB.BASEBOARD_FAB2(SCH_1):PAGE92_I1@MSTR_DIGITAL.GTL2014(CHIPS)':
 'B3': CDS_PINID='B3';
NODE_NAME     R3P41 2
 '@BASEBOARD_FAB2_LIB.BASEBOARD_FAB2(SCH_1):PAGE92_I9@MSTR_DISCRETE.RES(CHIPS)':
 'B': CDS_PINID='B';
NET_NAME
'H_CPU_CATERR_G_N'
 '@BASEBOARD_FAB2_LIB.BASEBOARD_FAB2(SCH_1):H_CPU_CATERR_G_N':
 C_SIGNAL='@baseboard_fab2_lib.baseboard_fab2(sch_1):h_cpu_caterr_g_n';
NODE_NAME     U3P2 5
 '@BASEBOARD_FAB2_LIB.BASEBOARD_FAB2(SCH_1):PAGE92_I1@MSTR_DIGITAL.GTL2014(CHIPS)':
 'B2': CDS_PINID='B2';
NODE_NAME     R3P59 2
 '@BASEBOARD_FAB2_LIB.BASEBOARD_FAB2(SCH_1):PAGE92_I97@MSTR_DISCRETE.RES(CHIPS)':
 'B': CDS_PINID='B';
NODE_NAME     R3P58 2
 '@BASEBOARD_FAB2_LIB.BASEBOARD_FAB2(SCH_1):PAGE92_I98@MSTR_DISCRETE.RES(CHIPS)':
 'B': CDS_PINID='B';
NET_NAME
'H_CPU_ERR0_GTL_N'
 '@BASEBOARD_FAB2_LIB.BASEBOARD_FAB2(SCH_1):H_CPU_ERR0_GTL_N':
 C_SIGNAL='@baseboard_fab2_lib.baseboard_fab2(sch_1):h_cpu_err0_gtl_n';
NODE_NAME     U2T4 6
 '@BASEBOARD_FAB2_LIB.BASEBOARD_FAB2(SCH_1):PAGE93_I30@MSTR_DIGITAL.GTL2014(CHIPS)':
 'B3': CDS_PINID='B3';
NODE_NAME     R2T16 2
 '@BASEBOARD_FAB2_LIB.BASEBOARD_FAB2(SCH_1):PAGE93_I67@MSTR_DISCRETE.RES(CHIPS)':
 'B': CDS_PINID='B';
NET_NAME
'H_CPU_ERR0_GTL_R_N'
 '@BASEBOARD_FAB2_LIB.BASEBOARD_FAB2(SCH_1):H_CPU_ERR0_GTL_R_N':
 C_SIGNAL='@baseboard_fab2_lib.baseboard_fab2(sch_1):h_cpu_err0_gtl_r_n';
NODE_NAME     R2T20 2
 '@BASEBOARD_FAB2_LIB.BASEBOARD_FAB2(SCH_1):PAGE93_I16@MSTR_DISCRETE.RES(CHIPS)':
 'B': CDS_PINID='B';
NODE_NAME     R2T17 2
 '@BASEBOARD_FAB2_LIB.BASEBOARD_FAB2(SCH_1):PAGE93_I23@MSTR_DISCRETE.RES(CHIPS)':
 'B': CDS_PINID='B';
NODE_NAME     R2T19 2
 '@BASEBOARD_FAB2_LIB.BASEBOARD_FAB2(SCH_1):PAGE93_I63@MSTR_DISCRETE.RES(CHIPS)':
 'B': CDS_PINID='B';
NODE_NAME     R2T16 1
 '@BASEBOARD_FAB2_LIB.BASEBOARD_FAB2(SCH_1):PAGE93_I67@MSTR_DISCRETE.RES(CHIPS)':
 'A': CDS_PINID='A';
NODE_NAME     R2T57 2
 '@BASEBOARD_FAB2_LIB.BASEBOARD_FAB2(SCH_1):PAGE93_I88@MSTR_DISCRETE.RES(CHIPS)':
 'B': CDS_PINID='B';
NET_NAME
'H_CPU_ERR0_PCH_N'
 '@BASEBOARD_FAB2_LIB.BASEBOARD_FAB2(SCH_1):H_CPU_ERR0_PCH_N':
 C_SIGNAL='@baseboard_fab2_lib.baseboard_fab2(sch_1):h_cpu_err0_pch_n';
NODE_NAME     R2T57 1
 '@BASEBOARD_FAB2_LIB.BASEBOARD_FAB2(SCH_1):PAGE93_I88@MSTR_DISCRETE.RES(CHIPS)':
 'A': CDS_PINID='A';
NODE_NAME     R2T58 1
 '@BASEBOARD_FAB2_LIB.BASEBOARD_FAB2(SCH_1):PAGE93_I94@MSTR_DISCRETE.RES(CHIPS)':
 'A': CDS_PINID='A';
NET_NAME
'H_CPU_ERR1_GTL_N'
 '@BASEBOARD_FAB2_LIB.BASEBOARD_FAB2(SCH_1):H_CPU_ERR1_GTL_N':
 C_SIGNAL='@baseboard_fab2_lib.baseboard_fab2(sch_1):h_cpu_err1_gtl_n';
NODE_NAME     U2T4 5
 '@BASEBOARD_FAB2_LIB.BASEBOARD_FAB2(SCH_1):PAGE93_I30@MSTR_DIGITAL.GTL2014(CHIPS)':
 'B2': CDS_PINID='B2';
NODE_NAME     R2T31 2
 '@BASEBOARD_FAB2_LIB.BASEBOARD_FAB2(SCH_1):PAGE93_I68@MSTR_DISCRETE.RES(CHIPS)':
 'B': CDS_PINID='B';
NET_NAME
'H_CPU_ERR1_GTL_R_N'
 '@BASEBOARD_FAB2_LIB.BASEBOARD_FAB2(SCH_1):H_CPU_ERR1_GTL_R_N':
 C_SIGNAL='@baseboard_fab2_lib.baseboard_fab2(sch_1):h_cpu_err1_gtl_r_n';
NODE_NAME     R2T27 2
 '@BASEBOARD_FAB2_LIB.BASEBOARD_FAB2(SCH_1):PAGE93_I13@MSTR_DISCRETE.RES(CHIPS)':
 'B': CDS_PINID='B';
NODE_NAME     R2T32 2
 '@BASEBOARD_FAB2_LIB.BASEBOARD_FAB2(SCH_1):PAGE93_I15@MSTR_DISCRETE.RES(CHIPS)':
 'B': CDS_PINID='B';
NODE_NAME     R2T31 1
 '@BASEBOARD_FAB2_LIB.BASEBOARD_FAB2(SCH_1):PAGE93_I68@MSTR_DISCRETE.RES(CHIPS)':
 'A': CDS_PINID='A';
NODE_NAME     R2T26 2
 '@BASEBOARD_FAB2_LIB.BASEBOARD_FAB2(SCH_1):PAGE93_I87@MSTR_DISCRETE.RES(CHIPS)':
 'B': CDS_PINID='B';
NODE_NAME     R2T61 2
 '@BASEBOARD_FAB2_LIB.BASEBOARD_FAB2(SCH_1):PAGE93_I89@MSTR_DISCRETE.RES(CHIPS)':
 'B': CDS_PINID='B';
NET_NAME
'H_CPU_ERR1_PCH_N'
 '@BASEBOARD_FAB2_LIB.BASEBOARD_FAB2(SCH_1):H_CPU_ERR1_PCH_N':
 C_SIGNAL='@baseboard_fab2_lib.baseboard_fab2(sch_1):h_cpu_err1_pch_n';
NODE_NAME     R2T61 1
 '@BASEBOARD_FAB2_LIB.BASEBOARD_FAB2(SCH_1):PAGE93_I89@MSTR_DISCRETE.RES(CHIPS)':
 'A': CDS_PINID='A';
NODE_NAME     R2T62 1
 '@BASEBOARD_FAB2_LIB.BASEBOARD_FAB2(SCH_1):PAGE93_I93@MSTR_DISCRETE.RES(CHIPS)':
 'A': CDS_PINID='A';
NET_NAME
'H_CPU_ERR2_GTL_N'
 '@BASEBOARD_FAB2_LIB.BASEBOARD_FAB2(SCH_1):H_CPU_ERR2_GTL_N':
 C_SIGNAL='@baseboard_fab2_lib.baseboard_fab2(sch_1):h_cpu_err2_gtl_n';
NODE_NAME     U7D2 5
 '@BASEBOARD_FAB2_LIB.BASEBOARD_FAB2(SCH_1):PAGE92_I32@MSTR_DIGITAL.GTL2014(CHIPS)':
 'B2': CDS_PINID='B2';
NODE_NAME     R2T43 2
 '@BASEBOARD_FAB2_LIB.BASEBOARD_FAB2(SCH_1):PAGE92_I96@MSTR_DISCRETE.RES(CHIPS)':
 'B': CDS_PINID='B';
NET_NAME
'H_CPU_ERR2_G_R_N'
 '@BASEBOARD_FAB2_LIB.BASEBOARD_FAB2(SCH_1):H_CPU_ERR2_G_R_N':
 C_SIGNAL='@baseboard_fab2_lib.baseboard_fab2(sch_1):h_cpu_err2_g_r_n';
NODE_NAME     R2T44 2
 '@BASEBOARD_FAB2_LIB.BASEBOARD_FAB2(SCH_1):PAGE92_I92@MSTR_DISCRETE.RES(CHIPS)':
 'B': CDS_PINID='B';
NODE_NAME     R2T40 2
 '@BASEBOARD_FAB2_LIB.BASEBOARD_FAB2(SCH_1):PAGE92_I93@MSTR_DISCRETE.RES(CHIPS)':
 'B': CDS_PINID='B';
NODE_NAME     R2T37 2
 '@BASEBOARD_FAB2_LIB.BASEBOARD_FAB2(SCH_1):PAGE92_I94@MSTR_DISCRETE.RES(CHIPS)':
 'B': CDS_PINID='B';
NODE_NAME     R2T43 1
 '@BASEBOARD_FAB2_LIB.BASEBOARD_FAB2(SCH_1):PAGE92_I96@MSTR_DISCRETE.RES(CHIPS)':
 'A': CDS_PINID='A';
NET_NAME
'H_CPU_MSMI_G_N'
 '@BASEBOARD_FAB2_LIB.BASEBOARD_FAB2(SCH_1):H_CPU_MSMI_G_N':
 C_SIGNAL='@baseboard_fab2_lib.baseboard_fab2(sch_1):h_cpu_msmi_g_n';
NODE_NAME     U7D2 2
 '@BASEBOARD_FAB2_LIB.BASEBOARD_FAB2(SCH_1):PAGE92_I32@MSTR_DIGITAL.GTL2014(CHIPS)':
 'B0': CDS_PINID='B0';
NODE_NAME     R7D28 2
 '@BASEBOARD_FAB2_LIB.BASEBOARD_FAB2(SCH_1):PAGE92_I67@MSTR_DISCRETE.RES(CHIPS)':
 'B': CDS_PINID='B';
NODE_NAME     R7D27 2
 '@BASEBOARD_FAB2_LIB.BASEBOARD_FAB2(SCH_1):PAGE92_I68@MSTR_DISCRETE.RES(CHIPS)':
 'B': CDS_PINID='B';
NET_NAME
'H_PMSYNC_CLK_24M'
 '@BASEBOARD_FAB2_LIB.BASEBOARD_FAB2(SCH_1):H_PMSYNC_CLK_24M':
 C_SIGNAL='@baseboard_fab2_lib.baseboard_fab2(sch_1):h_pmsync_clk_24m';
NODE_NAME     R4P19 2
 '@BASEBOARD_FAB2_LIB.BASEBOARD_FAB2(SCH_1):PAGE21_I219@MSTR_DISCRETE.RES(CHIPS)':
 'B': CDS_PINID='B';
NODE_NAME     R7P26 2
 '@BASEBOARD_FAB2_LIB.BASEBOARD_FAB2(SCH_1):PAGE55_I156@MSTR_DISCRETE.RES(CHIPS)':
 'B': CDS_PINID='B';
NODE_NAME     R8B20 2
 '@BASEBOARD_FAB2_LIB.BASEBOARD_FAB2(SCH_1):PAGE114_I110@MSTR_DISCRETE.RES(CHIPS)':
 'B': CDS_PINID='B';
NODE_NAME     R8B21 1
 '@BASEBOARD_FAB2_LIB.BASEBOARD_FAB2(SCH_1):PAGE114_I124@MSTR_DISCRETE.RES(CHIPS)':
 'A': CDS_PINID='A';
NET_NAME
'H_PMSYNC_CLK_24M_CPU0'
 '@BASEBOARD_FAB2_LIB.BASEBOARD_FAB2(SCH_1):H_PMSYNC_CLK_24M_CPU0':
 C_SIGNAL='@baseboard_fab2_lib.baseboard_fab2(sch_1):h_pmsync_clk_24m_cpu0';
NODE_NAME     R4P19 1
 '@BASEBOARD_FAB2_LIB.BASEBOARD_FAB2(SCH_1):PAGE21_I219@MSTR_DISCRETE.RES(CHIPS)':
 'A': CDS_PINID='A';
NODE_NAME     U5D1 AT19
 '@BASEBOARD_FAB2_LIB.BASEBOARD_FAB2(SCH_1):PAGE21_I259@CHPSET_LIB.SKX_EXT_B(CHIPS)':
 'PMSYNC_CLK': CDS_PINID='PMSYNC_CLK';
NET_NAME
'H_PMSYNC_CLK_24M_CPU1'
 '@BASEBOARD_FAB2_LIB.BASEBOARD_FAB2(SCH_1):H_PMSYNC_CLK_24M_CPU1':
 C_SIGNAL='@baseboard_fab2_lib.baseboard_fab2(sch_1):h_pmsync_clk_24m_cpu1';
NODE_NAME     R7P26 1
 '@BASEBOARD_FAB2_LIB.BASEBOARD_FAB2(SCH_1):PAGE55_I156@MSTR_DISCRETE.RES(CHIPS)':
 'A': CDS_PINID='A';
NODE_NAME     U2D1 AT19
 '@BASEBOARD_FAB2_LIB.BASEBOARD_FAB2(SCH_1):PAGE55_I172@CHPSET_LIB.SKX_EXT_B(CHIPS)':
 'PMSYNC_CLK': CDS_PINID='PMSYNC_CLK';
NET_NAME
'H_PMSYNC_CLK_24M_R'
 '@BASEBOARD_FAB2_LIB.BASEBOARD_FAB2(SCH_1):H_PMSYNC_CLK_24M_R':
 C_SIGNAL='@baseboard_fab2_lib.baseboard_fab2(sch_1):h_pmsync_clk_24m_r';
NODE_NAME     U7C1 BY51
 '@BASEBOARD_FAB2_LIB.BASEBOARD_FAB2(SCH_1):PAGE114_I40@MSTR_U_PROC.LBG_CORE_QAT_EXT_D(CHIPS)':
 'CLOCKSE_PMSYNCCLK1': CDS_PINID='CLOCKSE_PMSYNCCLK1';
NODE_NAME     R8B20 1
 '@BASEBOARD_FAB2_LIB.BASEBOARD_FAB2(SCH_1):PAGE114_I110@MSTR_DISCRETE.RES(CHIPS)':
 'A': CDS_PINID='A';
NET_NAME
'H_PM_SYNC1_GTL_R'
 '@BASEBOARD_FAB2_LIB.BASEBOARD_FAB2(SCH_1):H_PM_SYNC1_GTL_R':
 C_SIGNAL='@baseboard_fab2_lib.baseboard_fab2(sch_1):h_pm_sync1_gtl_r';
NODE_NAME     R3N9 1
 '@BASEBOARD_FAB2_LIB.BASEBOARD_FAB2(SCH_1):PAGE118_I66@MSTR_DISCRETE.RES(CHIPS)':
 'A': CDS_PINID='A';
NODE_NAME     U7C1 U13
 '@BASEBOARD_FAB2_LIB.BASEBOARD_FAB2(SCH_1):PAGE118_I73@MSTR_U_PROC.LBG_CORE_QAT_EXT_D(CHIPS)':
 'PM_SYNC': CDS_PINID='PM_SYNC';
NET_NAME
'H_PM_SYNC_GTL'
 '@BASEBOARD_FAB2_LIB.BASEBOARD_FAB2(SCH_1):H_PM_SYNC_GTL':
 C_SIGNAL='@baseboard_fab2_lib.baseboard_fab2(sch_1):h_pm_sync_gtl';
NODE_NAME     R4P18 2
 '@BASEBOARD_FAB2_LIB.BASEBOARD_FAB2(SCH_1):PAGE21_I244@MSTR_DISCRETE.RES(CHIPS)':
 'B': CDS_PINID='B';
NODE_NAME     R7P25 2
 '@BASEBOARD_FAB2_LIB.BASEBOARD_FAB2(SCH_1):PAGE55_I170@MSTR_DISCRETE.RES(CHIPS)':
 'B': CDS_PINID='B';
NODE_NAME     R3N9 2
 '@BASEBOARD_FAB2_LIB.BASEBOARD_FAB2(SCH_1):PAGE118_I66@MSTR_DISCRETE.RES(CHIPS)':
 'B': CDS_PINID='B';
NODE_NAME     R3N14 1
 '@BASEBOARD_FAB2_LIB.BASEBOARD_FAB2(SCH_1):PAGE118_I67@MSTR_DISCRETE.RES(CHIPS)':
 'A': CDS_PINID='A';
NET_NAME
'H_PM_SYNC_GTL_R1'
 '@BASEBOARD_FAB2_LIB.BASEBOARD_FAB2(SCH_1):H_PM_SYNC_GTL_R1':
 C_SIGNAL='@baseboard_fab2_lib.baseboard_fab2(sch_1):h_pm_sync_gtl_r1';
NODE_NAME     R4P18 1
 '@BASEBOARD_FAB2_LIB.BASEBOARD_FAB2(SCH_1):PAGE21_I244@MSTR_DISCRETE.RES(CHIPS)':
 'A': CDS_PINID='A';
NODE_NAME     U5D1 AR14
 '@BASEBOARD_FAB2_LIB.BASEBOARD_FAB2(SCH_1):PAGE21_I259@CHPSET_LIB.SKX_EXT_B(CHIPS)':
 'PMSYNC': CDS_PINID='PMSYNC';
NET_NAME
'H_PM_SYNC_GTL_R2'
 '@BASEBOARD_FAB2_LIB.BASEBOARD_FAB2(SCH_1):H_PM_SYNC_GTL_R2':
 C_SIGNAL='@baseboard_fab2_lib.baseboard_fab2(sch_1):h_pm_sync_gtl_r2';
NODE_NAME     R7P25 1
 '@BASEBOARD_FAB2_LIB.BASEBOARD_FAB2(SCH_1):PAGE55_I170@MSTR_DISCRETE.RES(CHIPS)':
 'A': CDS_PINID='A';
NODE_NAME     U2D1 AR14
 '@BASEBOARD_FAB2_LIB.BASEBOARD_FAB2(SCH_1):PAGE55_I172@CHPSET_LIB.SKX_EXT_B(CHIPS)':
 'PMSYNC': CDS_PINID='PMSYNC';
NET_NAME
'I2C_BMC_VGA_DDC_SCL'
 '@BASEBOARD_FAB2_LIB.BASEBOARD_FAB2(SCH_1):I2C_BMC_VGA_DDC_SCL':
 C_SIGNAL='@baseboard_fab2_lib.baseboard_fab2(sch_1):i2c_bmc_vga_ddc_scl';
NODE_NAME     U25W4 R3
 '@BASEBOARD_FAB2_LIB.BASEBOARD_FAB2(SCH_1):PAGE146_I105@W_HDL.AST2520A1-GP-GP(CHIPS)':
 'GPIOJ6_DDCCLK': CDS_PINID='GPIOJ6_DDCCLK';
NODE_NAME     R25W129 2
 '@BASEBOARD_FAB2_LIB.BASEBOARD_FAB2(SCH_1):PAGE146_I152@MSTR_DISCRETE.RES(CHIPS)':
 'B': CDS_PINID='B';
NODE_NAME     Q25W4 1
 '@BASEBOARD_FAB2_LIB.BASEBOARD_FAB2(SCH_1):PAGE255_I95@MSTR_DISCRETE.FET_N_DUAL(CHIPS)':
 'SOURCE'<0>: CDS_PINID='SOURCE(0)';
NET_NAME
'I2C_BMC_VGA_DDC_SCL_G'
 '@BASEBOARD_FAB2_LIB.BASEBOARD_FAB2(SCH_1):I2C_BMC_VGA_DDC_SCL_G':
 C_SIGNAL='@baseboard_fab2_lib.baseboard_fab2(sch_1):i2c_bmc_vga_ddc_scl_g';
NODE_NAME     R25W132 2
 '@BASEBOARD_FAB2_LIB.BASEBOARD_FAB2(SCH_1):PAGE255_I31@MSTR_DISCRETE.RES(CHIPS)':
 'B': CDS_PINID='B';
NODE_NAME     R25W133 1
 '@BASEBOARD_FAB2_LIB.BASEBOARD_FAB2(SCH_1):PAGE255_I34@MSTR_DISCRETE.RES(CHIPS)':
 'A': CDS_PINID='A';
NODE_NAME     Q25W4 6
 '@BASEBOARD_FAB2_LIB.BASEBOARD_FAB2(SCH_1):PAGE255_I95@MSTR_DISCRETE.FET_N_DUAL(CHIPS)':
 'DRAIN'<0>: CDS_PINID='DRAIN(0)';
NET_NAME
'I2C_BMC_VGA_DDC_SDA'
 '@BASEBOARD_FAB2_LIB.BASEBOARD_FAB2(SCH_1):I2C_BMC_VGA_DDC_SDA':
 C_SIGNAL='@baseboard_fab2_lib.baseboard_fab2(sch_1):i2c_bmc_vga_ddc_sda';
NODE_NAME     U25W4 T3
 '@BASEBOARD_FAB2_LIB.BASEBOARD_FAB2(SCH_1):PAGE146_I105@W_HDL.AST2520A1-GP-GP(CHIPS)':
 'GPIOJ7_DDCDAT': CDS_PINID='GPIOJ7_DDCDAT';
NODE_NAME     R25W130 2
 '@BASEBOARD_FAB2_LIB.BASEBOARD_FAB2(SCH_1):PAGE146_I153@MSTR_DISCRETE.RES(CHIPS)':
 'B': CDS_PINID='B';
NODE_NAME     Q25W4 4
 '@BASEBOARD_FAB2_LIB.BASEBOARD_FAB2(SCH_1):PAGE255_I96@MSTR_DISCRETE.FET_N_DUAL(CHIPS)':
 'SOURCE'<0>: CDS_PINID='SOURCE(0)';
NET_NAME
'I2C_BMC_VGA_DDC_SDA_G'
 '@BASEBOARD_FAB2_LIB.BASEBOARD_FAB2(SCH_1):I2C_BMC_VGA_DDC_SDA_G':
 C_SIGNAL='@baseboard_fab2_lib.baseboard_fab2(sch_1):i2c_bmc_vga_ddc_sda_g';
NODE_NAME     R25W136 1
 '@BASEBOARD_FAB2_LIB.BASEBOARD_FAB2(SCH_1):PAGE255_I38@MSTR_DISCRETE.RES(CHIPS)':
 'A': CDS_PINID='A';
NODE_NAME     R25W135 2
 '@BASEBOARD_FAB2_LIB.BASEBOARD_FAB2(SCH_1):PAGE255_I44@MSTR_DISCRETE.RES(CHIPS)':
 'B': CDS_PINID='B';
NODE_NAME     Q25W4 3
 '@BASEBOARD_FAB2_LIB.BASEBOARD_FAB2(SCH_1):PAGE255_I96@MSTR_DISCRETE.FET_N_DUAL(CHIPS)':
 'DRAIN'<0>: CDS_PINID='DRAIN(0)';
NET_NAME
'IRQ_BMC_PCH_NMI_STBY_N'
 '@BASEBOARD_FAB2_LIB.BASEBOARD_FAB2(SCH_1):IRQ_BMC_PCH_NMI_STBY_N':
 C_SIGNAL='@baseboard_fab2_lib.baseboard_fab2(sch_1):irq_bmc_pch_nmi_stby_n';
NODE_NAME     U7C1 BB52
 '@BASEBOARD_FAB2_LIB.BASEBOARD_FAB2(SCH_1):PAGE120_I147@MSTR_U_PROC.LBG_CORE_QAT_EXT_D(CHIPS)':
 'GPP_E6_SATA_DEVSLP2': CDS_PINID='GPP_E6_SATA_DEVSLP2';
NODE_NAME     R8E24 1
 '@BASEBOARD_FAB2_LIB.BASEBOARD_FAB2(SCH_1):PAGE156_I214@MSTR_DISCRETE.RES(CHIPS)':
 'A': CDS_PINID='A';
NODE_NAME     R8E22 2
 '@BASEBOARD_FAB2_LIB.BASEBOARD_FAB2(SCH_1):PAGE156_I215@MSTR_DISCRETE.RES(CHIPS)':
 'B': CDS_PINID='B';
NODE_NAME     U25W4 D19
 '@BASEBOARD_FAB2_LIB.BASEBOARD_FAB2(SCH_1):PAGE145_I117@W_HDL.AST2520A1-GP-GP(CHIPS)':
 'GPIOE5_NRTS3': CDS_PINID='GPIOE5_NRTS3';
NET_NAME
'IRQ_BMC_PCH_NMI_STBY_R_N'
 '@BASEBOARD_FAB2_LIB.BASEBOARD_FAB2(SCH_1):IRQ_BMC_PCH_NMI_STBY_R_N':
 C_SIGNAL='@baseboard_fab2_lib.baseboard_fab2(sch_1):irq_bmc_pch_nmi_stby_r_n';
NODE_NAME     U7C1 BR42
 '@BASEBOARD_FAB2_LIB.BASEBOARD_FAB2(SCH_1):PAGE119_I115@MSTR_U_PROC.LBG_CORE_QAT_EXT_D(CHIPS)':
 'GPP_D0': CDS_PINID='GPP_D0';
NODE_NAME     R8E24 2
 '@BASEBOARD_FAB2_LIB.BASEBOARD_FAB2(SCH_1):PAGE156_I214@MSTR_DISCRETE.RES(CHIPS)':
 'B': CDS_PINID='B';
NET_NAME
'IRQ_BMC_PCH_SCI_LPC_N'
 '@BASEBOARD_FAB2_LIB.BASEBOARD_FAB2(SCH_1):IRQ_BMC_PCH_SCI_LPC_N':
 C_SIGNAL='@baseboard_fab2_lib.baseboard_fab2(sch_1):irq_bmc_pch_sci_lpc_n';
NODE_NAME     U7C1 BY38
 '@BASEBOARD_FAB2_LIB.BASEBOARD_FAB2(SCH_1):PAGE119_I115@MSTR_U_PROC.LBG_CORE_QAT_EXT_D(CHIPS)':
 'GPP_C14': CDS_PINID='GPP_C14';
NODE_NAME     U7C1 BN48
 '@BASEBOARD_FAB2_LIB.BASEBOARD_FAB2(SCH_1):PAGE120_I147@MSTR_U_PROC.LBG_CORE_QAT_EXT_D(CHIPS)':
 'GPP_E10_USB2_OC1_N': CDS_PINID='GPP_E10_USB2_OC1_N';
NODE_NAME     R8C2 2
 '@BASEBOARD_FAB2_LIB.BASEBOARD_FAB2(SCH_1):PAGE133_I304@MSTR_DISCRETE.RES(CHIPS)':
 'B': CDS_PINID='B';
NODE_NAME     U25W4 AA21
 '@BASEBOARD_FAB2_LIB.BASEBOARD_FAB2(SCH_1):PAGE146_I104@W_HDL.AST2520A1-GP-GP(CHIPS)':
 'GPIOZ3_VPOG5_NORA3_SIOSCI#': CDS_PINID='\gpioz3_vpog5_nora3_siosci#\';
NET_NAME
'IRQ_BMC_PCH_SMI_LPC_N'
 '@BASEBOARD_FAB2_LIB.BASEBOARD_FAB2(SCH_1):IRQ_BMC_PCH_SMI_LPC_N':
 C_SIGNAL='@baseboard_fab2_lib.baseboard_fab2(sch_1):irq_bmc_pch_smi_lpc_n';
NODE_NAME     U7C1 CA34
 '@BASEBOARD_FAB2_LIB.BASEBOARD_FAB2(SCH_1):PAGE119_I115@MSTR_U_PROC.LBG_CORE_QAT_EXT_D(CHIPS)':
 'GPP_C22': CDS_PINID='GPP_C22';
NODE_NAME     U7C1 AW54
 '@BASEBOARD_FAB2_LIB.BASEBOARD_FAB2(SCH_1):PAGE120_I147@MSTR_U_PROC.LBG_CORE_QAT_EXT_D(CHIPS)':
 'GPP_E11_USB2_OC2_N': CDS_PINID='GPP_E11_USB2_OC2_N';
NODE_NAME     R8C4 2
 '@BASEBOARD_FAB2_LIB.BASEBOARD_FAB2(SCH_1):PAGE133_I286@MSTR_DISCRETE.RES(CHIPS)':
 'B': CDS_PINID='B';
NODE_NAME     U25W4 H21
 '@BASEBOARD_FAB2_LIB.BASEBOARD_FAB2(SCH_1):PAGE144_I95@W_HDL.AST2520A1-GP-GP(CHIPS)':
 'GPIOB5_LPCPD#_LPCSMI#': CDS_PINID='\gpiob5_lpcpd#_lpcsmi#\';
NET_NAME
'IRQ_BOARD_BMC_ALERT_N'
 '@BASEBOARD_FAB2_LIB.BASEBOARD_FAB2(SCH_1):IRQ_BOARD_BMC_ALERT_N':
 C_SIGNAL='@baseboard_fab2_lib.baseboard_fab2(sch_1):irq_board_bmc_alert_n',
 PHYS_NET_NAME='IRQ_BOARD_BMC_ALERT_N';
NODE_NAME     U7C1 BW24
 '@BASEBOARD_FAB2_LIB.BASEBOARD_FAB2(SCH_1):PAGE120_I147@MSTR_U_PROC.LBG_CORE_QAT_EXT_D(CHIPS)':
 'GPP_I5_DO_RESET_OUT_N': CDS_PINID='GPP_I5_DO_RESET_OUT_N';
NODE_NAME     R2N7 2
 '@BASEBOARD_FAB2_LIB.BASEBOARD_FAB2(SCH_1):PAGE133_I309@MSTR_DISCRETE.RES(CHIPS)':
 'B': CDS_PINID='B';
NODE_NAME     U25W4 AA1
 '@BASEBOARD_FAB2_LIB.BASEBOARD_FAB2(SCH_1):PAGE145_I117@W_HDL.AST2520A1-GP-GP(CHIPS)':
 'GPIOM2_NDSR2_VPIB4': CDS_PINID='GPIOM2_NDSR2_VPIB4';
NODE_NAME     R1C9 1
 '@BASEBOARD_FAB2_LIB.BASEBOARD_FAB2(SCH_1):PAGE182_I8@MSTR_DISCRETE.RES(CHIPS)':
 'A': CDS_PINID='A';
NODE_NAME     J1C1 B5
 '@BASEBOARD_FAB2_LIB.BASEBOARD_FAB2(SCH_1):PAGE182_I79@W_HDL.DM-FCI-CONN76-8R-GP-U-01(CHIPS)':
 'MNG_TX_DN': CDS_PINID='MNG_TX_DN';
NET_NAME
'IRQ_CPU0_PROCHOT_G_N'
 '@BASEBOARD_FAB2_LIB.BASEBOARD_FAB2(SCH_1):IRQ_CPU0_PROCHOT_G_N':
 C_SIGNAL='@baseboard_fab2_lib.baseboard_fab2(sch_1):irq_cpu0_prochot_g_n';
NODE_NAME     Q7E5 2
 '@BASEBOARD_FAB2_LIB.BASEBOARD_FAB2(SCH_1):PAGE95_I111@MSTR_DISCRETE.FET_N_DUAL(CHIPS)':
 'GATE'<0>: CDS_PINID='GATE(0)';
NODE_NAME     U7E2 4
 '@BASEBOARD_FAB2_LIB.BASEBOARD_FAB2(SCH_1):PAGE95_I117@MSTR_TTL.TTL1G08(CHIPS)':
 'Y'<0>: CDS_PINID='Y(0)';
NET_NAME
'IRQ_CPU0_VRHOT'
 '@BASEBOARD_FAB2_LIB.BASEBOARD_FAB2(SCH_1):IRQ_CPU0_VRHOT':
 C_SIGNAL='@baseboard_fab2_lib.baseboard_fab2(sch_1):irq_cpu0_vrhot';
NODE_NAME     Q7E5 5
 '@BASEBOARD_FAB2_LIB.BASEBOARD_FAB2(SCH_1):PAGE95_I59@MSTR_DISCRETE.FET_N_DUAL(CHIPS)':
 'GATE'<0>: CDS_PINID='GATE(0)';
NODE_NAME     R7E10 2
 '@BASEBOARD_FAB2_LIB.BASEBOARD_FAB2(SCH_1):PAGE95_I62@MSTR_DISCRETE.RES(CHIPS)':
 'B': CDS_PINID='B';
NODE_NAME     Q7E5 6
 '@BASEBOARD_FAB2_LIB.BASEBOARD_FAB2(SCH_1):PAGE95_I111@MSTR_DISCRETE.FET_N_DUAL(CHIPS)':
 'DRAIN'<0>: CDS_PINID='DRAIN(0)';
NET_NAME
'IRQ_CPU1_PROCHOT_G_N'
 '@BASEBOARD_FAB2_LIB.BASEBOARD_FAB2(SCH_1):IRQ_CPU1_PROCHOT_G_N':
 C_SIGNAL='@baseboard_fab2_lib.baseboard_fab2(sch_1):irq_cpu1_prochot_g_n';
NODE_NAME     Q7E6 2
 '@BASEBOARD_FAB2_LIB.BASEBOARD_FAB2(SCH_1):PAGE95_I112@MSTR_DISCRETE.FET_N_DUAL(CHIPS)':
 'GATE'<0>: CDS_PINID='GATE(0)';
NODE_NAME     U7E3 4
 '@BASEBOARD_FAB2_LIB.BASEBOARD_FAB2(SCH_1):PAGE95_I118@MSTR_TTL.TTL1G08(CHIPS)':
 'Y'<0>: CDS_PINID='Y(0)';
NET_NAME
'IRQ_CPU1_VRHOT'
 '@BASEBOARD_FAB2_LIB.BASEBOARD_FAB2(SCH_1):IRQ_CPU1_VRHOT':
 C_SIGNAL='@baseboard_fab2_lib.baseboard_fab2(sch_1):irq_cpu1_vrhot';
NODE_NAME     Q7E6 5
 '@BASEBOARD_FAB2_LIB.BASEBOARD_FAB2(SCH_1):PAGE95_I69@MSTR_DISCRETE.FET_N_DUAL(CHIPS)':
 'GATE'<0>: CDS_PINID='GATE(0)';
NODE_NAME     R7E11 2
 '@BASEBOARD_FAB2_LIB.BASEBOARD_FAB2(SCH_1):PAGE95_I72@MSTR_DISCRETE.RES(CHIPS)':
 'B': CDS_PINID='B';
NODE_NAME     Q7E6 6
 '@BASEBOARD_FAB2_LIB.BASEBOARD_FAB2(SCH_1):PAGE95_I112@MSTR_DISCRETE.FET_N_DUAL(CHIPS)':
 'DRAIN'<0>: CDS_PINID='DRAIN(0)';
NET_NAME
'IRQ_DIMM_SAVE_CPU1_R_N'
 '@BASEBOARD_FAB2_LIB.BASEBOARD_FAB2(SCH_1):IRQ_DIMM_SAVE_CPU1_R_N':
 C_SIGNAL='@baseboard_fab2_lib.baseboard_fab2(sch_1):irq_dimm_save_cpu1_r_n';
NODE_NAME     WR8D30 2
 '@BASEBOARD_FAB2_LIB.BASEBOARD_FAB2(SCH_1):PAGE89_I45@MSTR_DISCRETE.RES(CHIPS)':
 'B': CDS_PINID='B';
NODE_NAME     Q8W1 5
 '@BASEBOARD_FAB2_LIB.BASEBOARD_FAB2(SCH_1):PAGE89_I52@MSTR_DISCRETE.NPN_DUAL(CHIPS)':
 'B'<0>: CDS_PINID='B(0)';
NET_NAME
'IRQ_DIMM_SAVE_LVT3'
 '@BASEBOARD_FAB2_LIB.BASEBOARD_FAB2(SCH_1):IRQ_DIMM_SAVE_LVT3':
 C_SIGNAL='@baseboard_fab2_lib.baseboard_fab2(sch_1):irq_dimm_save_lvt3';
NODE_NAME     R8D29 2
 '@BASEBOARD_FAB2_LIB.BASEBOARD_FAB2(SCH_1):PAGE89_I26@MSTR_DISCRETE.RES(CHIPS)':
 'B': CDS_PINID='B';
NODE_NAME     Q8D1 3
 '@BASEBOARD_FAB2_LIB.BASEBOARD_FAB2(SCH_1):PAGE89_I35@MSTR_DISCRETE.NPN_DUAL(CHIPS)':
 'C'<0>: CDS_PINID='C(0)';
NODE_NAME     Q8D1 2
 '@BASEBOARD_FAB2_LIB.BASEBOARD_FAB2(SCH_1):PAGE89_I46@MSTR_DISCRETE.NPN_DUAL(CHIPS)':
 'B'<0>: CDS_PINID='B(0)';
NET_NAME
'IRQ_DIMM_SAVE_LVT3_CPU1'
 '@BASEBOARD_FAB2_LIB.BASEBOARD_FAB2(SCH_1):IRQ_DIMM_SAVE_LVT3_CPU1':
 C_SIGNAL='@baseboard_fab2_lib.baseboard_fab2(sch_1):irq_dimm_save_lvt3_cpu1';
NODE_NAME     R8W9 2
 '@BASEBOARD_FAB2_LIB.BASEBOARD_FAB2(SCH_1):PAGE89_I49@MSTR_DISCRETE.RES(CHIPS)':
 'B': CDS_PINID='B';
NODE_NAME     Q8W1 2
 '@BASEBOARD_FAB2_LIB.BASEBOARD_FAB2(SCH_1):PAGE89_I51@MSTR_DISCRETE.NPN_DUAL(CHIPS)':
 'B'<0>: CDS_PINID='B(0)';
NODE_NAME     Q8W1 3
 '@BASEBOARD_FAB2_LIB.BASEBOARD_FAB2(SCH_1):PAGE89_I52@MSTR_DISCRETE.NPN_DUAL(CHIPS)':
 'C'<0>: CDS_PINID='C(0)';
NET_NAME
'IRQ_DIMM_SAVE_LVT3_N'
 '@BASEBOARD_FAB2_LIB.BASEBOARD_FAB2(SCH_1):IRQ_DIMM_SAVE_LVT3_N':
 C_SIGNAL='@baseboard_fab2_lib.baseboard_fab2(sch_1):irq_dimm_save_lvt3_n',
 PHYS_NET_NAME='IRQ_DIMM_SAVE_LVT3_N';
NODE_NAME     R2P12 1
 '@BASEBOARD_FAB2_LIB.BASEBOARD_FAB2(SCH_1):PAGE89_I23@MSTR_DISCRETE.RES(CHIPS)':
 'A': CDS_PINID='A';
NODE_NAME     R8D31 2
 '@BASEBOARD_FAB2_LIB.BASEBOARD_FAB2(SCH_1):PAGE89_I27@MSTR_DISCRETE.RES(CHIPS)':
 'B': CDS_PINID='B';
NODE_NAME     U25W4 D21
 '@BASEBOARD_FAB2_LIB.BASEBOARD_FAB2(SCH_1):PAGE145_I117@W_HDL.AST2520A1-GP-GP(CHIPS)':
 'GPIOD4_SD2DAT2': CDS_PINID='GPIOD4_SD2DAT2';
NODE_NAME     Q8D1 6
 '@BASEBOARD_FAB2_LIB.BASEBOARD_FAB2(SCH_1):PAGE89_I46@MSTR_DISCRETE.NPN_DUAL(CHIPS)':
 'C'<0>: CDS_PINID='C(0)';
NODE_NAME     Q8W1 6
 '@BASEBOARD_FAB2_LIB.BASEBOARD_FAB2(SCH_1):PAGE89_I51@MSTR_DISCRETE.NPN_DUAL(CHIPS)':
 'C'<0>: CDS_PINID='C(0)';
NODE_NAME     R7W16 2
 '@BASEBOARD_FAB2_LIB.BASEBOARD_FAB2(SCH_1):PAGE120_I276@MSTR_DISCRETE.RES(CHIPS)':
 'B': CDS_PINID='B';
NET_NAME
'IRQ_DIMM_SAVE_LVT3_R_N'
 '@BASEBOARD_FAB2_LIB.BASEBOARD_FAB2(SCH_1):IRQ_DIMM_SAVE_LVT3_R_N':
 C_SIGNAL='@baseboard_fab2_lib.baseboard_fab2(sch_1):irq_dimm_save_lvt3_r_n';
NODE_NAME     U7C1 BW20
 '@BASEBOARD_FAB2_LIB.BASEBOARD_FAB2(SCH_1):PAGE120_I147@MSTR_U_PROC.LBG_CORE_QAT_EXT_D(CHIPS)':
 'GPP_I4_DO_RESET_IN_N': CDS_PINID='GPP_I4_DO_RESET_IN_N';
NODE_NAME     R7W16 1
 '@BASEBOARD_FAB2_LIB.BASEBOARD_FAB2(SCH_1):PAGE120_I276@MSTR_DISCRETE.RES(CHIPS)':
 'A': CDS_PINID='A';
NET_NAME
'IRQ_DIMM_SAVE_N'
 '@BASEBOARD_FAB2_LIB.BASEBOARD_FAB2(SCH_1):IRQ_DIMM_SAVE_N':
 C_SIGNAL='@baseboard_fab2_lib.baseboard_fab2(sch_1):irq_dimm_save_n';
NODE_NAME     R6F4 1
 '@BASEBOARD_FAB2_LIB.BASEBOARD_FAB2(SCH_1):PAGE89_I3@MSTR_DISCRETE.RES(CHIPS)':
 'A': CDS_PINID='A';
NODE_NAME     R6F1 1
 '@BASEBOARD_FAB2_LIB.BASEBOARD_FAB2(SCH_1):PAGE89_I4@MSTR_DISCRETE.RES(CHIPS)':
 'A': CDS_PINID='A';
NODE_NAME     R6F3 2
 '@BASEBOARD_FAB2_LIB.BASEBOARD_FAB2(SCH_1):PAGE89_I7@MSTR_DISCRETE.RES(CHIPS)':
 'B': CDS_PINID='B';
NODE_NAME     R8D30 1
 '@BASEBOARD_FAB2_LIB.BASEBOARD_FAB2(SCH_1):PAGE89_I34@MSTR_DISCRETE.RES(CHIPS)':
 'A': CDS_PINID='A';
NODE_NAME     Q1F1 3
 '@BASEBOARD_FAB2_LIB.BASEBOARD_FAB2(SCH_1):PAGE89_I53@MSTR_DISCRETE.NPN(CHIPS)':
 'C': CDS_PINID='C';
NET_NAME
'IRQ_DIMM_SAVE_R_N'
 '@BASEBOARD_FAB2_LIB.BASEBOARD_FAB2(SCH_1):IRQ_DIMM_SAVE_R_N':
 C_SIGNAL='@baseboard_fab2_lib.baseboard_fab2(sch_1):irq_dimm_save_r_n';
NODE_NAME     R8D30 2
 '@BASEBOARD_FAB2_LIB.BASEBOARD_FAB2(SCH_1):PAGE89_I34@MSTR_DISCRETE.RES(CHIPS)':
 'B': CDS_PINID='B';
NODE_NAME     Q8D1 5
 '@BASEBOARD_FAB2_LIB.BASEBOARD_FAB2(SCH_1):PAGE89_I35@MSTR_DISCRETE.NPN_DUAL(CHIPS)':
 'B'<0>: CDS_PINID='B(0)';
NET_NAME
'IRQ_FORCE_NM_THROTTLE_N'
 '@BASEBOARD_FAB2_LIB.BASEBOARD_FAB2(SCH_1):IRQ_FORCE_NM_THROTTLE_N':
 C_SIGNAL='@baseboard_fab2_lib.baseboard_fab2(sch_1):irq_force_nm_throttle_n';
NODE_NAME     U7C1 BY42
 '@BASEBOARD_FAB2_LIB.BASEBOARD_FAB2(SCH_1):PAGE119_I115@MSTR_U_PROC.LBG_CORE_QAT_EXT_D(CHIPS)':
 'GPP_D9_SSATA_DEVSLP3': CDS_PINID='GPP_D9_SSATA_DEVSLP3';
NODE_NAME     U7C1 BA17
 '@BASEBOARD_FAB2_LIB.BASEBOARD_FAB2(SCH_1):PAGE120_I147@MSTR_U_PROC.LBG_CORE_QAT_EXT_D(CHIPS)':
 'GPP_G20_SSATA_DEVSLP0': CDS_PINID='GPP_G20_SSATA_DEVSLP0';
NODE_NAME     U8E1 1
 '@BASEBOARD_FAB2_LIB.BASEBOARD_FAB2(SCH_1):PAGE170_I10@MSTR_TTL.TTL08(CHIPS)':
 'A'<0>: CDS_PINID='A(0)';
NODE_NAME     R2P4 2
 '@BASEBOARD_FAB2_LIB.BASEBOARD_FAB2(SCH_1):PAGE170_I74@MSTR_DISCRETE.RES(CHIPS)':
 'B': CDS_PINID='B';
NODE_NAME     R2T41 1
 '@BASEBOARD_FAB2_LIB.BASEBOARD_FAB2(SCH_1):PAGE145_I136@MSTR_DISCRETE.RES(CHIPS)':
 'A': CDS_PINID='A';
NET_NAME
'IRQ_FORCE_NM_THROTTLE_R_N'
 '@BASEBOARD_FAB2_LIB.BASEBOARD_FAB2(SCH_1):IRQ_FORCE_NM_THROTTLE_R_N':
 C_SIGNAL='@baseboard_fab2_lib.baseboard_fab2(sch_1):irq_force_nm_throttle_r_n';
NODE_NAME     R2P3 2
 '@BASEBOARD_FAB2_LIB.BASEBOARD_FAB2(SCH_1):PAGE170_I2@MSTR_DISCRETE.RES(CHIPS)':
 'B': CDS_PINID='B';
NODE_NAME     U8D3 4
 '@BASEBOARD_FAB2_LIB.BASEBOARD_FAB2(SCH_1):PAGE170_I4@MSTR_TTL.TTL1G07_A(CHIPS)':
 'Y': CDS_PINID='Y';
NODE_NAME     R2P4 1
 '@BASEBOARD_FAB2_LIB.BASEBOARD_FAB2(SCH_1):PAGE170_I74@MSTR_DISCRETE.RES(CHIPS)':
 'A': CDS_PINID='A';
NET_NAME
'IRQ_HFI0_CPU0_LVT2_N'
 '@BASEBOARD_FAB2_LIB.BASEBOARD_FAB2(SCH_1):IRQ_HFI0_CPU0_LVT2_N':
 C_SIGNAL='@baseboard_fab2_lib.baseboard_fab2(sch_1):irq_hfi0_cpu0_lvt2_n';
NODE_NAME     U5D1 BP19
 '@BASEBOARD_FAB2_LIB.BASEBOARD_FAB2(SCH_1):PAGE29_I61@CHPSET_LIB.SKX_EXT_B(CHIPS)':
 'CD_HFI0_INT_N': CDS_PINID='CD_HFI0_INT_N';
NODE_NAME     J8B1 8
 '@BASEBOARD_FAB2_LIB.BASEBOARD_FAB2(SCH_1):PAGE91_I1@MSTR_SCONN.SCONN24_H46321001(CHIPS)':
 'IO8': CDS_PINID='IO8';
NODE_NAME     R8B10 2
 '@BASEBOARD_FAB2_LIB.BASEBOARD_FAB2(SCH_1):PAGE91_I16@MSTR_DISCRETE.RES(CHIPS)':
 'B': CDS_PINID='B';
NET_NAME
'IRQ_HFI1_CPU0_LVT2_N'
 '@BASEBOARD_FAB2_LIB.BASEBOARD_FAB2(SCH_1):IRQ_HFI1_CPU0_LVT2_N':
 C_SIGNAL='@baseboard_fab2_lib.baseboard_fab2(sch_1):irq_hfi1_cpu0_lvt2_n';
NODE_NAME     U5D1 BM21
 '@BASEBOARD_FAB2_LIB.BASEBOARD_FAB2(SCH_1):PAGE29_I61@CHPSET_LIB.SKX_EXT_B(CHIPS)':
 'CD_HFI1_INT_N': CDS_PINID='CD_HFI1_INT_N';
NODE_NAME     J8B1 16
 '@BASEBOARD_FAB2_LIB.BASEBOARD_FAB2(SCH_1):PAGE91_I1@MSTR_SCONN.SCONN24_H46321001(CHIPS)':
 'IO16': CDS_PINID='IO16';
NODE_NAME     R8B17 2
 '@BASEBOARD_FAB2_LIB.BASEBOARD_FAB2(SCH_1):PAGE91_I18@MSTR_DISCRETE.RES(CHIPS)':
 'B': CDS_PINID='B';
NET_NAME
'IRQ_HSC_FAULT_N'
 '@BASEBOARD_FAB2_LIB.BASEBOARD_FAB2(SCH_1):IRQ_HSC_FAULT_N':
 C_SIGNAL='@baseboard_fab2_lib.baseboard_fab2(sch_1):irq_hsc_fault_n',
 PHYS_NET_NAME='IRQ_HSC_FAULT_N';
NODE_NAME     U7C1 BJ44
 '@BASEBOARD_FAB2_LIB.BASEBOARD_FAB2(SCH_1):PAGE119_I115@MSTR_U_PROC.LBG_CORE_QAT_EXT_D(CHIPS)':
 'GPP_D2': CDS_PINID='GPP_D2';
NODE_NAME     R2M4 2
 '@BASEBOARD_FAB2_LIB.BASEBOARD_FAB2(SCH_1):PAGE133_I284@MSTR_DISCRETE.RES(CHIPS)':
 'B': CDS_PINID='B';
NODE_NAME     R1D30 2
 '@BASEBOARD_FAB2_LIB.BASEBOARD_FAB2(SCH_1):PAGE199_I110@MSTR_DISCRETE.RES(CHIPS)':
 'B': CDS_PINID='B';
NODE_NAME     U25W4 N19
 '@BASEBOARD_FAB2_LIB.BASEBOARD_FAB2(SCH_1):PAGE146_I105@W_HDL.AST2520A1-GP-GP(CHIPS)':
 'GPIOAB0_VPODE_NOROE#': CDS_PINID='\gpioab0_vpode_noroe#\';
NET_NAME
'IRQ_HSC_FAULT_R_N'
 '@BASEBOARD_FAB2_LIB.BASEBOARD_FAB2(SCH_1):IRQ_HSC_FAULT_R_N':
 C_SIGNAL='@baseboard_fab2_lib.baseboard_fab2(sch_1):irq_hsc_fault_r_n';
NODE_NAME     EU1D2 6
 '@BASEBOARD_FAB2_LIB.BASEBOARD_FAB2(SCH_1):PAGE199_I10@MSTR_CONTROLLER.ADM1278(CHIPS)':
 'FAULT_N': CDS_PINID='FAULT_N';
NODE_NAME     R1D30 1
 '@BASEBOARD_FAB2_LIB.BASEBOARD_FAB2(SCH_1):PAGE199_I110@MSTR_DISCRETE.RES(CHIPS)':
 'A': CDS_PINID='A';
NET_NAME
'IRQ_LOM_ALERT_N'
 '@BASEBOARD_FAB2_LIB.BASEBOARD_FAB2(SCH_1):IRQ_LOM_ALERT_N':
 C_SIGNAL='@baseboard_fab2_lib.baseboard_fab2(sch_1):irq_lom_alert_n';
NODE_NAME     U7C1 BY47
 '@BASEBOARD_FAB2_LIB.BASEBOARD_FAB2(SCH_1):PAGE119_I115@MSTR_U_PROC.LBG_CORE_QAT_EXT_D(CHIPS)':
 'GPP_D11_SSATA_DEVSLP5': CDS_PINID='GPP_D11_SSATA_DEVSLP5';
NODE_NAME     EU9E1 35
 '@BASEBOARD_FAB2_LIB.BASEBOARD_FAB2(SCH_1):PAGE139_I72@MSTR_INTEL.SPRINGVILLE(CHIPS)':
 'SMB_ALRT_N': CDS_PINID='SMB_ALRT_N';
NODE_NAME     R9E7 2
 '@BASEBOARD_FAB2_LIB.BASEBOARD_FAB2(SCH_1):PAGE139_I193@MSTR_DISCRETE.RES(CHIPS)':
 'B': CDS_PINID='B';
NODE_NAME     U25W4 N18
 '@BASEBOARD_FAB2_LIB.BASEBOARD_FAB2(SCH_1):PAGE146_I104@W_HDL.AST2520A1-GP-GP(CHIPS)':
 'GPIOAA6_VPOR8_NORD6_SALT13': CDS_PINID='GPIOAA6_VPOR8_NORD6_SALT13';
NET_NAME
'IRQ_LPC_SERIRQ_N'
 '@BASEBOARD_FAB2_LIB.BASEBOARD_FAB2(SCH_1):IRQ_LPC_SERIRQ_N':
 C_SIGNAL='@baseboard_fab2_lib.baseboard_fab2(sch_1):irq_lpc_serirq_n';
NODE_NAME     U7C1 P2
 '@BASEBOARD_FAB2_LIB.BASEBOARD_FAB2(SCH_1):PAGE119_I115@MSTR_U_PROC.LBG_CORE_QAT_EXT_D(CHIPS)':
 'GPP_A6_SERIRQ_ESPI_CS1_N': CDS_PINID='GPP_A6_SERIRQ_ESPI_CS1_N';
NODE_NAME     R7D3 2
 '@BASEBOARD_FAB2_LIB.BASEBOARD_FAB2(SCH_1):PAGE133_I243@MSTR_DISCRETE.RES(CHIPS)':
 'B': CDS_PINID='B';
NODE_NAME     R25W73 1
 '@BASEBOARD_FAB2_LIB.BASEBOARD_FAB2(SCH_1):PAGE146_I73@MSTR_DISCRETE.RES(CHIPS)':
 'A': CDS_PINID='A';
NET_NAME
'IRQ_LPC_SERIRQ_R'
 '@BASEBOARD_FAB2_LIB.BASEBOARD_FAB2(SCH_1):IRQ_LPC_SERIRQ_R':
 C_SIGNAL='@baseboard_fab2_lib.baseboard_fab2(sch_1):irq_lpc_serirq_r';
NODE_NAME     R25W73 2
 '@BASEBOARD_FAB2_LIB.BASEBOARD_FAB2(SCH_1):PAGE146_I73@MSTR_DISCRETE.RES(CHIPS)':
 'B': CDS_PINID='B';
NODE_NAME     U25W4 F22
 '@BASEBOARD_FAB2_LIB.BASEBOARD_FAB2(SCH_1):PAGE146_I105@W_HDL.AST2520A1-GP-GP(CHIPS)':
 'GPIOAC6_ESPIALT#_LSIRQ#': CDS_PINID='\gpioac6_espialt#_lsirq#\';
NET_NAME
'IRQ_LVC3_WAKE_N'
 '@BASEBOARD_FAB2_LIB.BASEBOARD_FAB2(SCH_1):IRQ_LVC3_WAKE_N':
 C_SIGNAL='@baseboard_fab2_lib.baseboard_fab2(sch_1):irq_lvc3_wake_n';
NODE_NAME     R3N13 2
 '@BASEBOARD_FAB2_LIB.BASEBOARD_FAB2(SCH_1):PAGE118_I71@MSTR_DISCRETE.RES(CHIPS)':
 'B': CDS_PINID='B';
NODE_NAME     U7C1 K9
 '@BASEBOARD_FAB2_LIB.BASEBOARD_FAB2(SCH_1):PAGE118_I73@MSTR_U_PROC.LBG_CORE_QAT_EXT_D(CHIPS)':
 'WAKE_N': CDS_PINID='WAKE_N';
NODE_NAME     R8E17 2
 '@BASEBOARD_FAB2_LIB.BASEBOARD_FAB2(SCH_1):PAGE142_I2@MSTR_DISCRETE.RES(CHIPS)':
 'B': CDS_PINID='B';
NET_NAME
'IRQ_LVC3_WAKE_R_N'
 '@BASEBOARD_FAB2_LIB.BASEBOARD_FAB2(SCH_1):IRQ_LVC3_WAKE_R_N':
 C_SIGNAL='@baseboard_fab2_lib.baseboard_fab2(sch_1):irq_lvc3_wake_r_n';
NODE_NAME     U8E4 4
 '@BASEBOARD_FAB2_LIB.BASEBOARD_FAB2(SCH_1):PAGE142_I1@MSTR_TTL.TTL1G126_A(CHIPS)':
 'Y': CDS_PINID='Y';
NODE_NAME     R8E17 1
 '@BASEBOARD_FAB2_LIB.BASEBOARD_FAB2(SCH_1):PAGE142_I2@MSTR_DISCRETE.RES(CHIPS)':
 'A': CDS_PINID='A';
NET_NAME
'IRQ_MEZZ_LAN_ALERT_N'
 '@BASEBOARD_FAB2_LIB.BASEBOARD_FAB2(SCH_1):IRQ_MEZZ_LAN_ALERT_N':
 C_SIGNAL='@baseboard_fab2_lib.baseboard_fab2(sch_1):irq_mezz_lan_alert_n',
 PHYS_NET_NAME='IRQ_MEZZ_LAN_ALERT_N';
NODE_NAME     U7C1 BW45
 '@BASEBOARD_FAB2_LIB.BASEBOARD_FAB2(SCH_1):PAGE119_I115@MSTR_U_PROC.LBG_CORE_QAT_EXT_D(CHIPS)':
 'GPP_D3': CDS_PINID='GPP_D3';
NODE_NAME     R8F23 2
 '@BASEBOARD_FAB2_LIB.BASEBOARD_FAB2(SCH_1):PAGE157_I296@MSTR_DISCRETE.RES(CHIPS)':
 'B': CDS_PINID='B';
NODE_NAME     J9B3 28
 '@BASEBOARD_FAB2_LIB.BASEBOARD_FAB2(SCH_1):PAGE186_I336@MSTR_SCONN.SCONN120_A28699018(CHIPS)':
 'IO28': CDS_PINID='IO28';
NODE_NAME     U25W4 D15
 '@BASEBOARD_FAB2_LIB.BASEBOARD_FAB2(SCH_1):PAGE145_I117@W_HDL.AST2520A1-GP-GP(CHIPS)':
 'GPIOG6_SGPS2I0_SALT3': CDS_PINID='GPIOG6_SGPS2I0_SALT3';
NODE_NAME     U32W2 7
 '@BASEBOARD_FAB2_LIB.BASEBOARD_FAB2(SCH_1):PAGE185_I204@W_HDL.TCA9517DGKR-GP(CHIPS)':
 'SCLB': CDS_PINID='SCLB';
NET_NAME
'IRQ_OC_DETECT_N'
 '@BASEBOARD_FAB2_LIB.BASEBOARD_FAB2(SCH_1):IRQ_OC_DETECT_N':
 C_SIGNAL='@baseboard_fab2_lib.baseboard_fab2(sch_1):irq_oc_detect_n';
NODE_NAME     U7C1 AG7
 '@BASEBOARD_FAB2_LIB.BASEBOARD_FAB2(SCH_1):PAGE120_I147@MSTR_U_PROC.LBG_CORE_QAT_EXT_D(CHIPS)':
 'GPP_F0_SATAXPCIE3_SATAGP3': CDS_PINID='GPP_F0_SATAXPCIE3_SATAGP3';
NODE_NAME     U1D1 2
 '@BASEBOARD_FAB2_LIB.BASEBOARD_FAB2(SCH_1):PAGE200_I103@MSTR_TTL.TTL1G126_A(CHIPS)':
 'A': CDS_PINID='A';
NODE_NAME     U1D2 1
 '@BASEBOARD_FAB2_LIB.BASEBOARD_FAB2(SCH_1):PAGE200_I170@MSTR_VREG.TPS3700(CHIPS)':
 'OUTB': CDS_PINID='OUTB';
NODE_NAME     R1D23 2
 '@BASEBOARD_FAB2_LIB.BASEBOARD_FAB2(SCH_1):PAGE200_I191@MSTR_DISCRETE.RES(CHIPS)':
 'B': CDS_PINID='B';
NODE_NAME     U25W4 T1
 '@BASEBOARD_FAB2_LIB.BASEBOARD_FAB2(SCH_1):PAGE145_I117@W_HDL.AST2520A1-GP-GP(CHIPS)':
 'GPIOL1_NDCD1_VPIDE': CDS_PINID='GPIOL1_NDCD1_VPIDE';
NODE_NAME     R9P15 2
 '@BASEBOARD_FAB2_LIB.BASEBOARD_FAB2(SCH_1):PAGE200_I243@MSTR_DISCRETE.RES(CHIPS)':
 'B': CDS_PINID='B';
NET_NAME
'IRQ_OOB_MGMT_RISER_ALERT_N'
 '@BASEBOARD_FAB2_LIB.BASEBOARD_FAB2(SCH_1):IRQ_OOB_MGMT_RISER_ALERT_N':
 C_SIGNAL='@baseboard_fab2_lib.baseboard_fab2(sch_1):irq_oob_mgmt_riser_alert_n';
NODE_NAME     J8G1 16
 '@BASEBOARD_FAB2_LIB.BASEBOARD_FAB2(SCH_1):PAGE108_I258@MSTR_SCONN.SCONN200_H68296001(CHIPS)':
 'IO16': CDS_PINID='IO16';
NODE_NAME     U7C1 BV42
 '@BASEBOARD_FAB2_LIB.BASEBOARD_FAB2(SCH_1):PAGE119_I115@MSTR_U_PROC.LBG_CORE_QAT_EXT_D(CHIPS)':
 'GPP_D16_SML0BALERT_IE_N': CDS_PINID='GPP_D16_SML0BALERT_IE_N';
NODE_NAME     R2T29 2
 '@BASEBOARD_FAB2_LIB.BASEBOARD_FAB2(SCH_1):PAGE157_I298@MSTR_DISCRETE.RES(CHIPS)':
 'B': CDS_PINID='B';
NODE_NAME     U25W4 D16
 '@BASEBOARD_FAB2_LIB.BASEBOARD_FAB2(SCH_1):PAGE145_I117@W_HDL.AST2520A1-GP-GP(CHIPS)':
 'GPIOG5_SGPS2LD_SALT2': CDS_PINID='GPIOG5_SGPS2LD_SALT2';
NET_NAME
'IRQ_PCH_NIC_ALERT_N'
 '@BASEBOARD_FAB2_LIB.BASEBOARD_FAB2(SCH_1):IRQ_PCH_NIC_ALERT_N':
 C_SIGNAL='@baseboard_fab2_lib.baseboard_fab2(sch_1):irq_pch_nic_alert_n';
NODE_NAME     U7C1 BG22
 '@BASEBOARD_FAB2_LIB.BASEBOARD_FAB2(SCH_1):PAGE119_I115@MSTR_U_PROC.LBG_CORE_QAT_EXT_D(CHIPS)':
 'GPP_B16': CDS_PINID='GPP_B16';
NODE_NAME     U7C1 AR17
 '@BASEBOARD_FAB2_LIB.BASEBOARD_FAB2(SCH_1):PAGE120_I147@MSTR_U_PROC.LBG_CORE_QAT_EXT_D(CHIPS)':
 'GPP_F21_LAN_SMBALRT_N': CDS_PINID='GPP_F21_LAN_SMBALRT_N';
NODE_NAME     R8C25 2
 '@BASEBOARD_FAB2_LIB.BASEBOARD_FAB2(SCH_1):PAGE133_I333@MSTR_DISCRETE.RES(CHIPS)':
 'B': CDS_PINID='B';
NODE_NAME     U25W4 E17
 '@BASEBOARD_FAB2_LIB.BASEBOARD_FAB2(SCH_1):PAGE145_I117@W_HDL.AST2520A1-GP-GP(CHIPS)':
 'GPIOG4_SGPS2CK_SALT1': CDS_PINID='GPIOG4_SGPS2CK_SALT1';
NET_NAME
'IRQ_PIRQA_SPI_TPM_N'
 '@BASEBOARD_FAB2_LIB.BASEBOARD_FAB2(SCH_1):IRQ_PIRQA_SPI_TPM_N':
 C_SIGNAL='@baseboard_fab2_lib.baseboard_fab2(sch_1):irq_pirqa_spi_tpm_n';
NODE_NAME     U7C1 AA2
 '@BASEBOARD_FAB2_LIB.BASEBOARD_FAB2(SCH_1):PAGE119_I115@MSTR_U_PROC.LBG_CORE_QAT_EXT_D(CHIPS)':
 'GPP_A7_PIRQA_N_ESPI_ALERT0_N': CDS_PINID='GPP_A7_PIRQA_N_ESPI_ALERT0_N';
NODE_NAME     R7D7 2
 '@BASEBOARD_FAB2_LIB.BASEBOARD_FAB2(SCH_1):PAGE133_I331@MSTR_DISCRETE.RES(CHIPS)':
 'B': CDS_PINID='B';
NODE_NAME     R8E1 2
 '@BASEBOARD_FAB2_LIB.BASEBOARD_FAB2(SCH_1):PAGE184_I99@MSTR_DISCRETE.RES(CHIPS)':
 'B': CDS_PINID='B';
NET_NAME
'IRQ_PVCCIN_CPU0_VRHOT_LVC3_N'
 '@BASEBOARD_FAB2_LIB.BASEBOARD_FAB2(SCH_1):IRQ_PVCCIN_CPU0_VRHOT_LVC3_N':
 C_SIGNAL='@baseboard_fab2_lib.baseboard_fab2(sch_1):irq_pvccin_cpu0_vrhot_lvc3_~
n';
NODE_NAME     U7E2 2
 '@BASEBOARD_FAB2_LIB.BASEBOARD_FAB2(SCH_1):PAGE95_I117@MSTR_TTL.TTL1G08(CHIPS)':
 'B'<0>: CDS_PINID='B(0)';
NODE_NAME     R6P45 2
 '@BASEBOARD_FAB2_LIB.BASEBOARD_FAB2(SCH_1):PAGE201_I128@MSTR_DISCRETE.RES(CHIPS)':
 'B': CDS_PINID='B';
NODE_NAME     U25W4 B22
 '@BASEBOARD_FAB2_LIB.BASEBOARD_FAB2(SCH_1):PAGE145_I117@W_HDL.AST2520A1-GP-GP(CHIPS)':
 'GPIOF2_NDSR4_LHAD2': CDS_PINID='GPIOF2_NDSR4_LHAD2';
NET_NAME
'IRQ_PVCCIN_CPU0_VRHOT_LVC3_R_N'
 '@BASEBOARD_FAB2_LIB.BASEBOARD_FAB2(SCH_1):IRQ_PVCCIN_CPU0_VRHOT_LVC3_R_N':
 C_SIGNAL='@baseboard_fab2_lib.baseboard_fab2(sch_1):irq_pvccin_cpu0_vrhot_lvc3_~
r_n';
NODE_NAME     R4E3 2
 '@BASEBOARD_FAB2_LIB.BASEBOARD_FAB2(SCH_1):PAGE201_I111@MSTR_DISCRETE.RES(CHIPS)':
 'B': CDS_PINID='B';
NODE_NAME     R6P45 1
 '@BASEBOARD_FAB2_LIB.BASEBOARD_FAB2(SCH_1):PAGE201_I128@MSTR_DISCRETE.RES(CHIPS)':
 'A': CDS_PINID='A';
NODE_NAME     EU4D4 13
 '@BASEBOARD_FAB2_LIB.BASEBOARD_FAB2(SCH_1):PAGE201_I155@MSTR_CONTROLLER.PXE1610B(CHIPS)':
 'VRHOT_N': CDS_PINID='VRHOT_N';
NET_NAME
'IRQ_PVCCIN_CPU1_VRHOT_LVC3_N'
 '@BASEBOARD_FAB2_LIB.BASEBOARD_FAB2(SCH_1):IRQ_PVCCIN_CPU1_VRHOT_LVC3_N':
 C_SIGNAL='@baseboard_fab2_lib.baseboard_fab2(sch_1):irq_pvccin_cpu1_vrhot_lvc3_~
n';
NODE_NAME     U7E3 2
 '@BASEBOARD_FAB2_LIB.BASEBOARD_FAB2(SCH_1):PAGE95_I118@MSTR_TTL.TTL1G08(CHIPS)':
 'B'<0>: CDS_PINID='B(0)';
NODE_NAME     R9P3 2
 '@BASEBOARD_FAB2_LIB.BASEBOARD_FAB2(SCH_1):PAGE206_I117@MSTR_DISCRETE.RES(CHIPS)':
 'B': CDS_PINID='B';
NODE_NAME     U25W4 B21
 '@BASEBOARD_FAB2_LIB.BASEBOARD_FAB2(SCH_1):PAGE145_I117@W_HDL.AST2520A1-GP-GP(CHIPS)':
 'GPIOF3_NRI4_LHAD3': CDS_PINID='GPIOF3_NRI4_LHAD3';
NET_NAME
'IRQ_PVCCIN_CPU1_VRHOT_LVC3_R_N'
 '@BASEBOARD_FAB2_LIB.BASEBOARD_FAB2(SCH_1):IRQ_PVCCIN_CPU1_VRHOT_LVC3_R_N':
 C_SIGNAL='@baseboard_fab2_lib.baseboard_fab2(sch_1):irq_pvccin_cpu1_vrhot_lvc3_~
r_n';
NODE_NAME     R1D6 2
 '@BASEBOARD_FAB2_LIB.BASEBOARD_FAB2(SCH_1):PAGE206_I6@MSTR_DISCRETE.RES(CHIPS)':
 'B': CDS_PINID='B';
NODE_NAME     R9P3 1
 '@BASEBOARD_FAB2_LIB.BASEBOARD_FAB2(SCH_1):PAGE206_I117@MSTR_DISCRETE.RES(CHIPS)':
 'A': CDS_PINID='A';
NODE_NAME     EU1C2 13
 '@BASEBOARD_FAB2_LIB.BASEBOARD_FAB2(SCH_1):PAGE206_I130@MSTR_CONTROLLER.PXE1610B(CHIPS)':
 'VRHOT_N': CDS_PINID='VRHOT_N';
NET_NAME
'IRQ_PVCCIO_CPU0_VRHOT_N'
 '@BASEBOARD_FAB2_LIB.BASEBOARD_FAB2(SCH_1):IRQ_PVCCIO_CPU0_VRHOT_N':
 C_SIGNAL='@baseboard_fab2_lib.baseboard_fab2(sch_1):irq_pvccio_cpu0_vrhot_n';
NODE_NAME     R3P18 2
 '@BASEBOARD_FAB2_LIB.BASEBOARD_FAB2(SCH_1):PAGE211_I64@MSTR_DISCRETE.RES(CHIPS)':
 'B': CDS_PINID='B';
NODE_NAME     EU3P1 11
 '@BASEBOARD_FAB2_LIB.BASEBOARD_FAB2(SCH_1):PAGE211_I93@MSTR_CONTROLLER.PXE1110B(CHIPS)':
 'VRHOT_N': CDS_PINID='VRHOT_N';
NET_NAME
'IRQ_PVCCIO_CPU1_VRHOT_N'
 '@BASEBOARD_FAB2_LIB.BASEBOARD_FAB2(SCH_1):IRQ_PVCCIO_CPU1_VRHOT_N':
 C_SIGNAL='@baseboard_fab2_lib.baseboard_fab2(sch_1):irq_pvccio_cpu1_vrhot_n';
NODE_NAME     R4D49 2
 '@BASEBOARD_FAB2_LIB.BASEBOARD_FAB2(SCH_1):PAGE213_I63@MSTR_DISCRETE.RES(CHIPS)':
 'B': CDS_PINID='B';
NODE_NAME     EU4D5 11
 '@BASEBOARD_FAB2_LIB.BASEBOARD_FAB2(SCH_1):PAGE213_I96@MSTR_CONTROLLER.PXE1110B(CHIPS)':
 'VRHOT_N': CDS_PINID='VRHOT_N';
NET_NAME
'IRQ_PVDDQ_ABC_VRHOT_LVT3_N'
 '@BASEBOARD_FAB2_LIB.BASEBOARD_FAB2(SCH_1):IRQ_PVDDQ_ABC_VRHOT_LVT3_N':
 C_SIGNAL='@baseboard_fab2_lib.baseboard_fab2(sch_1):irq_pvddq_abc_vrhot_lvt3_n';
NODE_NAME     Q3U1 2
 '@BASEBOARD_FAB2_LIB.BASEBOARD_FAB2(SCH_1):PAGE94_I49@MSTR_DISCRETE.FET_N_DUAL(CHIPS)':
 'GATE'<0>: CDS_PINID='GATE(0)';
NODE_NAME     U7C1 BN7
 '@BASEBOARD_FAB2_LIB.BASEBOARD_FAB2(SCH_1):PAGE119_I115@MSTR_U_PROC.LBG_CORE_QAT_EXT_D(CHIPS)':
 'GPP_B4_CPU_GP3': CDS_PINID='GPP_B4_CPU_GP3';
NODE_NAME     U25W4 J19
 '@BASEBOARD_FAB2_LIB.BASEBOARD_FAB2(SCH_1):PAGE145_I117@W_HDL.AST2520A1-GP-GP(CHIPS)':
 'GPIOF0_NCTS4_LHAD0': CDS_PINID='GPIOF0_NCTS4_LHAD0';
NODE_NAME     R7F23 2
 '@BASEBOARD_FAB2_LIB.BASEBOARD_FAB2(SCH_1):PAGE215_I53@MSTR_DISCRETE.RES(CHIPS)':
 'B': CDS_PINID='B';
NET_NAME
'IRQ_PVDDQ_ABC_VRHOT_LVT3_R_N'
 '@BASEBOARD_FAB2_LIB.BASEBOARD_FAB2(SCH_1):IRQ_PVDDQ_ABC_VRHOT_LVT3_R_N':
 C_SIGNAL='@baseboard_fab2_lib.baseboard_fab2(sch_1):irq_pvddq_abc_vrhot_lvt3_r_~
n';
NODE_NAME     R7F27 2
 '@BASEBOARD_FAB2_LIB.BASEBOARD_FAB2(SCH_1):PAGE215_I50@MSTR_DISCRETE.RES(CHIPS)':
 'B': CDS_PINID='B';
NODE_NAME     R7F23 1
 '@BASEBOARD_FAB2_LIB.BASEBOARD_FAB2(SCH_1):PAGE215_I53@MSTR_DISCRETE.RES(CHIPS)':
 'A': CDS_PINID='A';
NODE_NAME     EU7G1 11
 '@BASEBOARD_FAB2_LIB.BASEBOARD_FAB2(SCH_1):PAGE215_I69@MSTR_CONTROLLER.PXM1310B(CHIPS)':
 'VRHOT_N': CDS_PINID='VRHOT_N';
NET_NAME
'IRQ_PVDDQ_DEF_VRHOT_LVT3_N'
 '@BASEBOARD_FAB2_LIB.BASEBOARD_FAB2(SCH_1):IRQ_PVDDQ_DEF_VRHOT_LVT3_N':
 C_SIGNAL='@baseboard_fab2_lib.baseboard_fab2(sch_1):irq_pvddq_def_vrhot_lvt3_n';
NODE_NAME     Q7E1 2
 '@BASEBOARD_FAB2_LIB.BASEBOARD_FAB2(SCH_1):PAGE94_I60@MSTR_DISCRETE.FET_N_DUAL(CHIPS)':
 'GATE'<0>: CDS_PINID='GATE(0)';
NODE_NAME     U7C1 BK17
 '@BASEBOARD_FAB2_LIB.BASEBOARD_FAB2(SCH_1):PAGE119_I115@MSTR_U_PROC.LBG_CORE_QAT_EXT_D(CHIPS)':
 'GPP_B5_SRCCLKREQ0_N': CDS_PINID='GPP_B5_SRCCLKREQ0_N';
NODE_NAME     R7B1 2
 '@BASEBOARD_FAB2_LIB.BASEBOARD_FAB2(SCH_1):PAGE218_I59@MSTR_DISCRETE.RES(CHIPS)':
 'B': CDS_PINID='B';
NODE_NAME     U25W4 AB21
 '@BASEBOARD_FAB2_LIB.BASEBOARD_FAB2(SCH_1):PAGE146_I104@W_HDL.AST2520A1-GP-GP(CHIPS)':
 'GPIOZ2_VPOG4_NORA2_SIOPBO#': CDS_PINID='\gpioz2_vpog4_nora2_siopbo#\';
NET_NAME
'IRQ_PVDDQ_DEF_VRHOT_LVT3_R_N'
 '@BASEBOARD_FAB2_LIB.BASEBOARD_FAB2(SCH_1):IRQ_PVDDQ_DEF_VRHOT_LVT3_R_N':
 C_SIGNAL='@baseboard_fab2_lib.baseboard_fab2(sch_1):irq_pvddq_def_vrhot_lvt3_r_~
n';
NODE_NAME     R7B1 1
 '@BASEBOARD_FAB2_LIB.BASEBOARD_FAB2(SCH_1):PAGE218_I59@MSTR_DISCRETE.RES(CHIPS)':
 'A': CDS_PINID='A';
NODE_NAME     R7B4 2
 '@BASEBOARD_FAB2_LIB.BASEBOARD_FAB2(SCH_1):PAGE218_I57@MSTR_DISCRETE.RES(CHIPS)':
 'B': CDS_PINID='B';
NODE_NAME     EU7A5 11
 '@BASEBOARD_FAB2_LIB.BASEBOARD_FAB2(SCH_1):PAGE218_I69@MSTR_CONTROLLER.PXM1310B(CHIPS)':
 'VRHOT_N': CDS_PINID='VRHOT_N';
NET_NAME
'IRQ_PVDDQ_GHJ_VRHOT_LVT3_N'
 '@BASEBOARD_FAB2_LIB.BASEBOARD_FAB2(SCH_1):IRQ_PVDDQ_GHJ_VRHOT_LVT3_N':
 C_SIGNAL='@baseboard_fab2_lib.baseboard_fab2(sch_1):irq_pvddq_ghj_vrhot_lvt3_n';
NODE_NAME     Q7E2 2
 '@BASEBOARD_FAB2_LIB.BASEBOARD_FAB2(SCH_1):PAGE94_I69@MSTR_DISCRETE.FET_N_DUAL(CHIPS)':
 'GATE'<0>: CDS_PINID='GATE(0)';
NODE_NAME     U7C1 BG18
 '@BASEBOARD_FAB2_LIB.BASEBOARD_FAB2(SCH_1):PAGE119_I115@MSTR_U_PROC.LBG_CORE_QAT_EXT_D(CHIPS)':
 'GPP_B6_SRCCLKREQ1_N': CDS_PINID='GPP_B6_SRCCLKREQ1_N';
NODE_NAME     U25W4 H20
 '@BASEBOARD_FAB2_LIB.BASEBOARD_FAB2(SCH_1):PAGE144_I95@W_HDL.AST2520A1-GP-GP(CHIPS)':
 'GPIOB7': CDS_PINID='GPIOB7';
NODE_NAME     R1G8 2
 '@BASEBOARD_FAB2_LIB.BASEBOARD_FAB2(SCH_1):PAGE223_I55@MSTR_DISCRETE.RES(CHIPS)':
 'B': CDS_PINID='B';
NET_NAME
'IRQ_PVDDQ_GHJ_VRHOT_LVT3_R_N'
 '@BASEBOARD_FAB2_LIB.BASEBOARD_FAB2(SCH_1):IRQ_PVDDQ_GHJ_VRHOT_LVT3_R_N':
 C_SIGNAL='@baseboard_fab2_lib.baseboard_fab2(sch_1):irq_pvddq_ghj_vrhot_lvt3_r_~
n';
NODE_NAME     R1G11 2
 '@BASEBOARD_FAB2_LIB.BASEBOARD_FAB2(SCH_1):PAGE223_I49@MSTR_DISCRETE.RES(CHIPS)':
 'B': CDS_PINID='B';
NODE_NAME     R1G8 1
 '@BASEBOARD_FAB2_LIB.BASEBOARD_FAB2(SCH_1):PAGE223_I55@MSTR_DISCRETE.RES(CHIPS)':
 'A': CDS_PINID='A';
NODE_NAME     EU1G2 11
 '@BASEBOARD_FAB2_LIB.BASEBOARD_FAB2(SCH_1):PAGE223_I69@MSTR_CONTROLLER.PXM1310B(CHIPS)':
 'VRHOT_N': CDS_PINID='VRHOT_N';
NET_NAME
'IRQ_PVDDQ_KLM_VRHOT_LVT3_N'
 '@BASEBOARD_FAB2_LIB.BASEBOARD_FAB2(SCH_1):IRQ_PVDDQ_KLM_VRHOT_LVT3_N':
 C_SIGNAL='@baseboard_fab2_lib.baseboard_fab2(sch_1):irq_pvddq_klm_vrhot_lvt3_n';
NODE_NAME     Q4B1 2
 '@BASEBOARD_FAB2_LIB.BASEBOARD_FAB2(SCH_1):PAGE94_I84@MSTR_DISCRETE.FET_N_DUAL(CHIPS)':
 'GATE'<0>: CDS_PINID='GATE(0)';
NODE_NAME     U7C1 BR13
 '@BASEBOARD_FAB2_LIB.BASEBOARD_FAB2(SCH_1):PAGE119_I115@MSTR_U_PROC.LBG_CORE_QAT_EXT_D(CHIPS)':
 'GPP_B7_SRCCLKREQ2_N': CDS_PINID='GPP_B7_SRCCLKREQ2_N';
NODE_NAME     U25W4 A21
 '@BASEBOARD_FAB2_LIB.BASEBOARD_FAB2(SCH_1):PAGE145_I117@W_HDL.AST2520A1-GP-GP(CHIPS)':
 'GPIOF4_NDTR4_LHCLK': CDS_PINID='GPIOF4_NDTR4_LHCLK';
NODE_NAME     R1B4 2
 '@BASEBOARD_FAB2_LIB.BASEBOARD_FAB2(SCH_1):PAGE226_I54@MSTR_DISCRETE.RES(CHIPS)':
 'B': CDS_PINID='B';
NET_NAME
'IRQ_PVDDQ_KLM_VRHOT_LVT3_R_N'
 '@BASEBOARD_FAB2_LIB.BASEBOARD_FAB2(SCH_1):IRQ_PVDDQ_KLM_VRHOT_LVT3_R_N':
 C_SIGNAL='@baseboard_fab2_lib.baseboard_fab2(sch_1):irq_pvddq_klm_vrhot_lvt3_r_~
n';
NODE_NAME     R1B1 2
 '@BASEBOARD_FAB2_LIB.BASEBOARD_FAB2(SCH_1):PAGE226_I49@MSTR_DISCRETE.RES(CHIPS)':
 'B': CDS_PINID='B';
NODE_NAME     R1B4 1
 '@BASEBOARD_FAB2_LIB.BASEBOARD_FAB2(SCH_1):PAGE226_I54@MSTR_DISCRETE.RES(CHIPS)':
 'A': CDS_PINID='A';
NODE_NAME     EU1B1 11
 '@BASEBOARD_FAB2_LIB.BASEBOARD_FAB2(SCH_1):PAGE226_I69@MSTR_CONTROLLER.PXM1310B(CHIPS)':
 'VRHOT_N': CDS_PINID='VRHOT_N';
NET_NAME
'IRQ_PVNN_PCH_VRHOT_N'
 '@BASEBOARD_FAB2_LIB.BASEBOARD_FAB2(SCH_1):IRQ_PVNN_PCH_VRHOT_N':
 C_SIGNAL='@baseboard_fab2_lib.baseboard_fab2(sch_1):irq_pvnn_pch_vrhot_n';
NODE_NAME     R8A5 2
 '@BASEBOARD_FAB2_LIB.BASEBOARD_FAB2(SCH_1):PAGE235_I216@MSTR_DISCRETE.RES(CHIPS)':
 'B': CDS_PINID='B';
NODE_NAME     EU8A1 11
 '@BASEBOARD_FAB2_LIB.BASEBOARD_FAB2(SCH_1):PAGE235_I229@MSTR_CONTROLLER.PXE1110B(CHIPS)':
 'VRHOT_N': CDS_PINID='VRHOT_N';
NET_NAME
'IRQ_SML0_ALERT_N'
 '@BASEBOARD_FAB2_LIB.BASEBOARD_FAB2(SCH_1):IRQ_SML0_ALERT_N':
 C_SIGNAL='@baseboard_fab2_lib.baseboard_fab2(sch_1):irq_sml0_alert_n';
NODE_NAME     U7C1 BW34
 '@BASEBOARD_FAB2_LIB.BASEBOARD_FAB2(SCH_1):PAGE119_I115@MSTR_U_PROC.LBG_CORE_QAT_EXT_D(CHIPS)':
 'GPP_C5_SML0ALERT_IE_N': CDS_PINID='GPP_C5_SML0ALERT_IE_N';
NODE_NAME     Q8E2 3
 '@BASEBOARD_FAB2_LIB.BASEBOARD_FAB2(SCH_1):PAGE126_I13@MSTR_DISCRETE.FET_N(CHIPS)':
 'DRN': CDS_PINID='DRN';
NODE_NAME     R8C9 2
 '@BASEBOARD_FAB2_LIB.BASEBOARD_FAB2(SCH_1):PAGE126_I20@MSTR_DISCRETE.RES(CHIPS)':
 'B': CDS_PINID='B';
NODE_NAME     U25W4 R18
 '@BASEBOARD_FAB2_LIB.BASEBOARD_FAB2(SCH_1):PAGE146_I104@W_HDL.AST2520A1-GP-GP(CHIPS)':
 'GPIOS2_VPOB4_SALT5': CDS_PINID='GPIOS2_VPOB4_SALT5';
NET_NAME
'IRQ_SML1_PMBUS_ALERT_BUF_N'
 '@BASEBOARD_FAB2_LIB.BASEBOARD_FAB2(SCH_1):IRQ_SML1_PMBUS_ALERT_BUF_N':
 C_SIGNAL='@baseboard_fab2_lib.baseboard_fab2(sch_1):irq_sml1_pmbus_alert_buf_n';
NODE_NAME     U8D3 2
 '@BASEBOARD_FAB2_LIB.BASEBOARD_FAB2(SCH_1):PAGE170_I4@MSTR_TTL.TTL1G07_A(CHIPS)':
 'A': CDS_PINID='A';
NODE_NAME     U8D5 4
 '@BASEBOARD_FAB2_LIB.BASEBOARD_FAB2(SCH_1):PAGE170_I38@MSTR_TTL.TTL1G126_A(CHIPS)':
 'Y': CDS_PINID='Y';
NODE_NAME     R8D26 2
 '@BASEBOARD_FAB2_LIB.BASEBOARD_FAB2(SCH_1):PAGE170_I71@MSTR_DISCRETE.RES(CHIPS)':
 'B': CDS_PINID='B';
NET_NAME
'IRQ_SML1_PMBUS_ALERT_N'
 '@BASEBOARD_FAB2_LIB.BASEBOARD_FAB2(SCH_1):IRQ_SML1_PMBUS_ALERT_N':
 C_SIGNAL='@baseboard_fab2_lib.baseboard_fab2(sch_1):irq_sml1_pmbus_alert_n';
NODE_NAME     U8D5 2
 '@BASEBOARD_FAB2_LIB.BASEBOARD_FAB2(SCH_1):PAGE170_I38@MSTR_TTL.TTL1G126_A(CHIPS)':
 'A': CDS_PINID='A';
NODE_NAME     C8D3 1
 '@BASEBOARD_FAB2_LIB.BASEBOARD_FAB2(SCH_1):PAGE170_I42@MSTR_DISCRETE.CAP(CHIPS)':
 'A': CDS_PINID='A';
NODE_NAME     R1D26 2
 '@BASEBOARD_FAB2_LIB.BASEBOARD_FAB2(SCH_1):PAGE199_I109@MSTR_DISCRETE.RES(CHIPS)':
 'B': CDS_PINID='B';
NODE_NAME     U25W4 V21
 '@BASEBOARD_FAB2_LIB.BASEBOARD_FAB2(SCH_1):PAGE146_I104@W_HDL.AST2520A1-GP-GP(CHIPS)':
 'GPIOAA1_VPOR3_NORD1_SALT8': CDS_PINID='GPIOAA1_VPOR3_NORD1_SALT8';
NODE_NAME     R2P8 2
 '@BASEBOARD_FAB2_LIB.BASEBOARD_FAB2(SCH_1):PAGE170_I75@MSTR_DISCRETE.RES(CHIPS)':
 'B': CDS_PINID='B';
NODE_NAME     R7W18 1
 '@BASEBOARD_FAB2_LIB.BASEBOARD_FAB2(SCH_1):PAGE120_I277@MSTR_DISCRETE.RES(CHIPS)':
 'A': CDS_PINID='A';
NET_NAME
'IRQ_SML1_PMBUS_ALERT_R1_N'
 '@BASEBOARD_FAB2_LIB.BASEBOARD_FAB2(SCH_1):IRQ_SML1_PMBUS_ALERT_R1_N':
 C_SIGNAL='@baseboard_fab2_lib.baseboard_fab2(sch_1):irq_sml1_pmbus_alert_r1_n';
NODE_NAME     U7C1 AP7
 '@BASEBOARD_FAB2_LIB.BASEBOARD_FAB2(SCH_1):PAGE120_I147@MSTR_U_PROC.LBG_CORE_QAT_EXT_D(CHIPS)':
 'GPP_F12_SATA_SDATAOUT1': CDS_PINID='GPP_F12_SATA_SDATAOUT1';
NODE_NAME     R7W18 2
 '@BASEBOARD_FAB2_LIB.BASEBOARD_FAB2(SCH_1):PAGE120_I277@MSTR_DISCRETE.RES(CHIPS)':
 'B': CDS_PINID='B';
NET_NAME
'IRQ_SML1_PMBUS_ALERT_R_N'
 '@BASEBOARD_FAB2_LIB.BASEBOARD_FAB2(SCH_1):IRQ_SML1_PMBUS_ALERT_R_N':
 C_SIGNAL='@baseboard_fab2_lib.baseboard_fab2(sch_1):irq_sml1_pmbus_alert_r_n';
NODE_NAME     EU1D2 13
 '@BASEBOARD_FAB2_LIB.BASEBOARD_FAB2(SCH_1):PAGE199_I10@MSTR_CONTROLLER.ADM1278(CHIPS)':
 'GPO1_ALERT1_N_CONV': CDS_PINID='GPO1_ALERT1_N_CONV';
NODE_NAME     R1D26 1
 '@BASEBOARD_FAB2_LIB.BASEBOARD_FAB2(SCH_1):PAGE199_I109@MSTR_DISCRETE.RES(CHIPS)':
 'A': CDS_PINID='A';
NODE_NAME     J1F3 5
 '@BASEBOARD_FAB2_LIB.BASEBOARD_FAB2(SCH_1):PAGE181_I106@MSTR_CONN.CONN8_H62179001(CHIPS)':
 'IO5': CDS_PINID='IO5';
NODE_NAME     J1F1 A6
 '@BASEBOARD_FAB2_LIB.BASEBOARD_FAB2(SCH_1):PAGE181_I134@W_HDL.DM-FCI-CONN76-8R-GP-U-01(CHIPS)':
 'PMBUS_ALERT#': CDS_PINID='\pmbus_alert#\';
NET_NAME
'IRQ_SPI_TPM_N_R'
 '@BASEBOARD_FAB2_LIB.BASEBOARD_FAB2(SCH_1):IRQ_SPI_TPM_N_R':
 C_SIGNAL='@baseboard_fab2_lib.baseboard_fab2(sch_1):irq_spi_tpm_n_r';
NODE_NAME     J8E1 9
 '@BASEBOARD_FAB2_LIB.BASEBOARD_FAB2(SCH_1):PAGE184_I87@MSTR_SCONN.SCONN11_H67026001(CHIPS)':
 'IO9': CDS_PINID='IO9';
NODE_NAME     R8E1 1
 '@BASEBOARD_FAB2_LIB.BASEBOARD_FAB2(SCH_1):PAGE184_I99@MSTR_DISCRETE.RES(CHIPS)':
 'A': CDS_PINID='A';
NET_NAME
'IRQ_UV_DETECT_N'
 '@BASEBOARD_FAB2_LIB.BASEBOARD_FAB2(SCH_1):IRQ_UV_DETECT_N':
 C_SIGNAL='@baseboard_fab2_lib.baseboard_fab2(sch_1):irq_uv_detect_n';
NODE_NAME     U7C1 AU58
 '@BASEBOARD_FAB2_LIB.BASEBOARD_FAB2(SCH_1):PAGE120_I147@MSTR_U_PROC.LBG_CORE_QAT_EXT_D(CHIPS)':
 'GPP_E12_USB2_OC3_N': CDS_PINID='GPP_E12_USB2_OC3_N';
NODE_NAME     U8E1 4
 '@BASEBOARD_FAB2_LIB.BASEBOARD_FAB2(SCH_1):PAGE170_I11@MSTR_TTL.TTL08(CHIPS)':
 'A'<0>: CDS_PINID='A(0)';
NODE_NAME     Q9P1 3
 '@BASEBOARD_FAB2_LIB.BASEBOARD_FAB2(SCH_1):PAGE200_I199@MSTR_DISCRETE.FET_N_DUAL(CHIPS)':
 'DRAIN'<0>: CDS_PINID='DRAIN(0)';
NODE_NAME     R9P4 2
 '@BASEBOARD_FAB2_LIB.BASEBOARD_FAB2(SCH_1):PAGE200_I210@MSTR_DISCRETE.RES(CHIPS)':
 'B': CDS_PINID='B';
NODE_NAME     CR9P1 1
 '@BASEBOARD_FAB2_LIB.BASEBOARD_FAB2(SCH_1):PAGE200_I214@MSTR_DISCRETE.DIODE(CHIPS)':
 'C': CDS_PINID='C';
NODE_NAME     U25W4 T2
 '@BASEBOARD_FAB2_LIB.BASEBOARD_FAB2(SCH_1):PAGE145_I117@W_HDL.AST2520A1-GP-GP(CHIPS)':
 'GPIOL0_NCTS1': CDS_PINID='GPIOL0_NCTS1';
NET_NAME
'ISENSE_P1V05_PCH_STBY_PH1_IMON'
 '@BASEBOARD_FAB2_LIB.BASEBOARD_FAB2(SCH_1):ISENSE_P1V05_PCH_STBY_PH1_IMON':
 C_SIGNAL='@baseboard_fab2_lib.baseboard_fab2(sch_1):isense_p1v05_pch_stby_ph1_i~
mon';
NODE_NAME     EU8A1 26
 '@BASEBOARD_FAB2_LIB.BASEBOARD_FAB2(SCH_1):PAGE235_I229@MSTR_CONTROLLER.PXE1110B(CHIPS)':
 'BISEN1': CDS_PINID='BISEN1';
NODE_NAME     EU7A2 38
 '@BASEBOARD_FAB2_LIB.BASEBOARD_FAB2(SCH_1):PAGE236_I117@MSTR_DISCRETE.IR354XX(CHIPS)':
 'IOUT': CDS_PINID='IOUT';
NODE_NAME     CF24 2
 '@BASEBOARD_FAB2_LIB.BASEBOARD_FAB2(SCH_1):PAGE235_I240@W_HDL.SC22P50V2JN-4GP(CHIPS)':
 '2': CDS_PINID='\2\';
NODE_NAME     RF24 2
 '@BASEBOARD_FAB2_LIB.BASEBOARD_FAB2(SCH_1):PAGE235_I242@MSTR_DISCRETE.RES(CHIPS)':
 'B': CDS_PINID='B';
NET_NAME
'ISENSE_PVCCIN_CPU0_PH1_IMON'
 '@BASEBOARD_FAB2_LIB.BASEBOARD_FAB2(SCH_1):ISENSE_PVCCIN_CPU0_PH1_IMON':
 C_SIGNAL='@baseboard_fab2_lib.baseboard_fab2(sch_1):isense_pvccin_cpu0_ph1_imon~
';
NODE_NAME     EU4D4 24
 '@BASEBOARD_FAB2_LIB.BASEBOARD_FAB2(SCH_1):PAGE201_I155@MSTR_CONTROLLER.PXE1610B(CHIPS)':
 'AISEN1': CDS_PINID='AISEN1';
NODE_NAME     EU4E1 38
 '@BASEBOARD_FAB2_LIB.BASEBOARD_FAB2(SCH_1):PAGE202_I63@MSTR_DISCRETE.IR354XX(CHIPS)':
 'IOUT': CDS_PINID='IOUT';
NODE_NAME     CF1 2
 '@BASEBOARD_FAB2_LIB.BASEBOARD_FAB2(SCH_1):PAGE201_I168@W_HDL.SC22P50V2JN-4GP(CHIPS)':
 '2': CDS_PINID='\2\';
NODE_NAME     RF1 2
 '@BASEBOARD_FAB2_LIB.BASEBOARD_FAB2(SCH_1):PAGE201_I182@MSTR_DISCRETE.RES(CHIPS)':
 'B': CDS_PINID='B';
NET_NAME
'ISENSE_PVCCIN_CPU0_PH2_IMON'
 '@BASEBOARD_FAB2_LIB.BASEBOARD_FAB2(SCH_1):ISENSE_PVCCIN_CPU0_PH2_IMON':
 C_SIGNAL='@baseboard_fab2_lib.baseboard_fab2(sch_1):isense_pvccin_cpu0_ph2_imon~
';
NODE_NAME     EU4D4 26
 '@BASEBOARD_FAB2_LIB.BASEBOARD_FAB2(SCH_1):PAGE201_I155@MSTR_CONTROLLER.PXE1610B(CHIPS)':
 'AISEN2': CDS_PINID='AISEN2';
NODE_NAME     EU4D6 38
 '@BASEBOARD_FAB2_LIB.BASEBOARD_FAB2(SCH_1):PAGE202_I64@MSTR_DISCRETE.IR354XX(CHIPS)':
 'IOUT': CDS_PINID='IOUT';
NODE_NAME     CF2 2
 '@BASEBOARD_FAB2_LIB.BASEBOARD_FAB2(SCH_1):PAGE201_I169@W_HDL.SC22P50V2JN-4GP(CHIPS)':
 '2': CDS_PINID='\2\';
NODE_NAME     RF2 2
 '@BASEBOARD_FAB2_LIB.BASEBOARD_FAB2(SCH_1):PAGE201_I183@MSTR_DISCRETE.RES(CHIPS)':
 'B': CDS_PINID='B';
NET_NAME
'ISENSE_PVCCIN_CPU0_PH3_IMON'
 '@BASEBOARD_FAB2_LIB.BASEBOARD_FAB2(SCH_1):ISENSE_PVCCIN_CPU0_PH3_IMON':
 C_SIGNAL='@baseboard_fab2_lib.baseboard_fab2(sch_1):isense_pvccin_cpu0_ph3_imon~
';
NODE_NAME     EU4D4 28
 '@BASEBOARD_FAB2_LIB.BASEBOARD_FAB2(SCH_1):PAGE201_I155@MSTR_CONTROLLER.PXE1610B(CHIPS)':
 'AISEN3': CDS_PINID='AISEN3';
NODE_NAME     EU4D3 38
 '@BASEBOARD_FAB2_LIB.BASEBOARD_FAB2(SCH_1):PAGE203_I70@MSTR_DISCRETE.IR354XX(CHIPS)':
 'IOUT': CDS_PINID='IOUT';
NODE_NAME     CF3 2
 '@BASEBOARD_FAB2_LIB.BASEBOARD_FAB2(SCH_1):PAGE201_I170@W_HDL.SC22P50V2JN-4GP(CHIPS)':
 '2': CDS_PINID='\2\';
NODE_NAME     RF3 2
 '@BASEBOARD_FAB2_LIB.BASEBOARD_FAB2(SCH_1):PAGE201_I184@MSTR_DISCRETE.RES(CHIPS)':
 'B': CDS_PINID='B';
NET_NAME
'ISENSE_PVCCIN_CPU0_PH4_IMON'
 '@BASEBOARD_FAB2_LIB.BASEBOARD_FAB2(SCH_1):ISENSE_PVCCIN_CPU0_PH4_IMON':
 C_SIGNAL='@baseboard_fab2_lib.baseboard_fab2(sch_1):isense_pvccin_cpu0_ph4_imon~
';
NODE_NAME     EU4D4 30
 '@BASEBOARD_FAB2_LIB.BASEBOARD_FAB2(SCH_1):PAGE201_I155@MSTR_CONTROLLER.PXE1610B(CHIPS)':
 'AISEN4': CDS_PINID='AISEN4';
NODE_NAME     EU4D1 38
 '@BASEBOARD_FAB2_LIB.BASEBOARD_FAB2(SCH_1):PAGE203_I71@MSTR_DISCRETE.IR354XX(CHIPS)':
 'IOUT': CDS_PINID='IOUT';
NODE_NAME     CF4 2
 '@BASEBOARD_FAB2_LIB.BASEBOARD_FAB2(SCH_1):PAGE201_I171@W_HDL.SC22P50V2JN-4GP(CHIPS)':
 '2': CDS_PINID='\2\';
NODE_NAME     RF4 2
 '@BASEBOARD_FAB2_LIB.BASEBOARD_FAB2(SCH_1):PAGE201_I185@MSTR_DISCRETE.RES(CHIPS)':
 'B': CDS_PINID='B';
NET_NAME
'ISENSE_PVCCIN_CPU0_PH5_IMON'
 '@BASEBOARD_FAB2_LIB.BASEBOARD_FAB2(SCH_1):ISENSE_PVCCIN_CPU0_PH5_IMON':
 C_SIGNAL='@baseboard_fab2_lib.baseboard_fab2(sch_1):isense_pvccin_cpu0_ph5_imon~
';
NODE_NAME     EU4D4 32
 '@BASEBOARD_FAB2_LIB.BASEBOARD_FAB2(SCH_1):PAGE201_I155@MSTR_CONTROLLER.PXE1610B(CHIPS)':
 'AISEN5': CDS_PINID='AISEN5';
NODE_NAME     EU4C2 38
 '@BASEBOARD_FAB2_LIB.BASEBOARD_FAB2(SCH_1):PAGE204_I71@MSTR_DISCRETE.IR354XX(CHIPS)':
 'IOUT': CDS_PINID='IOUT';
NODE_NAME     CF5 2
 '@BASEBOARD_FAB2_LIB.BASEBOARD_FAB2(SCH_1):PAGE201_I172@W_HDL.SC22P50V2JN-4GP(CHIPS)':
 '2': CDS_PINID='\2\';
NODE_NAME     RF5 2
 '@BASEBOARD_FAB2_LIB.BASEBOARD_FAB2(SCH_1):PAGE201_I186@MSTR_DISCRETE.RES(CHIPS)':
 'B': CDS_PINID='B';
NET_NAME
'ISENSE_PVCCIN_CPU1_PH1_IMON'
 '@BASEBOARD_FAB2_LIB.BASEBOARD_FAB2(SCH_1):ISENSE_PVCCIN_CPU1_PH1_IMON':
 C_SIGNAL='@baseboard_fab2_lib.baseboard_fab2(sch_1):isense_pvccin_cpu1_ph1_imon~
';
NODE_NAME     EU1C2 24
 '@BASEBOARD_FAB2_LIB.BASEBOARD_FAB2(SCH_1):PAGE206_I130@MSTR_CONTROLLER.PXE1610B(CHIPS)':
 'AISEN1': CDS_PINID='AISEN1';
NODE_NAME     EU1E2 38
 '@BASEBOARD_FAB2_LIB.BASEBOARD_FAB2(SCH_1):PAGE207_I20@MSTR_DISCRETE.IR354XX(CHIPS)':
 'IOUT': CDS_PINID='IOUT';
NODE_NAME     CF7 2
 '@BASEBOARD_FAB2_LIB.BASEBOARD_FAB2(SCH_1):PAGE206_I137@W_HDL.SC22P50V2JN-4GP(CHIPS)':
 '2': CDS_PINID='\2\';
NODE_NAME     RF7 2
 '@BASEBOARD_FAB2_LIB.BASEBOARD_FAB2(SCH_1):PAGE206_I150@MSTR_DISCRETE.RES(CHIPS)':
 'B': CDS_PINID='B';
NET_NAME
'ISENSE_PVCCIN_CPU1_PH2_IMON'
 '@BASEBOARD_FAB2_LIB.BASEBOARD_FAB2(SCH_1):ISENSE_PVCCIN_CPU1_PH2_IMON':
 C_SIGNAL='@baseboard_fab2_lib.baseboard_fab2(sch_1):isense_pvccin_cpu1_ph2_imon~
';
NODE_NAME     EU1C2 26
 '@BASEBOARD_FAB2_LIB.BASEBOARD_FAB2(SCH_1):PAGE206_I130@MSTR_CONTROLLER.PXE1610B(CHIPS)':
 'AISEN2': CDS_PINID='AISEN2';
NODE_NAME     CF8 2
 '@BASEBOARD_FAB2_LIB.BASEBOARD_FAB2(SCH_1):PAGE206_I138@W_HDL.SC22P50V2JN-4GP(CHIPS)':
 '2': CDS_PINID='\2\';
NODE_NAME     RF8 2
 '@BASEBOARD_FAB2_LIB.BASEBOARD_FAB2(SCH_1):PAGE206_I151@MSTR_DISCRETE.RES(CHIPS)':
 'B': CDS_PINID='B';
NODE_NAME     EU1D4 38
 '@BASEBOARD_FAB2_LIB.BASEBOARD_FAB2(SCH_1):PAGE207_I113@MSTR_DISCRETE.IR354XX(CHIPS)':
 'IOUT': CDS_PINID='IOUT';
NET_NAME
'ISENSE_PVCCIN_CPU1_PH3_IMON'
 '@BASEBOARD_FAB2_LIB.BASEBOARD_FAB2(SCH_1):ISENSE_PVCCIN_CPU1_PH3_IMON':
 C_SIGNAL='@baseboard_fab2_lib.baseboard_fab2(sch_1):isense_pvccin_cpu1_ph3_imon~
';
NODE_NAME     EU1C2 28
 '@BASEBOARD_FAB2_LIB.BASEBOARD_FAB2(SCH_1):PAGE206_I130@MSTR_CONTROLLER.PXE1610B(CHIPS)':
 'AISEN3': CDS_PINID='AISEN3';
NODE_NAME     EU1D3 38
 '@BASEBOARD_FAB2_LIB.BASEBOARD_FAB2(SCH_1):PAGE208_I27@MSTR_DISCRETE.IR354XX(CHIPS)':
 'IOUT': CDS_PINID='IOUT';
NODE_NAME     CF9 2
 '@BASEBOARD_FAB2_LIB.BASEBOARD_FAB2(SCH_1):PAGE206_I139@W_HDL.SC22P50V2JN-4GP(CHIPS)':
 '2': CDS_PINID='\2\';
NODE_NAME     RF9 2
 '@BASEBOARD_FAB2_LIB.BASEBOARD_FAB2(SCH_1):PAGE206_I152@MSTR_DISCRETE.RES(CHIPS)':
 'B': CDS_PINID='B';
NET_NAME
'ISENSE_PVCCIN_CPU1_PH4_IMON'
 '@BASEBOARD_FAB2_LIB.BASEBOARD_FAB2(SCH_1):ISENSE_PVCCIN_CPU1_PH4_IMON':
 C_SIGNAL='@baseboard_fab2_lib.baseboard_fab2(sch_1):isense_pvccin_cpu1_ph4_imon~
';
NODE_NAME     EU1C2 30
 '@BASEBOARD_FAB2_LIB.BASEBOARD_FAB2(SCH_1):PAGE206_I130@MSTR_CONTROLLER.PXE1610B(CHIPS)':
 'AISEN4': CDS_PINID='AISEN4';
NODE_NAME     EU1D1 38
 '@BASEBOARD_FAB2_LIB.BASEBOARD_FAB2(SCH_1):PAGE208_I71@MSTR_DISCRETE.IR354XX(CHIPS)':
 'IOUT': CDS_PINID='IOUT';
NODE_NAME     CF10 2
 '@BASEBOARD_FAB2_LIB.BASEBOARD_FAB2(SCH_1):PAGE206_I140@W_HDL.SC22P50V2JN-4GP(CHIPS)':
 '2': CDS_PINID='\2\';
NODE_NAME     RF10 2
 '@BASEBOARD_FAB2_LIB.BASEBOARD_FAB2(SCH_1):PAGE206_I153@MSTR_DISCRETE.RES(CHIPS)':
 'B': CDS_PINID='B';
NET_NAME
'ISENSE_PVCCIN_CPU1_PH5_IMON'
 '@BASEBOARD_FAB2_LIB.BASEBOARD_FAB2(SCH_1):ISENSE_PVCCIN_CPU1_PH5_IMON':
 C_SIGNAL='@baseboard_fab2_lib.baseboard_fab2(sch_1):isense_pvccin_cpu1_ph5_imon~
';
NODE_NAME     EU1C2 32
 '@BASEBOARD_FAB2_LIB.BASEBOARD_FAB2(SCH_1):PAGE206_I130@MSTR_CONTROLLER.PXE1610B(CHIPS)':
 'AISEN5': CDS_PINID='AISEN5';
NODE_NAME     EU1C3 38
 '@BASEBOARD_FAB2_LIB.BASEBOARD_FAB2(SCH_1):PAGE209_I56@MSTR_DISCRETE.IR354XX(CHIPS)':
 'IOUT': CDS_PINID='IOUT';
NODE_NAME     CF11 2
 '@BASEBOARD_FAB2_LIB.BASEBOARD_FAB2(SCH_1):PAGE206_I141@W_HDL.SC22P50V2JN-4GP(CHIPS)':
 '2': CDS_PINID='\2\';
NODE_NAME     RF11 2
 '@BASEBOARD_FAB2_LIB.BASEBOARD_FAB2(SCH_1):PAGE206_I154@MSTR_DISCRETE.RES(CHIPS)':
 'B': CDS_PINID='B';
NET_NAME
'ISENSE_PVCCIO_CPU0_PH1_IMON'
 '@BASEBOARD_FAB2_LIB.BASEBOARD_FAB2(SCH_1):ISENSE_PVCCIO_CPU0_PH1_IMON':
 C_SIGNAL='@baseboard_fab2_lib.baseboard_fab2(sch_1):isense_pvccio_cpu0_ph1_imon~
';
NODE_NAME     EU3P1 22
 '@BASEBOARD_FAB2_LIB.BASEBOARD_FAB2(SCH_1):PAGE211_I93@MSTR_CONTROLLER.PXE1110B(CHIPS)':
 'AISEN1': CDS_PINID='AISEN1';
NODE_NAME     EU7C1 38
 '@BASEBOARD_FAB2_LIB.BASEBOARD_FAB2(SCH_1):PAGE212_I101@MSTR_DISCRETE.IR354XX(CHIPS)':
 'IOUT': CDS_PINID='IOUT';
NODE_NAME     CF13 2
 '@BASEBOARD_FAB2_LIB.BASEBOARD_FAB2(SCH_1):PAGE211_I95@W_HDL.SC22P50V2JN-4GP(CHIPS)':
 '2': CDS_PINID='\2\';
NODE_NAME     RF13 2
 '@BASEBOARD_FAB2_LIB.BASEBOARD_FAB2(SCH_1):PAGE211_I96@MSTR_DISCRETE.RES(CHIPS)':
 'B': CDS_PINID='B';
NET_NAME
'ISENSE_PVCCIO_CPU1_PH1_IMON'
 '@BASEBOARD_FAB2_LIB.BASEBOARD_FAB2(SCH_1):ISENSE_PVCCIO_CPU1_PH1_IMON':
 C_SIGNAL='@baseboard_fab2_lib.baseboard_fab2(sch_1):isense_pvccio_cpu1_ph1_imon~
';
NODE_NAME     EU4D5 22
 '@BASEBOARD_FAB2_LIB.BASEBOARD_FAB2(SCH_1):PAGE213_I96@MSTR_CONTROLLER.PXE1110B(CHIPS)':
 'AISEN1': CDS_PINID='AISEN1';
NODE_NAME     EU4E2 38
 '@BASEBOARD_FAB2_LIB.BASEBOARD_FAB2(SCH_1):PAGE214_I126@MSTR_DISCRETE.IR354XX(CHIPS)':
 'IOUT': CDS_PINID='IOUT';
NODE_NAME     CF14 2
 '@BASEBOARD_FAB2_LIB.BASEBOARD_FAB2(SCH_1):PAGE213_I98@W_HDL.SC22P50V2JN-4GP(CHIPS)':
 '2': CDS_PINID='\2\';
NODE_NAME     RF14 2
 '@BASEBOARD_FAB2_LIB.BASEBOARD_FAB2(SCH_1):PAGE213_I99@MSTR_DISCRETE.RES(CHIPS)':
 'B': CDS_PINID='B';
NET_NAME
'ISENSE_PVDDQ_ABC_PH1_IMON'
 '@BASEBOARD_FAB2_LIB.BASEBOARD_FAB2(SCH_1):ISENSE_PVDDQ_ABC_PH1_IMON':
 C_SIGNAL='@baseboard_fab2_lib.baseboard_fab2(sch_1):isense_pvddq_abc_ph1_imon';
NODE_NAME     EU7G2 38
 '@BASEBOARD_FAB2_LIB.BASEBOARD_FAB2(SCH_1):PAGE216_I102@MSTR_DISCRETE.IR354XX(CHIPS)':
 'IOUT': CDS_PINID='IOUT';
NODE_NAME     RF15 2
 '@BASEBOARD_FAB2_LIB.BASEBOARD_FAB2(SCH_1):PAGE215_I15@MSTR_DISCRETE.RES(CHIPS)':
 'B': CDS_PINID='B';
NODE_NAME     CF15 2
 '@BASEBOARD_FAB2_LIB.BASEBOARD_FAB2(SCH_1):PAGE215_I16@W_HDL.SC22P50V2JN-4GP(CHIPS)':
 '2': CDS_PINID='\2\';
NODE_NAME     EU7G1 22
 '@BASEBOARD_FAB2_LIB.BASEBOARD_FAB2(SCH_1):PAGE215_I69@MSTR_CONTROLLER.PXM1310B(CHIPS)':
 'AISEN1': CDS_PINID='AISEN1';
NET_NAME
'ISENSE_PVDDQ_ABC_PH2_IMON'
 '@BASEBOARD_FAB2_LIB.BASEBOARD_FAB2(SCH_1):ISENSE_PVDDQ_ABC_PH2_IMON':
 C_SIGNAL='@baseboard_fab2_lib.baseboard_fab2(sch_1):isense_pvddq_abc_ph2_imon';
NODE_NAME     EU7G3 38
 '@BASEBOARD_FAB2_LIB.BASEBOARD_FAB2(SCH_1):PAGE216_I103@MSTR_DISCRETE.IR354XX(CHIPS)':
 'IOUT': CDS_PINID='IOUT';
NODE_NAME     CF16 2
 '@BASEBOARD_FAB2_LIB.BASEBOARD_FAB2(SCH_1):PAGE215_I26@W_HDL.SC22P50V2JN-4GP(CHIPS)':
 '2': CDS_PINID='\2\';
NODE_NAME     RF16 2
 '@BASEBOARD_FAB2_LIB.BASEBOARD_FAB2(SCH_1):PAGE215_I27@MSTR_DISCRETE.RES(CHIPS)':
 'B': CDS_PINID='B';
NODE_NAME     EU7G1 24
 '@BASEBOARD_FAB2_LIB.BASEBOARD_FAB2(SCH_1):PAGE215_I69@MSTR_CONTROLLER.PXM1310B(CHIPS)':
 'AISEN2': CDS_PINID='AISEN2';
NET_NAME
'ISENSE_PVDDQ_DEF_PH1_IMON'
 '@BASEBOARD_FAB2_LIB.BASEBOARD_FAB2(SCH_1):ISENSE_PVDDQ_DEF_PH1_IMON':
 C_SIGNAL='@baseboard_fab2_lib.baseboard_fab2(sch_1):isense_pvddq_def_ph1_imon';
NODE_NAME     EU7A1 38
 '@BASEBOARD_FAB2_LIB.BASEBOARD_FAB2(SCH_1):PAGE219_I106@MSTR_DISCRETE.IR354XX(CHIPS)':
 'IOUT': CDS_PINID='IOUT';
NODE_NAME     RF17 2
 '@BASEBOARD_FAB2_LIB.BASEBOARD_FAB2(SCH_1):PAGE218_I18@MSTR_DISCRETE.RES(CHIPS)':
 'B': CDS_PINID='B';
NODE_NAME     EU7A5 22
 '@BASEBOARD_FAB2_LIB.BASEBOARD_FAB2(SCH_1):PAGE218_I69@MSTR_CONTROLLER.PXM1310B(CHIPS)':
 'AISEN1': CDS_PINID='AISEN1';
NODE_NAME     CF17 2
 '@BASEBOARD_FAB2_LIB.BASEBOARD_FAB2(SCH_1):PAGE218_I17@W_HDL.SC22P50V2JN-4GP(CHIPS)':
 '2': CDS_PINID='\2\';
NET_NAME
'ISENSE_PVDDQ_DEF_PH2_IMON'
 '@BASEBOARD_FAB2_LIB.BASEBOARD_FAB2(SCH_1):ISENSE_PVDDQ_DEF_PH2_IMON':
 C_SIGNAL='@baseboard_fab2_lib.baseboard_fab2(sch_1):isense_pvddq_def_ph2_imon';
NODE_NAME     EU7A4 38
 '@BASEBOARD_FAB2_LIB.BASEBOARD_FAB2(SCH_1):PAGE219_I107@MSTR_DISCRETE.IR354XX(CHIPS)':
 'IOUT': CDS_PINID='IOUT';
NODE_NAME     RF18 2
 '@BASEBOARD_FAB2_LIB.BASEBOARD_FAB2(SCH_1):PAGE218_I19@MSTR_DISCRETE.RES(CHIPS)':
 'B': CDS_PINID='B';
NODE_NAME     CF18 2
 '@BASEBOARD_FAB2_LIB.BASEBOARD_FAB2(SCH_1):PAGE218_I20@W_HDL.SC22P50V2JN-4GP(CHIPS)':
 '2': CDS_PINID='\2\';
NODE_NAME     EU7A5 24
 '@BASEBOARD_FAB2_LIB.BASEBOARD_FAB2(SCH_1):PAGE218_I69@MSTR_CONTROLLER.PXM1310B(CHIPS)':
 'AISEN2': CDS_PINID='AISEN2';
NET_NAME
'ISENSE_PVDDQ_GHJ_PH1_IMON'
 '@BASEBOARD_FAB2_LIB.BASEBOARD_FAB2(SCH_1):ISENSE_PVDDQ_GHJ_PH1_IMON':
 C_SIGNAL='@baseboard_fab2_lib.baseboard_fab2(sch_1):isense_pvddq_ghj_ph1_imon';
NODE_NAME     RF19 2
 '@BASEBOARD_FAB2_LIB.BASEBOARD_FAB2(SCH_1):PAGE223_I16@MSTR_DISCRETE.RES(CHIPS)':
 'B': CDS_PINID='B';
NODE_NAME     EU1G1 38
 '@BASEBOARD_FAB2_LIB.BASEBOARD_FAB2(SCH_1):PAGE224_I110@MSTR_DISCRETE.IR354XX(CHIPS)':
 'IOUT': CDS_PINID='IOUT';
NODE_NAME     CF19 2
 '@BASEBOARD_FAB2_LIB.BASEBOARD_FAB2(SCH_1):PAGE223_I15@W_HDL.SC22P50V2JN-4GP(CHIPS)':
 '2': CDS_PINID='\2\';
NODE_NAME     EU1G2 22
 '@BASEBOARD_FAB2_LIB.BASEBOARD_FAB2(SCH_1):PAGE223_I69@MSTR_CONTROLLER.PXM1310B(CHIPS)':
 'AISEN1': CDS_PINID='AISEN1';
NET_NAME
'ISENSE_PVDDQ_GHJ_PH2_IMON'
 '@BASEBOARD_FAB2_LIB.BASEBOARD_FAB2(SCH_1):ISENSE_PVDDQ_GHJ_PH2_IMON':
 C_SIGNAL='@baseboard_fab2_lib.baseboard_fab2(sch_1):isense_pvddq_ghj_ph2_imon';
NODE_NAME     EU1F1 38
 '@BASEBOARD_FAB2_LIB.BASEBOARD_FAB2(SCH_1):PAGE224_I111@MSTR_DISCRETE.IR354XX(CHIPS)':
 'IOUT': CDS_PINID='IOUT';
NODE_NAME     RF20 2
 '@BASEBOARD_FAB2_LIB.BASEBOARD_FAB2(SCH_1):PAGE223_I19@MSTR_DISCRETE.RES(CHIPS)':
 'B': CDS_PINID='B';
NODE_NAME     EU1G2 24
 '@BASEBOARD_FAB2_LIB.BASEBOARD_FAB2(SCH_1):PAGE223_I69@MSTR_CONTROLLER.PXM1310B(CHIPS)':
 'AISEN2': CDS_PINID='AISEN2';
NODE_NAME     CF20 2
 '@BASEBOARD_FAB2_LIB.BASEBOARD_FAB2(SCH_1):PAGE223_I17@W_HDL.SC22P50V2JN-4GP(CHIPS)':
 '2': CDS_PINID='\2\';
NET_NAME
'ISENSE_PVDDQ_KLM_PH1_IMON'
 '@BASEBOARD_FAB2_LIB.BASEBOARD_FAB2(SCH_1):ISENSE_PVDDQ_KLM_PH1_IMON':
 C_SIGNAL='@baseboard_fab2_lib.baseboard_fab2(sch_1):isense_pvddq_klm_ph1_imon';
NODE_NAME     RF21 2
 '@BASEBOARD_FAB2_LIB.BASEBOARD_FAB2(SCH_1):PAGE226_I16@MSTR_DISCRETE.RES(CHIPS)':
 'B': CDS_PINID='B';
NODE_NAME     EU1A2 38
 '@BASEBOARD_FAB2_LIB.BASEBOARD_FAB2(SCH_1):PAGE227_I101@MSTR_DISCRETE.IR354XX(CHIPS)':
 'IOUT': CDS_PINID='IOUT';
NODE_NAME     CF21 2
 '@BASEBOARD_FAB2_LIB.BASEBOARD_FAB2(SCH_1):PAGE226_I15@W_HDL.SC22P50V2JN-4GP(CHIPS)':
 '2': CDS_PINID='\2\';
NODE_NAME     EU1B1 22
 '@BASEBOARD_FAB2_LIB.BASEBOARD_FAB2(SCH_1):PAGE226_I69@MSTR_CONTROLLER.PXM1310B(CHIPS)':
 'AISEN1': CDS_PINID='AISEN1';
NET_NAME
'ISENSE_PVDDQ_KLM_PH2_IMON'
 '@BASEBOARD_FAB2_LIB.BASEBOARD_FAB2(SCH_1):ISENSE_PVDDQ_KLM_PH2_IMON':
 C_SIGNAL='@baseboard_fab2_lib.baseboard_fab2(sch_1):isense_pvddq_klm_ph2_imon';
NODE_NAME     EU1A1 38
 '@BASEBOARD_FAB2_LIB.BASEBOARD_FAB2(SCH_1):PAGE227_I102@MSTR_DISCRETE.IR354XX(CHIPS)':
 'IOUT': CDS_PINID='IOUT';
NODE_NAME     RF22 2
 '@BASEBOARD_FAB2_LIB.BASEBOARD_FAB2(SCH_1):PAGE226_I18@MSTR_DISCRETE.RES(CHIPS)':
 'B': CDS_PINID='B';
NODE_NAME     EU1B1 24
 '@BASEBOARD_FAB2_LIB.BASEBOARD_FAB2(SCH_1):PAGE226_I69@MSTR_CONTROLLER.PXM1310B(CHIPS)':
 'AISEN2': CDS_PINID='AISEN2';
NODE_NAME     CF22 2
 '@BASEBOARD_FAB2_LIB.BASEBOARD_FAB2(SCH_1):PAGE226_I17@W_HDL.SC22P50V2JN-4GP(CHIPS)':
 '2': CDS_PINID='\2\';
NET_NAME
'ISENSE_PVNN_PCH_PH1_IMON'
 '@BASEBOARD_FAB2_LIB.BASEBOARD_FAB2(SCH_1):ISENSE_PVNN_PCH_PH1_IMON':
 C_SIGNAL='@baseboard_fab2_lib.baseboard_fab2(sch_1):isense_pvnn_pch_ph1_imon';
NODE_NAME     EU8A1 22
 '@BASEBOARD_FAB2_LIB.BASEBOARD_FAB2(SCH_1):PAGE235_I229@MSTR_CONTROLLER.PXE1110B(CHIPS)':
 'AISEN1': CDS_PINID='AISEN1';
NODE_NAME     EU7A3 38
 '@BASEBOARD_FAB2_LIB.BASEBOARD_FAB2(SCH_1):PAGE236_I116@MSTR_DISCRETE.IR354XX(CHIPS)':
 'IOUT': CDS_PINID='IOUT';
NODE_NAME     CF23 2
 '@BASEBOARD_FAB2_LIB.BASEBOARD_FAB2(SCH_1):PAGE235_I239@W_HDL.SC22P50V2JN-4GP(CHIPS)':
 '2': CDS_PINID='\2\';
NODE_NAME     RF23 2
 '@BASEBOARD_FAB2_LIB.BASEBOARD_FAB2(SCH_1):PAGE235_I241@MSTR_DISCRETE.RES(CHIPS)':
 'B': CDS_PINID='B';
NET_NAME
'ISENSE_PVSA_CPU0_IMON'
 '@BASEBOARD_FAB2_LIB.BASEBOARD_FAB2(SCH_1):ISENSE_PVSA_CPU0_IMON':
 C_SIGNAL='@baseboard_fab2_lib.baseboard_fab2(sch_1):isense_pvsa_cpu0_imon';
NODE_NAME     EU4D4 38
 '@BASEBOARD_FAB2_LIB.BASEBOARD_FAB2(SCH_1):PAGE201_I155@MSTR_CONTROLLER.PXE1610B(CHIPS)':
 'BISEN1': CDS_PINID='BISEN1';
NODE_NAME     EU4C1 38
 '@BASEBOARD_FAB2_LIB.BASEBOARD_FAB2(SCH_1):PAGE205_I46@MSTR_DISCRETE.IR354XX(CHIPS)':
 'IOUT': CDS_PINID='IOUT';
NODE_NAME     CF6 2
 '@BASEBOARD_FAB2_LIB.BASEBOARD_FAB2(SCH_1):PAGE201_I173@W_HDL.SC22P50V2JN-4GP(CHIPS)':
 '2': CDS_PINID='\2\';
NODE_NAME     RF6 2
 '@BASEBOARD_FAB2_LIB.BASEBOARD_FAB2(SCH_1):PAGE201_I180@MSTR_DISCRETE.RES(CHIPS)':
 'B': CDS_PINID='B';
NET_NAME
'ISENSE_PVSA_CPU1_IMON'
 '@BASEBOARD_FAB2_LIB.BASEBOARD_FAB2(SCH_1):ISENSE_PVSA_CPU1_IMON':
 C_SIGNAL='@baseboard_fab2_lib.baseboard_fab2(sch_1):isense_pvsa_cpu1_imon';
NODE_NAME     EU1C2 38
 '@BASEBOARD_FAB2_LIB.BASEBOARD_FAB2(SCH_1):PAGE206_I130@MSTR_CONTROLLER.PXE1610B(CHIPS)':
 'BISEN1': CDS_PINID='BISEN1';
NODE_NAME     EU1C1 38
 '@BASEBOARD_FAB2_LIB.BASEBOARD_FAB2(SCH_1):PAGE210_I51@MSTR_DISCRETE.IR354XX(CHIPS)':
 'IOUT': CDS_PINID='IOUT';
NODE_NAME     CF12 2
 '@BASEBOARD_FAB2_LIB.BASEBOARD_FAB2(SCH_1):PAGE206_I142@W_HDL.SC22P50V2JN-4GP(CHIPS)':
 '2': CDS_PINID='\2\';
NODE_NAME     RF12 2
 '@BASEBOARD_FAB2_LIB.BASEBOARD_FAB2(SCH_1):PAGE206_I149@MSTR_DISCRETE.RES(CHIPS)':
 'B': CDS_PINID='B';
NET_NAME
'ISENSE_TMP421_1_BC'
 '@BASEBOARD_FAB2_LIB.BASEBOARD_FAB2(SCH_1):ISENSE_TMP421_1_BC':
 C_SIGNAL='@baseboard_fab2_lib.baseboard_fab2(sch_1):isense_tmp421_1_bc';
NODE_NAME     R9B5 1
 '@BASEBOARD_FAB2_LIB.BASEBOARD_FAB2(SCH_1):PAGE167_I5@MSTR_DISCRETE.RES(CHIPS)':
 'A': CDS_PINID='A';
NODE_NAME     Q9B1 B
 '@BASEBOARD_FAB2_LIB.BASEBOARD_FAB2(SCH_1):PAGE167_I93@W_HDL.2SB2907A-B0-00001-GP(CHIPS)':
 'B': CDS_PINID='B';
NODE_NAME     Q9B1 C
 '@BASEBOARD_FAB2_LIB.BASEBOARD_FAB2(SCH_1):PAGE167_I93@W_HDL.2SB2907A-B0-00001-GP(CHIPS)':
 'C': CDS_PINID='C';
NET_NAME
'ISENSE_TMP421_1_DXN'
 '@BASEBOARD_FAB2_LIB.BASEBOARD_FAB2(SCH_1):ISENSE_TMP421_1_DXN':
 C_SIGNAL='@baseboard_fab2_lib.baseboard_fab2(sch_1):isense_tmp421_1_dxn';
NODE_NAME     U9B4 2
 '@BASEBOARD_FAB2_LIB.BASEBOARD_FAB2(SCH_1):PAGE167_I1@MSTR_ANALOG.TMP421(CHIPS)':
 'DXN': CDS_PINID='DXN';
NODE_NAME     R9B5 2
 '@BASEBOARD_FAB2_LIB.BASEBOARD_FAB2(SCH_1):PAGE167_I5@MSTR_DISCRETE.RES(CHIPS)':
 'B': CDS_PINID='B';
NODE_NAME     C1M4 2
 '@BASEBOARD_FAB2_LIB.BASEBOARD_FAB2(SCH_1):PAGE167_I7@MSTR_DISCRETE.CAP(CHIPS)':
 'B': CDS_PINID='B';
NET_NAME
'ISENSE_TMP421_1_DXP'
 '@BASEBOARD_FAB2_LIB.BASEBOARD_FAB2(SCH_1):ISENSE_TMP421_1_DXP':
 C_SIGNAL='@baseboard_fab2_lib.baseboard_fab2(sch_1):isense_tmp421_1_dxp';
NODE_NAME     U9B4 1
 '@BASEBOARD_FAB2_LIB.BASEBOARD_FAB2(SCH_1):PAGE167_I1@MSTR_ANALOG.TMP421(CHIPS)':
 'DXP': CDS_PINID='DXP';
NODE_NAME     R9B4 2
 '@BASEBOARD_FAB2_LIB.BASEBOARD_FAB2(SCH_1):PAGE167_I6@MSTR_DISCRETE.RES(CHIPS)':
 'B': CDS_PINID='B';
NODE_NAME     C1M4 1
 '@BASEBOARD_FAB2_LIB.BASEBOARD_FAB2(SCH_1):PAGE167_I7@MSTR_DISCRETE.CAP(CHIPS)':
 'A': CDS_PINID='A';
NET_NAME
'ISENSE_TMP421_1_E'
 '@BASEBOARD_FAB2_LIB.BASEBOARD_FAB2(SCH_1):ISENSE_TMP421_1_E':
 C_SIGNAL='@baseboard_fab2_lib.baseboard_fab2(sch_1):isense_tmp421_1_e';
NODE_NAME     R9B4 1
 '@BASEBOARD_FAB2_LIB.BASEBOARD_FAB2(SCH_1):PAGE167_I6@MSTR_DISCRETE.RES(CHIPS)':
 'A': CDS_PINID='A';
NODE_NAME     Q9B1 E
 '@BASEBOARD_FAB2_LIB.BASEBOARD_FAB2(SCH_1):PAGE167_I93@W_HDL.2SB2907A-B0-00001-GP(CHIPS)':
 'E': CDS_PINID='E';
NET_NAME
'ISENSE_TMP421_2_BC'
 '@BASEBOARD_FAB2_LIB.BASEBOARD_FAB2(SCH_1):ISENSE_TMP421_2_BC':
 C_SIGNAL='@baseboard_fab2_lib.baseboard_fab2(sch_1):isense_tmp421_2_bc';
NODE_NAME     R9R6 1
 '@BASEBOARD_FAB2_LIB.BASEBOARD_FAB2(SCH_1):PAGE167_I26@MSTR_DISCRETE.RES(CHIPS)':
 'A': CDS_PINID='A';
NODE_NAME     Q1E1 B
 '@BASEBOARD_FAB2_LIB.BASEBOARD_FAB2(SCH_1):PAGE167_I94@W_HDL.2SB2907A-B0-00001-GP(CHIPS)':
 'B': CDS_PINID='B';
NODE_NAME     Q1E1 C
 '@BASEBOARD_FAB2_LIB.BASEBOARD_FAB2(SCH_1):PAGE167_I94@W_HDL.2SB2907A-B0-00001-GP(CHIPS)':
 'C': CDS_PINID='C';
NET_NAME
'ISENSE_TMP421_2_DXN'
 '@BASEBOARD_FAB2_LIB.BASEBOARD_FAB2(SCH_1):ISENSE_TMP421_2_DXN':
 C_SIGNAL='@baseboard_fab2_lib.baseboard_fab2(sch_1):isense_tmp421_2_dxn';
NODE_NAME     C1E19 2
 '@BASEBOARD_FAB2_LIB.BASEBOARD_FAB2(SCH_1):PAGE167_I24@MSTR_DISCRETE.CAP(CHIPS)':
 'B': CDS_PINID='B';
NODE_NAME     R9R6 2
 '@BASEBOARD_FAB2_LIB.BASEBOARD_FAB2(SCH_1):PAGE167_I26@MSTR_DISCRETE.RES(CHIPS)':
 'B': CDS_PINID='B';
NODE_NAME     U1E1 2
 '@BASEBOARD_FAB2_LIB.BASEBOARD_FAB2(SCH_1):PAGE167_I30@MSTR_ANALOG.TMP421(CHIPS)':
 'DXN': CDS_PINID='DXN';
NET_NAME
'ISENSE_TMP421_2_DXP'
 '@BASEBOARD_FAB2_LIB.BASEBOARD_FAB2(SCH_1):ISENSE_TMP421_2_DXP':
 C_SIGNAL='@baseboard_fab2_lib.baseboard_fab2(sch_1):isense_tmp421_2_dxp';
NODE_NAME     C1E19 1
 '@BASEBOARD_FAB2_LIB.BASEBOARD_FAB2(SCH_1):PAGE167_I24@MSTR_DISCRETE.CAP(CHIPS)':
 'A': CDS_PINID='A';
NODE_NAME     R9R5 2
 '@BASEBOARD_FAB2_LIB.BASEBOARD_FAB2(SCH_1):PAGE167_I25@MSTR_DISCRETE.RES(CHIPS)':
 'B': CDS_PINID='B';
NODE_NAME     U1E1 1
 '@BASEBOARD_FAB2_LIB.BASEBOARD_FAB2(SCH_1):PAGE167_I30@MSTR_ANALOG.TMP421(CHIPS)':
 'DXP': CDS_PINID='DXP';
NET_NAME
'ISENSE_TMP421_2_E'
 '@BASEBOARD_FAB2_LIB.BASEBOARD_FAB2(SCH_1):ISENSE_TMP421_2_E':
 C_SIGNAL='@baseboard_fab2_lib.baseboard_fab2(sch_1):isense_tmp421_2_e';
NODE_NAME     R9R5 1
 '@BASEBOARD_FAB2_LIB.BASEBOARD_FAB2(SCH_1):PAGE167_I25@MSTR_DISCRETE.RES(CHIPS)':
 'A': CDS_PINID='A';
NODE_NAME     Q1E1 E
 '@BASEBOARD_FAB2_LIB.BASEBOARD_FAB2(SCH_1):PAGE167_I94@W_HDL.2SB2907A-B0-00001-GP(CHIPS)':
 'E': CDS_PINID='E';
NET_NAME
'JTAG_BMC_BUF_TDI'
 '@BASEBOARD_FAB2_LIB.BASEBOARD_FAB2(SCH_1):JTAG_BMC_BUF_TDI':
 C_SIGNAL='@baseboard_fab2_lib.baseboard_fab2(sch_1):jtag_bmc_buf_tdi';
NODE_NAME     R25W160 2
 '@BASEBOARD_FAB2_LIB.BASEBOARD_FAB2(SCH_1):PAGE269_I20@MSTR_DISCRETE.RES(CHIPS)':
 'B': CDS_PINID='B';
NODE_NAME     U25W10 10
 '@BASEBOARD_FAB2_LIB.BASEBOARD_FAB2(SCH_1):PAGE269_I49@MSTR_DIGITAL.GTL2014(CHIPS)':
 'A2': CDS_PINID='A2';
NODE_NAME     U25W16 3
 '@BASEBOARD_FAB2_LIB.BASEBOARD_FAB2(SCH_1):PAGE268_I38@MSTR_TTL.TTL3126(CHIPS)'(3):
 'B'<3>: CDS_PINID='B(3)';
NET_NAME
'JTAG_BMC_BUF_TDO'
 '@BASEBOARD_FAB2_LIB.BASEBOARD_FAB2(SCH_1):JTAG_BMC_BUF_TDO':
 C_SIGNAL='@baseboard_fab2_lib.baseboard_fab2(sch_1):jtag_bmc_buf_tdo';
NODE_NAME     U25W16 8
 '@BASEBOARD_FAB2_LIB.BASEBOARD_FAB2(SCH_1):PAGE268_I38@MSTR_TTL.TTL3126(CHIPS)'(1):
 'B'<1>: CDS_PINID='B(1)';
NODE_NAME     R25W187 2
 '@BASEBOARD_FAB2_LIB.BASEBOARD_FAB2(SCH_1):PAGE268_I66@MSTR_DISCRETE.RES(CHIPS)':
 'B': CDS_PINID='B';
NET_NAME
'JTAG_BMC_BUF_TDO_R'
 '@BASEBOARD_FAB2_LIB.BASEBOARD_FAB2(SCH_1):JTAG_BMC_BUF_TDO_R':
 C_SIGNAL='@baseboard_fab2_lib.baseboard_fab2(sch_1):jtag_bmc_buf_tdo_r';
NODE_NAME     U25W11 9
 '@BASEBOARD_FAB2_LIB.BASEBOARD_FAB2(SCH_1):PAGE268_I33@MSTR_DIGITAL.GTL2014(CHIPS)':
 'A3': CDS_PINID='A3';
NODE_NAME     R25W187 1
 '@BASEBOARD_FAB2_LIB.BASEBOARD_FAB2(SCH_1):PAGE268_I66@MSTR_DISCRETE.RES(CHIPS)':
 'A': CDS_PINID='A';
NET_NAME
'JTAG_BMC_BUF_TMS'
 '@BASEBOARD_FAB2_LIB.BASEBOARD_FAB2(SCH_1):JTAG_BMC_BUF_TMS':
 C_SIGNAL='@baseboard_fab2_lib.baseboard_fab2(sch_1):jtag_bmc_buf_tms';
NODE_NAME     R25W161 2
 '@BASEBOARD_FAB2_LIB.BASEBOARD_FAB2(SCH_1):PAGE269_I21@MSTR_DISCRETE.RES(CHIPS)':
 'B': CDS_PINID='B';
NODE_NAME     U25W10 9
 '@BASEBOARD_FAB2_LIB.BASEBOARD_FAB2(SCH_1):PAGE269_I49@MSTR_DIGITAL.GTL2014(CHIPS)':
 'A3': CDS_PINID='A3';
NODE_NAME     U25W16 6
 '@BASEBOARD_FAB2_LIB.BASEBOARD_FAB2(SCH_1):PAGE268_I38@MSTR_TTL.TTL3126(CHIPS)'(2):
 'B'<2>: CDS_PINID='B(2)';
NET_NAME
'JTAG_BMC_TCK'
 '@BASEBOARD_FAB2_LIB.BASEBOARD_FAB2(SCH_1):JTAG_BMC_TCK':
 C_SIGNAL='@baseboard_fab2_lib.baseboard_fab2(sch_1):jtag_bmc_tck';
NODE_NAME     R8G17 1
 '@BASEBOARD_FAB2_LIB.BASEBOARD_FAB2(SCH_1):PAGE189_I25@MSTR_DISCRETE.RES(CHIPS)':
 'A': CDS_PINID='A';
NODE_NAME     U25W4 C10
 '@BASEBOARD_FAB2_LIB.BASEBOARD_FAB2(SCH_1):PAGE144_I95@W_HDL.AST2520A1-GP-GP(CHIPS)':
 'TCK': CDS_PINID='TCK';
NODE_NAME     U25W19 2
 '@BASEBOARD_FAB2_LIB.BASEBOARD_FAB2(SCH_1):PAGE269_I76@MSTR_TTL.TTL1G126_A(CHIPS)':
 'A': CDS_PINID='A';
NET_NAME
'JTAG_BMC_TCK0'
 '@BASEBOARD_FAB2_LIB.BASEBOARD_FAB2(SCH_1):JTAG_BMC_TCK0':
 C_SIGNAL='@baseboard_fab2_lib.baseboard_fab2(sch_1):jtag_bmc_tck0';
NODE_NAME     R25W168 1
 '@BASEBOARD_FAB2_LIB.BASEBOARD_FAB2(SCH_1):PAGE269_I11@MSTR_DISCRETE.RES(CHIPS)':
 'A': CDS_PINID='A';
NODE_NAME     U25W12 4
 '@BASEBOARD_FAB2_LIB.BASEBOARD_FAB2(SCH_1):PAGE269_I33@MSTR_TTL.TTL3126(CHIPS)'(2):
 'OE'<2>: CDS_PINID='OE(2)';
NODE_NAME     U25W13 1
 '@BASEBOARD_FAB2_LIB.BASEBOARD_FAB2(SCH_1):PAGE269_I53@W_HDL.MAX4564EKA-GP(CHIPS)':
 'NC': CDS_PINID='NC';
NET_NAME
'JTAG_BMC_TCK1'
 '@BASEBOARD_FAB2_LIB.BASEBOARD_FAB2(SCH_1):JTAG_BMC_TCK1':
 C_SIGNAL='@baseboard_fab2_lib.baseboard_fab2(sch_1):jtag_bmc_tck1';
NODE_NAME     R25W169 1
 '@BASEBOARD_FAB2_LIB.BASEBOARD_FAB2(SCH_1):PAGE269_I12@MSTR_DISCRETE.RES(CHIPS)':
 'A': CDS_PINID='A';
NODE_NAME     U25W12 10
 '@BASEBOARD_FAB2_LIB.BASEBOARD_FAB2(SCH_1):PAGE269_I33@MSTR_TTL.TTL3126(CHIPS)'(1):
 'OE'<1>: CDS_PINID='OE(1)';
NODE_NAME     U25W13 4
 '@BASEBOARD_FAB2_LIB.BASEBOARD_FAB2(SCH_1):PAGE269_I53@W_HDL.MAX4564EKA-GP(CHIPS)':
 'NO': CDS_PINID='NO';
NET_NAME
'JTAG_BMC_TCK_BUF'
 '@BASEBOARD_FAB2_LIB.BASEBOARD_FAB2(SCH_1):JTAG_BMC_TCK_BUF':
 C_SIGNAL='@baseboard_fab2_lib.baseboard_fab2(sch_1):jtag_bmc_tck_buf';
NODE_NAME     U25W13 8
 '@BASEBOARD_FAB2_LIB.BASEBOARD_FAB2(SCH_1):PAGE269_I53@W_HDL.MAX4564EKA-GP(CHIPS)':
 'COM': CDS_PINID='COM';
NODE_NAME     U25W19 4
 '@BASEBOARD_FAB2_LIB.BASEBOARD_FAB2(SCH_1):PAGE269_I76@MSTR_TTL.TTL1G126_A(CHIPS)':
 'Y': CDS_PINID='Y';
NET_NAME
'JTAG_BMC_TDI'
 '@BASEBOARD_FAB2_LIB.BASEBOARD_FAB2(SCH_1):JTAG_BMC_TDI':
 C_SIGNAL='@baseboard_fab2_lib.baseboard_fab2(sch_1):jtag_bmc_tdi';
NODE_NAME     R8G8 1
 '@BASEBOARD_FAB2_LIB.BASEBOARD_FAB2(SCH_1):PAGE189_I17@MSTR_DISCRETE.RES(CHIPS)':
 'A': CDS_PINID='A';
NODE_NAME     U25W4 D12
 '@BASEBOARD_FAB2_LIB.BASEBOARD_FAB2(SCH_1):PAGE144_I95@W_HDL.AST2520A1-GP-GP(CHIPS)':
 'TDI': CDS_PINID='TDI';
NODE_NAME     U25W16 2
 '@BASEBOARD_FAB2_LIB.BASEBOARD_FAB2(SCH_1):PAGE268_I38@MSTR_TTL.TTL3126(CHIPS)'(3):
 'A'<3>: CDS_PINID='A(3)';
NET_NAME
'JTAG_BMC_TDO'
 '@BASEBOARD_FAB2_LIB.BASEBOARD_FAB2(SCH_1):JTAG_BMC_TDO':
 C_SIGNAL='@baseboard_fab2_lib.baseboard_fab2(sch_1):jtag_bmc_tdo';
NODE_NAME     R7G17 1
 '@BASEBOARD_FAB2_LIB.BASEBOARD_FAB2(SCH_1):PAGE189_I37@MSTR_DISCRETE.RES(CHIPS)':
 'A': CDS_PINID='A';
NODE_NAME     U25W4 D11
 '@BASEBOARD_FAB2_LIB.BASEBOARD_FAB2(SCH_1):PAGE144_I95@W_HDL.AST2520A1-GP-GP(CHIPS)':
 'TDO': CDS_PINID='TDO';
NODE_NAME     U25W16 9
 '@BASEBOARD_FAB2_LIB.BASEBOARD_FAB2(SCH_1):PAGE268_I38@MSTR_TTL.TTL3126(CHIPS)'(1):
 'A'<1>: CDS_PINID='A(1)';
NET_NAME
'JTAG_BMC_TMS'
 '@BASEBOARD_FAB2_LIB.BASEBOARD_FAB2(SCH_1):JTAG_BMC_TMS':
 C_SIGNAL='@baseboard_fab2_lib.baseboard_fab2(sch_1):jtag_bmc_tms';
NODE_NAME     R8G14 1
 '@BASEBOARD_FAB2_LIB.BASEBOARD_FAB2(SCH_1):PAGE189_I20@MSTR_DISCRETE.RES(CHIPS)':
 'A': CDS_PINID='A';
NODE_NAME     U25W4 C8
 '@BASEBOARD_FAB2_LIB.BASEBOARD_FAB2(SCH_1):PAGE144_I95@W_HDL.AST2520A1-GP-GP(CHIPS)':
 'TMS': CDS_PINID='TMS';
NODE_NAME     U25W16 5
 '@BASEBOARD_FAB2_LIB.BASEBOARD_FAB2(SCH_1):PAGE268_I38@MSTR_TTL.TTL3126(CHIPS)'(2):
 'A'<2>: CDS_PINID='A(2)';
NET_NAME
'JTAG_BMC_TRST_BUF_N'
 '@BASEBOARD_FAB2_LIB.BASEBOARD_FAB2(SCH_1):JTAG_BMC_TRST_BUF_N':
 C_SIGNAL='@baseboard_fab2_lib.baseboard_fab2(sch_1):jtag_bmc_trst_buf_n';
NODE_NAME     R25W170 1
 '@BASEBOARD_FAB2_LIB.BASEBOARD_FAB2(SCH_1):PAGE269_I13@MSTR_DISCRETE.RES(CHIPS)':
 'A': CDS_PINID='A';
NODE_NAME     U25W12 13
 '@BASEBOARD_FAB2_LIB.BASEBOARD_FAB2(SCH_1):PAGE269_I33@MSTR_TTL.TTL3126(CHIPS)'(0):
 'OE'<0>: CDS_PINID='OE(0)';
NODE_NAME     U25W17 4
 '@BASEBOARD_FAB2_LIB.BASEBOARD_FAB2(SCH_1):PAGE269_I61@MSTR_TTL.TTL1G08(CHIPS)':
 'Y'<0>: CDS_PINID='Y(0)';
NET_NAME
'JTAG_BMC_TRST_N'
 '@BASEBOARD_FAB2_LIB.BASEBOARD_FAB2(SCH_1):JTAG_BMC_TRST_N':
 C_SIGNAL='@baseboard_fab2_lib.baseboard_fab2(sch_1):jtag_bmc_trst_n';
NODE_NAME     R8G10 1
 '@BASEBOARD_FAB2_LIB.BASEBOARD_FAB2(SCH_1):PAGE189_I7@MSTR_DISCRETE.RES(CHIPS)':
 'A': CDS_PINID='A';
NODE_NAME     U25W4 E11
 '@BASEBOARD_FAB2_LIB.BASEBOARD_FAB2(SCH_1):PAGE144_I95@W_HDL.AST2520A1-GP-GP(CHIPS)':
 'NTRST': CDS_PINID='NTRST';
NODE_NAME     U25W17 1
 '@BASEBOARD_FAB2_LIB.BASEBOARD_FAB2(SCH_1):PAGE269_I61@MSTR_TTL.TTL1G08(CHIPS)':
 'A'<0>: CDS_PINID='A(0)';
NODE_NAME     R8W12 2
 '@BASEBOARD_FAB2_LIB.BASEBOARD_FAB2(SCH_1):PAGE245_I58@MSTR_DISCRETE.RES(CHIPS)':
 'B': CDS_PINID='B';
NET_NAME
'JTAG_MCP_CPU0_TDI'
 '@BASEBOARD_FAB2_LIB.BASEBOARD_FAB2(SCH_1):JTAG_MCP_CPU0_TDI':
 C_SIGNAL='@baseboard_fab2_lib.baseboard_fab2(sch_1):jtag_mcp_cpu0_tdi';
NODE_NAME     U5D1 BY21
 '@BASEBOARD_FAB2_LIB.BASEBOARD_FAB2(SCH_1):PAGE29_I61@CHPSET_LIB.SKX_EXT_B(CHIPS)':
 'CD_TDI': CDS_PINID='CD_TDI';
NODE_NAME     U2M1 1
 '@BASEBOARD_FAB2_LIB.BASEBOARD_FAB2(SCH_1):PAGE113_I255@MSTR_ANALOG.NC7SB3157(CHIPS)':
 'B1': CDS_PINID='B1';
NODE_NAME     R4R6 2
 '@BASEBOARD_FAB2_LIB.BASEBOARD_FAB2(SCH_1):PAGE113_I270@MSTR_DISCRETE.RES(CHIPS)':
 'B': CDS_PINID='B';
NET_NAME
'JTAG_MCP_CPU0_TDI_R'
 '@BASEBOARD_FAB2_LIB.BASEBOARD_FAB2(SCH_1):JTAG_MCP_CPU0_TDI_R':
 C_SIGNAL='@baseboard_fab2_lib.baseboard_fab2(sch_1):jtag_mcp_cpu0_tdi_r';
NODE_NAME     U4R1 4
 '@BASEBOARD_FAB2_LIB.BASEBOARD_FAB2(SCH_1):PAGE113_I206@MSTR_TTL.74CBTLV1G125(CHIPS)':
 'B': CDS_PINID='B';
NODE_NAME     C4R2 1
 '@BASEBOARD_FAB2_LIB.BASEBOARD_FAB2(SCH_1):PAGE113_I246@DEV_DISCRETE.CAP_A(CHIPS)':
 'A': CDS_PINID='A';
NODE_NAME     R4R6 1
 '@BASEBOARD_FAB2_LIB.BASEBOARD_FAB2(SCH_1):PAGE113_I270@MSTR_DISCRETE.RES(CHIPS)':
 'A': CDS_PINID='A';
NODE_NAME     R5W1 2
 '@BASEBOARD_FAB2_LIB.BASEBOARD_FAB2(SCH_1):PAGE113_I272@MSTR_DISCRETE.RES(CHIPS)':
 'B': CDS_PINID='B';
NET_NAME
'JTAG_MCP_CPU0_TDO'
 '@BASEBOARD_FAB2_LIB.BASEBOARD_FAB2(SCH_1):JTAG_MCP_CPU0_TDO':
 C_SIGNAL='@baseboard_fab2_lib.baseboard_fab2(sch_1):jtag_mcp_cpu0_tdo';
NODE_NAME     U5D1 CC22
 '@BASEBOARD_FAB2_LIB.BASEBOARD_FAB2(SCH_1):PAGE29_I61@CHPSET_LIB.SKX_EXT_B(CHIPS)':
 'CD_TDO': CDS_PINID='CD_TDO';
NODE_NAME     U1M2 1
 '@BASEBOARD_FAB2_LIB.BASEBOARD_FAB2(SCH_1):PAGE113_I107@MSTR_ANALOG.NC7SB3157(CHIPS)':
 'B1': CDS_PINID='B1';
NODE_NAME     U1M6 2
 '@BASEBOARD_FAB2_LIB.BASEBOARD_FAB2(SCH_1):PAGE113_I127@MSTR_TTL.74CBTLV1G125(CHIPS)':
 'A': CDS_PINID='A';
NET_NAME
'JTAG_MCP_CPU1_TDI'
 '@BASEBOARD_FAB2_LIB.BASEBOARD_FAB2(SCH_1):JTAG_MCP_CPU1_TDI':
 C_SIGNAL='@baseboard_fab2_lib.baseboard_fab2(sch_1):jtag_mcp_cpu1_tdi';
NODE_NAME     U2D1 BY21
 '@BASEBOARD_FAB2_LIB.BASEBOARD_FAB2(SCH_1):PAGE63_I23@CHPSET_LIB.SKX_EXT_B(CHIPS)':
 'CD_TDI': CDS_PINID='CD_TDI';
NODE_NAME     U1M6 4
 '@BASEBOARD_FAB2_LIB.BASEBOARD_FAB2(SCH_1):PAGE113_I127@MSTR_TTL.74CBTLV1G125(CHIPS)':
 'B': CDS_PINID='B';
NODE_NAME     U2M1 3
 '@BASEBOARD_FAB2_LIB.BASEBOARD_FAB2(SCH_1):PAGE113_I255@MSTR_ANALOG.NC7SB3157(CHIPS)':
 'B0': CDS_PINID='B0';
NODE_NAME     R6M8 2
 '@BASEBOARD_FAB2_LIB.BASEBOARD_FAB2(SCH_1):PAGE113_I271@MSTR_DISCRETE.RES(CHIPS)':
 'B': CDS_PINID='B';
NET_NAME
'JTAG_MCP_CPU1_TDI_R'
 '@BASEBOARD_FAB2_LIB.BASEBOARD_FAB2(SCH_1):JTAG_MCP_CPU1_TDI_R':
 C_SIGNAL='@baseboard_fab2_lib.baseboard_fab2(sch_1):jtag_mcp_cpu1_tdi_r';
NODE_NAME     U6M1 4
 '@BASEBOARD_FAB2_LIB.BASEBOARD_FAB2(SCH_1):PAGE113_I190@MSTR_TTL.74CBTLV1G125(CHIPS)':
 'B': CDS_PINID='B';
NODE_NAME     C6M6 1
 '@BASEBOARD_FAB2_LIB.BASEBOARD_FAB2(SCH_1):PAGE113_I250@DEV_DISCRETE.CAP_A(CHIPS)':
 'A': CDS_PINID='A';
NODE_NAME     R6M8 1
 '@BASEBOARD_FAB2_LIB.BASEBOARD_FAB2(SCH_1):PAGE113_I271@MSTR_DISCRETE.RES(CHIPS)':
 'A': CDS_PINID='A';
NODE_NAME     R5W2 2
 '@BASEBOARD_FAB2_LIB.BASEBOARD_FAB2(SCH_1):PAGE113_I273@MSTR_DISCRETE.RES(CHIPS)':
 'B': CDS_PINID='B';
NET_NAME
'JTAG_MCP_CPU1_TDO'
 '@BASEBOARD_FAB2_LIB.BASEBOARD_FAB2(SCH_1):JTAG_MCP_CPU1_TDO':
 C_SIGNAL='@baseboard_fab2_lib.baseboard_fab2(sch_1):jtag_mcp_cpu1_tdo';
NODE_NAME     U2D1 CC22
 '@BASEBOARD_FAB2_LIB.BASEBOARD_FAB2(SCH_1):PAGE63_I23@CHPSET_LIB.SKX_EXT_B(CHIPS)':
 'CD_TDO': CDS_PINID='CD_TDO';
NODE_NAME     U1M2 3
 '@BASEBOARD_FAB2_LIB.BASEBOARD_FAB2(SCH_1):PAGE113_I107@MSTR_ANALOG.NC7SB3157(CHIPS)':
 'B0': CDS_PINID='B0';
NET_NAME
'JTAG_MCP_MUX_TDI'
 '@BASEBOARD_FAB2_LIB.BASEBOARD_FAB2(SCH_1):JTAG_MCP_MUX_TDI':
 C_SIGNAL='@baseboard_fab2_lib.baseboard_fab2(sch_1):jtag_mcp_mux_tdi';
NODE_NAME     J9B4 9
 '@BASEBOARD_FAB2_LIB.BASEBOARD_FAB2(SCH_1):PAGE113_I175@MSTR_SCONN.SCONN10_C12536004(CHIPS)':
 'IO9': CDS_PINID='IO9';
NODE_NAME     R1M20 2
 '@BASEBOARD_FAB2_LIB.BASEBOARD_FAB2(SCH_1):PAGE113_I204@MSTR_DISCRETE.RES(CHIPS)':
 'B': CDS_PINID='B';
NODE_NAME     U2M1 4
 '@BASEBOARD_FAB2_LIB.BASEBOARD_FAB2(SCH_1):PAGE113_I255@MSTR_ANALOG.NC7SB3157(CHIPS)':
 'A': CDS_PINID='A';
NET_NAME
'JTAG_MCP_MUX_TDO'
 '@BASEBOARD_FAB2_LIB.BASEBOARD_FAB2(SCH_1):JTAG_MCP_MUX_TDO':
 C_SIGNAL='@baseboard_fab2_lib.baseboard_fab2(sch_1):jtag_mcp_mux_tdo';
NODE_NAME     U1M2 4
 '@BASEBOARD_FAB2_LIB.BASEBOARD_FAB2(SCH_1):PAGE113_I107@MSTR_ANALOG.NC7SB3157(CHIPS)':
 'A': CDS_PINID='A';
NODE_NAME     J9B4 3
 '@BASEBOARD_FAB2_LIB.BASEBOARD_FAB2(SCH_1):PAGE113_I175@MSTR_SCONN.SCONN10_C12536004(CHIPS)':
 'IO3': CDS_PINID='IO3';
NODE_NAME     R9B12 2
 '@BASEBOARD_FAB2_LIB.BASEBOARD_FAB2(SCH_1):PAGE113_I203@MSTR_DISCRETE.RES(CHIPS)':
 'B': CDS_PINID='B';
NET_NAME
'JTAG_MCP_TCK'
 '@BASEBOARD_FAB2_LIB.BASEBOARD_FAB2(SCH_1):JTAG_MCP_TCK':
 C_SIGNAL='@baseboard_fab2_lib.baseboard_fab2(sch_1):jtag_mcp_tck';
NODE_NAME     U5D1 CB23
 '@BASEBOARD_FAB2_LIB.BASEBOARD_FAB2(SCH_1):PAGE29_I61@CHPSET_LIB.SKX_EXT_B(CHIPS)':
 'CD_TCLK': CDS_PINID='CD_TCLK';
NODE_NAME     U2D1 CB23
 '@BASEBOARD_FAB2_LIB.BASEBOARD_FAB2(SCH_1):PAGE63_I23@CHPSET_LIB.SKX_EXT_B(CHIPS)':
 'CD_TCLK': CDS_PINID='CD_TCLK';
NODE_NAME     R9B9 1
 '@BASEBOARD_FAB2_LIB.BASEBOARD_FAB2(SCH_1):PAGE113_I179@MSTR_DISCRETE.RES(CHIPS)':
 'A': CDS_PINID='A';
NODE_NAME     R9B10 1
 '@BASEBOARD_FAB2_LIB.BASEBOARD_FAB2(SCH_1):PAGE113_I180@MSTR_DISCRETE.RES(CHIPS)':
 'A': CDS_PINID='A';
NODE_NAME     R9B11 1
 '@BASEBOARD_FAB2_LIB.BASEBOARD_FAB2(SCH_1):PAGE113_I239@MSTR_DISCRETE.RES(CHIPS)':
 'A': CDS_PINID='A';
NET_NAME
'JTAG_MCP_TCK_R'
 '@BASEBOARD_FAB2_LIB.BASEBOARD_FAB2(SCH_1):JTAG_MCP_TCK_R':
 C_SIGNAL='@baseboard_fab2_lib.baseboard_fab2(sch_1):jtag_mcp_tck_r';
NODE_NAME     J9B4 1
 '@BASEBOARD_FAB2_LIB.BASEBOARD_FAB2(SCH_1):PAGE113_I175@MSTR_SCONN.SCONN10_C12536004(CHIPS)':
 'IO1': CDS_PINID='IO1';
NODE_NAME     R9B11 2
 '@BASEBOARD_FAB2_LIB.BASEBOARD_FAB2(SCH_1):PAGE113_I239@MSTR_DISCRETE.RES(CHIPS)':
 'B': CDS_PINID='B';
NET_NAME
'JTAG_MCP_TCK_R1'
 '@BASEBOARD_FAB2_LIB.BASEBOARD_FAB2(SCH_1):JTAG_MCP_TCK_R1':
 C_SIGNAL='@baseboard_fab2_lib.baseboard_fab2(sch_1):jtag_mcp_tck_r1';
NODE_NAME     R9B10 2
 '@BASEBOARD_FAB2_LIB.BASEBOARD_FAB2(SCH_1):PAGE113_I180@MSTR_DISCRETE.RES(CHIPS)':
 'B': CDS_PINID='B';
NODE_NAME     U9A5 2
 '@BASEBOARD_FAB2_LIB.BASEBOARD_FAB2(SCH_1):PAGE113_I185@MSTR_TTL.74CBTLV1G125(CHIPS)':
 'A': CDS_PINID='A';
NET_NAME
'JTAG_MCP_TMS'
 '@BASEBOARD_FAB2_LIB.BASEBOARD_FAB2(SCH_1):JTAG_MCP_TMS':
 C_SIGNAL='@baseboard_fab2_lib.baseboard_fab2(sch_1):jtag_mcp_tms';
NODE_NAME     U5D1 CE24
 '@BASEBOARD_FAB2_LIB.BASEBOARD_FAB2(SCH_1):PAGE29_I61@CHPSET_LIB.SKX_EXT_B(CHIPS)':
 'CD_TMS': CDS_PINID='CD_TMS';
NODE_NAME     U2D1 CE24
 '@BASEBOARD_FAB2_LIB.BASEBOARD_FAB2(SCH_1):PAGE63_I23@CHPSET_LIB.SKX_EXT_B(CHIPS)':
 'CD_TMS': CDS_PINID='CD_TMS';
NODE_NAME     R1M22 2
 '@BASEBOARD_FAB2_LIB.BASEBOARD_FAB2(SCH_1):PAGE113_I195@MSTR_DISCRETE.RES(CHIPS)':
 'B': CDS_PINID='B';
NODE_NAME     R1M19 2
 '@BASEBOARD_FAB2_LIB.BASEBOARD_FAB2(SCH_1):PAGE113_I202@MSTR_DISCRETE.RES(CHIPS)':
 'B': CDS_PINID='B';
NODE_NAME     R9B13 1
 '@BASEBOARD_FAB2_LIB.BASEBOARD_FAB2(SCH_1):PAGE113_I240@MSTR_DISCRETE.RES(CHIPS)':
 'A': CDS_PINID='A';
NET_NAME
'JTAG_MCP_TMS_R'
 '@BASEBOARD_FAB2_LIB.BASEBOARD_FAB2(SCH_1):JTAG_MCP_TMS_R':
 C_SIGNAL='@baseboard_fab2_lib.baseboard_fab2(sch_1):jtag_mcp_tms_r';
NODE_NAME     J9B4 5
 '@BASEBOARD_FAB2_LIB.BASEBOARD_FAB2(SCH_1):PAGE113_I175@MSTR_SCONN.SCONN10_C12536004(CHIPS)':
 'IO5': CDS_PINID='IO5';
NODE_NAME     R9B13 2
 '@BASEBOARD_FAB2_LIB.BASEBOARD_FAB2(SCH_1):PAGE113_I240@MSTR_DISCRETE.RES(CHIPS)':
 'B': CDS_PINID='B';
NET_NAME
'JTAG_MCP_TMS_R1'
 '@BASEBOARD_FAB2_LIB.BASEBOARD_FAB2(SCH_1):JTAG_MCP_TMS_R1':
 C_SIGNAL='@baseboard_fab2_lib.baseboard_fab2(sch_1):jtag_mcp_tms_r1';
NODE_NAME     R1M22 1
 '@BASEBOARD_FAB2_LIB.BASEBOARD_FAB2(SCH_1):PAGE113_I195@MSTR_DISCRETE.RES(CHIPS)':
 'A': CDS_PINID='A';
NODE_NAME     U1M5 4
 '@BASEBOARD_FAB2_LIB.BASEBOARD_FAB2(SCH_1):PAGE113_I196@MSTR_TTL.74CBTLV1G125(CHIPS)':
 'B': CDS_PINID='B';
NODE_NAME     C1M33 1
 '@BASEBOARD_FAB2_LIB.BASEBOARD_FAB2(SCH_1):PAGE113_I248@DEV_DISCRETE.CAP_A(CHIPS)':
 'A': CDS_PINID='A';
NET_NAME
'JTAG_MCP_TRST_N'
 '@BASEBOARD_FAB2_LIB.BASEBOARD_FAB2(SCH_1):JTAG_MCP_TRST_N':
 C_SIGNAL='@baseboard_fab2_lib.baseboard_fab2(sch_1):jtag_mcp_trst_n';
NODE_NAME     U5D1 CD23
 '@BASEBOARD_FAB2_LIB.BASEBOARD_FAB2(SCH_1):PAGE29_I61@CHPSET_LIB.SKX_EXT_B(CHIPS)':
 'CD_TRST_N': CDS_PINID='CD_TRST_N';
NODE_NAME     U2D1 CD23
 '@BASEBOARD_FAB2_LIB.BASEBOARD_FAB2(SCH_1):PAGE63_I23@CHPSET_LIB.SKX_EXT_B(CHIPS)':
 'CD_TRST_N': CDS_PINID='CD_TRST_N';
NODE_NAME     J9B4 6
 '@BASEBOARD_FAB2_LIB.BASEBOARD_FAB2(SCH_1):PAGE113_I175@MSTR_SCONN.SCONN10_C12536004(CHIPS)':
 'IO6': CDS_PINID='IO6';
NODE_NAME     R1M23 1
 '@BASEBOARD_FAB2_LIB.BASEBOARD_FAB2(SCH_1):PAGE113_I199@MSTR_DISCRETE.RES(CHIPS)':
 'A': CDS_PINID='A';
NODE_NAME     R1M21 2
 '@BASEBOARD_FAB2_LIB.BASEBOARD_FAB2(SCH_1):PAGE113_I205@MSTR_DISCRETE.RES(CHIPS)':
 'B': CDS_PINID='B';
NET_NAME
'JTAG_PCH_GBE_CLK'
 '@BASEBOARD_FAB2_LIB.BASEBOARD_FAB2(SCH_1):JTAG_PCH_GBE_CLK':
 C_SIGNAL='@baseboard_fab2_lib.baseboard_fab2(sch_1):jtag_pch_gbe_clk';
NODE_NAME     U7C1 BV21
 '@BASEBOARD_FAB2_LIB.BASEBOARD_FAB2(SCH_1):PAGE120_I147@MSTR_U_PROC.LBG_CORE_QAT_EXT_D(CHIPS)':
 'GPP_I1_LAN_TCK': CDS_PINID='GPP_I1_LAN_TCK';
NODE_NAME     R8G15 1
 '@BASEBOARD_FAB2_LIB.BASEBOARD_FAB2(SCH_1):PAGE189_I24@MSTR_DISCRETE.RES(CHIPS)':
 'A': CDS_PINID='A';
NET_NAME
'JTAG_PCH_GBE_TDI'
 '@BASEBOARD_FAB2_LIB.BASEBOARD_FAB2(SCH_1):JTAG_PCH_GBE_TDI':
 C_SIGNAL='@baseboard_fab2_lib.baseboard_fab2(sch_1):jtag_pch_gbe_tdi';
NODE_NAME     U7C1 BY23
 '@BASEBOARD_FAB2_LIB.BASEBOARD_FAB2(SCH_1):PAGE120_I147@MSTR_U_PROC.LBG_CORE_QAT_EXT_D(CHIPS)':
 'GPP_I3_LAN_TDI': CDS_PINID='GPP_I3_LAN_TDI';
NODE_NAME     R7G19 1
 '@BASEBOARD_FAB2_LIB.BASEBOARD_FAB2(SCH_1):PAGE189_I8@MSTR_DISCRETE.RES(CHIPS)':
 'A': CDS_PINID='A';
NET_NAME
'JTAG_PCH_GBE_TDO'
 '@BASEBOARD_FAB2_LIB.BASEBOARD_FAB2(SCH_1):JTAG_PCH_GBE_TDO':
 C_SIGNAL='@baseboard_fab2_lib.baseboard_fab2(sch_1):jtag_pch_gbe_tdo';
NODE_NAME     U7C1 CA20
 '@BASEBOARD_FAB2_LIB.BASEBOARD_FAB2(SCH_1):PAGE120_I147@MSTR_U_PROC.LBG_CORE_QAT_EXT_D(CHIPS)':
 'GPP_I0_LAN_TDO': CDS_PINID='GPP_I0_LAN_TDO';
NODE_NAME     R7G16 1
 '@BASEBOARD_FAB2_LIB.BASEBOARD_FAB2(SCH_1):PAGE189_I27@MSTR_DISCRETE.RES(CHIPS)':
 'A': CDS_PINID='A';
NET_NAME
'JTAG_PCH_GBE_TMS'
 '@BASEBOARD_FAB2_LIB.BASEBOARD_FAB2(SCH_1):JTAG_PCH_GBE_TMS':
 C_SIGNAL='@baseboard_fab2_lib.baseboard_fab2(sch_1):jtag_pch_gbe_tms';
NODE_NAME     U7C1 CA22
 '@BASEBOARD_FAB2_LIB.BASEBOARD_FAB2(SCH_1):PAGE120_I147@MSTR_U_PROC.LBG_CORE_QAT_EXT_D(CHIPS)':
 'GPP_I2_LAN_TMS': CDS_PINID='GPP_I2_LAN_TMS';
NODE_NAME     R8G12 1
 '@BASEBOARD_FAB2_LIB.BASEBOARD_FAB2(SCH_1):PAGE189_I21@MSTR_DISCRETE.RES(CHIPS)':
 'A': CDS_PINID='A';
NET_NAME
'JTAG_PCH_GBE_TRST_N'
 '@BASEBOARD_FAB2_LIB.BASEBOARD_FAB2(SCH_1):JTAG_PCH_GBE_TRST_N':
 C_SIGNAL='@baseboard_fab2_lib.baseboard_fab2(sch_1):jtag_pch_gbe_trst_n';
NODE_NAME     U7C1 CA24
 '@BASEBOARD_FAB2_LIB.BASEBOARD_FAB2(SCH_1):PAGE120_I147@MSTR_U_PROC.LBG_CORE_QAT_EXT_D(CHIPS)':
 'GPP_I7_LAN_TRST_N': CDS_PINID='GPP_I7_LAN_TRST_N';
NODE_NAME     R8G9 1
 '@BASEBOARD_FAB2_LIB.BASEBOARD_FAB2(SCH_1):PAGE189_I9@MSTR_DISCRETE.RES(CHIPS)':
 'A': CDS_PINID='A';
NET_NAME
'JTAG_PCH_PLD_TCK'
 '@BASEBOARD_FAB2_LIB.BASEBOARD_FAB2(SCH_1):JTAG_PCH_PLD_TCK':
 C_SIGNAL='@baseboard_fab2_lib.baseboard_fab2(sch_1):jtag_pch_pld_tck';
NODE_NAME     U7C1 AL18
 '@BASEBOARD_FAB2_LIB.BASEBOARD_FAB2(SCH_1):PAGE120_I147@MSTR_U_PROC.LBG_CORE_QAT_EXT_D(CHIPS)':
 'GPP_F6_SATA_DEVSLP4': CDS_PINID='GPP_F6_SATA_DEVSLP4';
NODE_NAME     R8G16 1
 '@BASEBOARD_FAB2_LIB.BASEBOARD_FAB2(SCH_1):PAGE189_I22@MSTR_DISCRETE.RES(CHIPS)':
 'A': CDS_PINID='A';
NET_NAME
'JTAG_PCH_PLD_TDI'
 '@BASEBOARD_FAB2_LIB.BASEBOARD_FAB2(SCH_1):JTAG_PCH_PLD_TDI':
 C_SIGNAL='@baseboard_fab2_lib.baseboard_fab2(sch_1):jtag_pch_pld_tdi';
NODE_NAME     U7C1 AK17
 '@BASEBOARD_FAB2_LIB.BASEBOARD_FAB2(SCH_1):PAGE120_I147@MSTR_U_PROC.LBG_CORE_QAT_EXT_D(CHIPS)':
 'GPP_F7_SATA_DEVSLP5': CDS_PINID='GPP_F7_SATA_DEVSLP5';
NODE_NAME     R7G18 1
 '@BASEBOARD_FAB2_LIB.BASEBOARD_FAB2(SCH_1):PAGE189_I13@MSTR_DISCRETE.RES(CHIPS)':
 'A': CDS_PINID='A';
NET_NAME
'JTAG_PCH_PLD_TDO'
 '@BASEBOARD_FAB2_LIB.BASEBOARD_FAB2(SCH_1):JTAG_PCH_PLD_TDO':
 C_SIGNAL='@baseboard_fab2_lib.baseboard_fab2(sch_1):jtag_pch_pld_tdo';
NODE_NAME     U7C1 AR20
 '@BASEBOARD_FAB2_LIB.BASEBOARD_FAB2(SCH_1):PAGE120_I147@MSTR_U_PROC.LBG_CORE_QAT_EXT_D(CHIPS)':
 'GPP_F9_SATA_DEVSLP7': CDS_PINID='GPP_F9_SATA_DEVSLP7';
NODE_NAME     R7G15 1
 '@BASEBOARD_FAB2_LIB.BASEBOARD_FAB2(SCH_1):PAGE189_I36@MSTR_DISCRETE.RES(CHIPS)':
 'A': CDS_PINID='A';
NET_NAME
'JTAG_PCH_PLD_TMS'
 '@BASEBOARD_FAB2_LIB.BASEBOARD_FAB2(SCH_1):JTAG_PCH_PLD_TMS':
 C_SIGNAL='@baseboard_fab2_lib.baseboard_fab2(sch_1):jtag_pch_pld_tms';
NODE_NAME     U7C1 AH9
 '@BASEBOARD_FAB2_LIB.BASEBOARD_FAB2(SCH_1):PAGE120_I147@MSTR_U_PROC.LBG_CORE_QAT_EXT_D(CHIPS)':
 'GPP_F8_SATA_DEVSLP6': CDS_PINID='GPP_F8_SATA_DEVSLP6';
NODE_NAME     R8G11 1
 '@BASEBOARD_FAB2_LIB.BASEBOARD_FAB2(SCH_1):PAGE189_I19@MSTR_DISCRETE.RES(CHIPS)':
 'A': CDS_PINID='A';
NET_NAME
'JTAG_PLD_TCK'
 '@BASEBOARD_FAB2_LIB.BASEBOARD_FAB2(SCH_1):JTAG_PLD_TCK':
 C_SIGNAL='@baseboard_fab2_lib.baseboard_fab2(sch_1):jtag_pld_tck';
NODE_NAME     R8G18 1
 '@BASEBOARD_FAB2_LIB.BASEBOARD_FAB2(SCH_1):PAGE189_I26@MSTR_DISCRETE.RES(CHIPS)':
 'A': CDS_PINID='A';
NODE_NAME     U8D7 A7
 '@BASEBOARD_FAB2_LIB.BASEBOARD_FAB2(SCH_1):PAGE191_I59@MSTR_MEMORY.LCMXO2_A(CHIPS)':
 'PT16C_TCK': CDS_PINID='PT16C_TCK';
NET_NAME
'JTAG_PLD_TCK_MUX'
 '@BASEBOARD_FAB2_LIB.BASEBOARD_FAB2(SCH_1):JTAG_PLD_TCK_MUX':
 C_SIGNAL='@baseboard_fab2_lib.baseboard_fab2(sch_1):jtag_pld_tck_mux';
NODE_NAME     R8G18 2
 '@BASEBOARD_FAB2_LIB.BASEBOARD_FAB2(SCH_1):PAGE189_I26@MSTR_DISCRETE.RES(CHIPS)':
 'B': CDS_PINID='B';
NODE_NAME     U1L10 5
 '@BASEBOARD_FAB2_LIB.BASEBOARD_FAB2(SCH_1):PAGE189_I67@MSTR_TTL.TTL3126(CHIPS)'(2):
 'A'<2>: CDS_PINID='A(2)';
NODE_NAME     R8W11 2
 '@BASEBOARD_FAB2_LIB.BASEBOARD_FAB2(SCH_1):PAGE245_I57@MSTR_DISCRETE.RES(CHIPS)':
 'B': CDS_PINID='B';
NET_NAME
'JTAG_PLD_TDI'
 '@BASEBOARD_FAB2_LIB.BASEBOARD_FAB2(SCH_1):JTAG_PLD_TDI':
 C_SIGNAL='@baseboard_fab2_lib.baseboard_fab2(sch_1):jtag_pld_tdi';
NODE_NAME     R8G7 1
 '@BASEBOARD_FAB2_LIB.BASEBOARD_FAB2(SCH_1):PAGE189_I18@MSTR_DISCRETE.RES(CHIPS)':
 'A': CDS_PINID='A';
NODE_NAME     U8D7 A6
 '@BASEBOARD_FAB2_LIB.BASEBOARD_FAB2(SCH_1):PAGE191_I59@MSTR_MEMORY.LCMXO2_A(CHIPS)':
 'PT12D_TDI': CDS_PINID='PT12D_TDI';
NET_NAME
'JTAG_PLD_TDI_MUX'
 '@BASEBOARD_FAB2_LIB.BASEBOARD_FAB2(SCH_1):JTAG_PLD_TDI_MUX':
 C_SIGNAL='@baseboard_fab2_lib.baseboard_fab2(sch_1):jtag_pld_tdi_mux';
NODE_NAME     R8G7 2
 '@BASEBOARD_FAB2_LIB.BASEBOARD_FAB2(SCH_1):PAGE189_I18@MSTR_DISCRETE.RES(CHIPS)':
 'B': CDS_PINID='B';
NODE_NAME     U1L10 12
 '@BASEBOARD_FAB2_LIB.BASEBOARD_FAB2(SCH_1):PAGE189_I67@MSTR_TTL.TTL3126(CHIPS)'(0):
 'A'<0>: CDS_PINID='A(0)';
NET_NAME
'JTAG_PLD_TDO'
 '@BASEBOARD_FAB2_LIB.BASEBOARD_FAB2(SCH_1):JTAG_PLD_TDO':
 C_SIGNAL='@baseboard_fab2_lib.baseboard_fab2(sch_1):jtag_pld_tdo';
NODE_NAME     U8D7 C6
 '@BASEBOARD_FAB2_LIB.BASEBOARD_FAB2(SCH_1):PAGE191_I59@MSTR_MEMORY.LCMXO2_A(CHIPS)':
 'PT12C_TDO': CDS_PINID='PT12C_TDO';
NODE_NAME     U8W1 2
 '@BASEBOARD_FAB2_LIB.BASEBOARD_FAB2(SCH_1):PAGE245_I64@MSTR_TTL.74CBTLV1G125(CHIPS)':
 'A': CDS_PINID='A';
NODE_NAME     U8W2 1
 '@BASEBOARD_FAB2_LIB.BASEBOARD_FAB2(SCH_1):PAGE245_I66@MSTR_ANALOG.NC7SB3157(CHIPS)':
 'B1': CDS_PINID='B1';
NET_NAME
'JTAG_PLD_TDO_MUX'
 '@BASEBOARD_FAB2_LIB.BASEBOARD_FAB2(SCH_1):JTAG_PLD_TDO_MUX':
 C_SIGNAL='@baseboard_fab2_lib.baseboard_fab2(sch_1):jtag_pld_tdo_mux';
NODE_NAME     R7G14 2
 '@BASEBOARD_FAB2_LIB.BASEBOARD_FAB2(SCH_1):PAGE189_I38@MSTR_DISCRETE.RES(CHIPS)':
 'B': CDS_PINID='B';
NODE_NAME     U1L10 2
 '@BASEBOARD_FAB2_LIB.BASEBOARD_FAB2(SCH_1):PAGE189_I67@MSTR_TTL.TTL3126(CHIPS)'(3):
 'A'<3>: CDS_PINID='A(3)';
NET_NAME
'JTAG_PLD_TDO_MUX_R'
 '@BASEBOARD_FAB2_LIB.BASEBOARD_FAB2(SCH_1):JTAG_PLD_TDO_MUX_R':
 C_SIGNAL='@baseboard_fab2_lib.baseboard_fab2(sch_1):jtag_pld_tdo_mux_r';
NODE_NAME     R7G14 1
 '@BASEBOARD_FAB2_LIB.BASEBOARD_FAB2(SCH_1):PAGE189_I38@MSTR_DISCRETE.RES(CHIPS)':
 'A': CDS_PINID='A';
NODE_NAME     U8W2 4
 '@BASEBOARD_FAB2_LIB.BASEBOARD_FAB2(SCH_1):PAGE245_I66@MSTR_ANALOG.NC7SB3157(CHIPS)':
 'A': CDS_PINID='A';
NET_NAME
'JTAG_PLD_TMS'
 '@BASEBOARD_FAB2_LIB.BASEBOARD_FAB2(SCH_1):JTAG_PLD_TMS':
 C_SIGNAL='@baseboard_fab2_lib.baseboard_fab2(sch_1):jtag_pld_tms';
NODE_NAME     R8G13 1
 '@BASEBOARD_FAB2_LIB.BASEBOARD_FAB2(SCH_1):PAGE189_I23@MSTR_DISCRETE.RES(CHIPS)':
 'A': CDS_PINID='A';
NODE_NAME     U8D7 B8
 '@BASEBOARD_FAB2_LIB.BASEBOARD_FAB2(SCH_1):PAGE191_I59@MSTR_MEMORY.LCMXO2_A(CHIPS)':
 'PT16D_TMS': CDS_PINID='PT16D_TMS';
NET_NAME
'JTAG_PLD_TMS_MUX'
 '@BASEBOARD_FAB2_LIB.BASEBOARD_FAB2(SCH_1):JTAG_PLD_TMS_MUX':
 C_SIGNAL='@baseboard_fab2_lib.baseboard_fab2(sch_1):jtag_pld_tms_mux';
NODE_NAME     R8G13 2
 '@BASEBOARD_FAB2_LIB.BASEBOARD_FAB2(SCH_1):PAGE189_I23@MSTR_DISCRETE.RES(CHIPS)':
 'B': CDS_PINID='B';
NODE_NAME     U1L10 9
 '@BASEBOARD_FAB2_LIB.BASEBOARD_FAB2(SCH_1):PAGE189_I67@MSTR_TTL.TTL3126(CHIPS)'(1):
 'A'<1>: CDS_PINID='A(1)';
NODE_NAME     R8W10 2
 '@BASEBOARD_FAB2_LIB.BASEBOARD_FAB2(SCH_1):PAGE245_I56@MSTR_DISCRETE.RES(CHIPS)':
 'B': CDS_PINID='B';
NET_NAME
'JTAG_RISER_N'
 '@BASEBOARD_FAB2_LIB.BASEBOARD_FAB2(SCH_1):JTAG_RISER_N':
 C_SIGNAL='@baseboard_fab2_lib.baseboard_fab2(sch_1):jtag_riser_n';
NODE_NAME     U25W4 B14
 '@BASEBOARD_FAB2_LIB.BASEBOARD_FAB2(SCH_1):PAGE145_I117@W_HDL.AST2520A1-GP-GP(CHIPS)':
 'GPIOA0_MAC1LINK': CDS_PINID='GPIOA0_MAC1LINK';
NODE_NAME     U8W1 1
 '@BASEBOARD_FAB2_LIB.BASEBOARD_FAB2(SCH_1):PAGE245_I64@MSTR_TTL.74CBTLV1G125(CHIPS)':
 'OE_N': CDS_PINID='OE_N';
NODE_NAME     U8W2 6
 '@BASEBOARD_FAB2_LIB.BASEBOARD_FAB2(SCH_1):PAGE245_I66@MSTR_ANALOG.NC7SB3157(CHIPS)':
 'S': CDS_PINID='S';
NODE_NAME     R8W15 2
 '@BASEBOARD_FAB2_LIB.BASEBOARD_FAB2(SCH_1):PAGE245_I78@MSTR_DISCRETE.RES(CHIPS)':
 'B': CDS_PINID='B';
NET_NAME
'JTAG_RISER_TCK'
 '@BASEBOARD_FAB2_LIB.BASEBOARD_FAB2(SCH_1):JTAG_RISER_TCK':
 C_SIGNAL='@baseboard_fab2_lib.baseboard_fab2(sch_1):jtag_riser_tck';
NODE_NAME     CONX8 56
 '@BASEBOARD_FAB2_LIB.BASEBOARD_FAB2(SCH_1):PAGE245_I48@W_HDL.SMC-CONN60A-22-GP(CHIPS)':
 '56': CDS_PINID='\56\';
NODE_NAME     R8W11 1
 '@BASEBOARD_FAB2_LIB.BASEBOARD_FAB2(SCH_1):PAGE245_I57@MSTR_DISCRETE.RES(CHIPS)':
 'A': CDS_PINID='A';
NET_NAME
'JTAG_RISER_TDI'
 '@BASEBOARD_FAB2_LIB.BASEBOARD_FAB2(SCH_1):JTAG_RISER_TDI':
 C_SIGNAL='@baseboard_fab2_lib.baseboard_fab2(sch_1):jtag_riser_tdi';
NODE_NAME     CONX8 51
 '@BASEBOARD_FAB2_LIB.BASEBOARD_FAB2(SCH_1):PAGE245_I48@W_HDL.SMC-CONN60A-22-GP(CHIPS)':
 '51': CDS_PINID='\51\';
NODE_NAME     R8W13 2
 '@BASEBOARD_FAB2_LIB.BASEBOARD_FAB2(SCH_1):PAGE245_I59@MSTR_DISCRETE.RES(CHIPS)':
 'B': CDS_PINID='B';
NET_NAME
'JTAG_RISER_TDI_R'
 '@BASEBOARD_FAB2_LIB.BASEBOARD_FAB2(SCH_1):JTAG_RISER_TDI_R':
 C_SIGNAL='@baseboard_fab2_lib.baseboard_fab2(sch_1):jtag_riser_tdi_r';
NODE_NAME     R8W13 1
 '@BASEBOARD_FAB2_LIB.BASEBOARD_FAB2(SCH_1):PAGE245_I59@MSTR_DISCRETE.RES(CHIPS)':
 'A': CDS_PINID='A';
NODE_NAME     U8W1 4
 '@BASEBOARD_FAB2_LIB.BASEBOARD_FAB2(SCH_1):PAGE245_I64@MSTR_TTL.74CBTLV1G125(CHIPS)':
 'B': CDS_PINID='B';
NET_NAME
'JTAG_RISER_TDO'
 '@BASEBOARD_FAB2_LIB.BASEBOARD_FAB2(SCH_1):JTAG_RISER_TDO':
 C_SIGNAL='@baseboard_fab2_lib.baseboard_fab2(sch_1):jtag_riser_tdo';
NODE_NAME     CONX8 53
 '@BASEBOARD_FAB2_LIB.BASEBOARD_FAB2(SCH_1):PAGE245_I48@W_HDL.SMC-CONN60A-22-GP(CHIPS)':
 '53': CDS_PINID='\53\';
NODE_NAME     R8W14 2
 '@BASEBOARD_FAB2_LIB.BASEBOARD_FAB2(SCH_1):PAGE245_I60@MSTR_DISCRETE.RES(CHIPS)':
 'B': CDS_PINID='B';
NET_NAME
'JTAG_RISER_TDO_R'
 '@BASEBOARD_FAB2_LIB.BASEBOARD_FAB2(SCH_1):JTAG_RISER_TDO_R':
 C_SIGNAL='@baseboard_fab2_lib.baseboard_fab2(sch_1):jtag_riser_tdo_r';
NODE_NAME     R8W14 1
 '@BASEBOARD_FAB2_LIB.BASEBOARD_FAB2(SCH_1):PAGE245_I60@MSTR_DISCRETE.RES(CHIPS)':
 'A': CDS_PINID='A';
NODE_NAME     U8W2 3
 '@BASEBOARD_FAB2_LIB.BASEBOARD_FAB2(SCH_1):PAGE245_I66@MSTR_ANALOG.NC7SB3157(CHIPS)':
 'B0': CDS_PINID='B0';
NET_NAME
'JTAG_RISER_TMS'
 '@BASEBOARD_FAB2_LIB.BASEBOARD_FAB2(SCH_1):JTAG_RISER_TMS':
 C_SIGNAL='@baseboard_fab2_lib.baseboard_fab2(sch_1):jtag_riser_tms';
NODE_NAME     CONX8 54
 '@BASEBOARD_FAB2_LIB.BASEBOARD_FAB2(SCH_1):PAGE245_I48@W_HDL.SMC-CONN60A-22-GP(CHIPS)':
 '54': CDS_PINID='\54\';
NODE_NAME     R8W10 1
 '@BASEBOARD_FAB2_LIB.BASEBOARD_FAB2(SCH_1):PAGE245_I56@MSTR_DISCRETE.RES(CHIPS)':
 'A': CDS_PINID='A';
NET_NAME
'JTAG_RISER_TRST'
 '@BASEBOARD_FAB2_LIB.BASEBOARD_FAB2(SCH_1):JTAG_RISER_TRST':
 C_SIGNAL='@baseboard_fab2_lib.baseboard_fab2(sch_1):jtag_riser_trst';
NODE_NAME     CONX8 60
 '@BASEBOARD_FAB2_LIB.BASEBOARD_FAB2(SCH_1):PAGE245_I48@W_HDL.SMC-CONN60A-22-GP(CHIPS)':
 '60': CDS_PINID='\60\';
NODE_NAME     R8W12 1
 '@BASEBOARD_FAB2_LIB.BASEBOARD_FAB2(SCH_1):PAGE245_I58@MSTR_DISCRETE.RES(CHIPS)':
 'A': CDS_PINID='A';
NET_NAME
'JTAG_TCK'
 '@BASEBOARD_FAB2_LIB.BASEBOARD_FAB2(SCH_1):JTAG_TCK':
 C_SIGNAL='@baseboard_fab2_lib.baseboard_fab2(sch_1):jtag_tck';
NODE_NAME     R8G16 2
 '@BASEBOARD_FAB2_LIB.BASEBOARD_FAB2(SCH_1):PAGE189_I22@MSTR_DISCRETE.RES(CHIPS)':
 'B': CDS_PINID='B';
NODE_NAME     R8G15 2
 '@BASEBOARD_FAB2_LIB.BASEBOARD_FAB2(SCH_1):PAGE189_I24@MSTR_DISCRETE.RES(CHIPS)':
 'B': CDS_PINID='B';
NODE_NAME     R8G17 2
 '@BASEBOARD_FAB2_LIB.BASEBOARD_FAB2(SCH_1):PAGE189_I25@MSTR_DISCRETE.RES(CHIPS)':
 'B': CDS_PINID='B';
NODE_NAME     R8G22 1
 '@BASEBOARD_FAB2_LIB.BASEBOARD_FAB2(SCH_1):PAGE189_I66@MSTR_DISCRETE.RES(CHIPS)':
 'A': CDS_PINID='A';
NODE_NAME     U1L10 6
 '@BASEBOARD_FAB2_LIB.BASEBOARD_FAB2(SCH_1):PAGE189_I67@MSTR_TTL.TTL3126(CHIPS)'(2):
 'B'<2>: CDS_PINID='B(2)';
NET_NAME
'JTAG_TCK_R'
 '@BASEBOARD_FAB2_LIB.BASEBOARD_FAB2(SCH_1):JTAG_TCK_R':
 C_SIGNAL='@baseboard_fab2_lib.baseboard_fab2(sch_1):jtag_tck_r';
NODE_NAME     J7G2 8
 '@BASEBOARD_FAB2_LIB.BASEBOARD_FAB2(SCH_1):PAGE189_I47@MSTR_CONN.CONN8_C77962004(CHIPS)':
 'IO8': CDS_PINID='IO8';
NODE_NAME     R8G23 1
 '@BASEBOARD_FAB2_LIB.BASEBOARD_FAB2(SCH_1):PAGE189_I56@MSTR_DISCRETE.RES(CHIPS)':
 'A': CDS_PINID='A';
NODE_NAME     R8G22 2
 '@BASEBOARD_FAB2_LIB.BASEBOARD_FAB2(SCH_1):PAGE189_I66@MSTR_DISCRETE.RES(CHIPS)':
 'B': CDS_PINID='B';
NET_NAME
'JTAG_TDI'
 '@BASEBOARD_FAB2_LIB.BASEBOARD_FAB2(SCH_1):JTAG_TDI':
 C_SIGNAL='@baseboard_fab2_lib.baseboard_fab2(sch_1):jtag_tdi';
NODE_NAME     R7G19 2
 '@BASEBOARD_FAB2_LIB.BASEBOARD_FAB2(SCH_1):PAGE189_I8@MSTR_DISCRETE.RES(CHIPS)':
 'B': CDS_PINID='B';
NODE_NAME     R7G18 2
 '@BASEBOARD_FAB2_LIB.BASEBOARD_FAB2(SCH_1):PAGE189_I13@MSTR_DISCRETE.RES(CHIPS)':
 'B': CDS_PINID='B';
NODE_NAME     R8G8 2
 '@BASEBOARD_FAB2_LIB.BASEBOARD_FAB2(SCH_1):PAGE189_I17@MSTR_DISCRETE.RES(CHIPS)':
 'B': CDS_PINID='B';
NODE_NAME     R8G19 1
 '@BASEBOARD_FAB2_LIB.BASEBOARD_FAB2(SCH_1):PAGE189_I64@MSTR_DISCRETE.RES(CHIPS)':
 'A': CDS_PINID='A';
NODE_NAME     U1L10 11
 '@BASEBOARD_FAB2_LIB.BASEBOARD_FAB2(SCH_1):PAGE189_I67@MSTR_TTL.TTL3126(CHIPS)'(0):
 'B'<0>: CDS_PINID='B(0)';
NET_NAME
'JTAG_TDI_R'
 '@BASEBOARD_FAB2_LIB.BASEBOARD_FAB2(SCH_1):JTAG_TDI_R':
 C_SIGNAL='@baseboard_fab2_lib.baseboard_fab2(sch_1):jtag_tdi_r';
NODE_NAME     J7G2 3
 '@BASEBOARD_FAB2_LIB.BASEBOARD_FAB2(SCH_1):PAGE189_I47@MSTR_CONN.CONN8_C77962004(CHIPS)':
 'IO3': CDS_PINID='IO3';
NODE_NAME     R7G23 2
 '@BASEBOARD_FAB2_LIB.BASEBOARD_FAB2(SCH_1):PAGE189_I51@MSTR_DISCRETE.RES(CHIPS)':
 'B': CDS_PINID='B';
NODE_NAME     R8G19 2
 '@BASEBOARD_FAB2_LIB.BASEBOARD_FAB2(SCH_1):PAGE189_I64@MSTR_DISCRETE.RES(CHIPS)':
 'B': CDS_PINID='B';
NET_NAME
'JTAG_TDO'
 '@BASEBOARD_FAB2_LIB.BASEBOARD_FAB2(SCH_1):JTAG_TDO':
 C_SIGNAL='@baseboard_fab2_lib.baseboard_fab2(sch_1):jtag_tdo';
NODE_NAME     R7G16 2
 '@BASEBOARD_FAB2_LIB.BASEBOARD_FAB2(SCH_1):PAGE189_I27@MSTR_DISCRETE.RES(CHIPS)':
 'B': CDS_PINID='B';
NODE_NAME     R7G15 2
 '@BASEBOARD_FAB2_LIB.BASEBOARD_FAB2(SCH_1):PAGE189_I36@MSTR_DISCRETE.RES(CHIPS)':
 'B': CDS_PINID='B';
NODE_NAME     R7G17 2
 '@BASEBOARD_FAB2_LIB.BASEBOARD_FAB2(SCH_1):PAGE189_I37@MSTR_DISCRETE.RES(CHIPS)':
 'B': CDS_PINID='B';
NODE_NAME     R7G21 1
 '@BASEBOARD_FAB2_LIB.BASEBOARD_FAB2(SCH_1):PAGE189_I63@MSTR_DISCRETE.RES(CHIPS)':
 'A': CDS_PINID='A';
NODE_NAME     U1L10 3
 '@BASEBOARD_FAB2_LIB.BASEBOARD_FAB2(SCH_1):PAGE189_I67@MSTR_TTL.TTL3126(CHIPS)'(3):
 'B'<3>: CDS_PINID='B(3)';
NET_NAME
'JTAG_TDO_R'
 '@BASEBOARD_FAB2_LIB.BASEBOARD_FAB2(SCH_1):JTAG_TDO_R':
 C_SIGNAL='@baseboard_fab2_lib.baseboard_fab2(sch_1):jtag_tdo_r';
NODE_NAME     J7G2 2
 '@BASEBOARD_FAB2_LIB.BASEBOARD_FAB2(SCH_1):PAGE189_I47@MSTR_CONN.CONN8_C77962004(CHIPS)':
 'IO2': CDS_PINID='IO2';
NODE_NAME     R7G22 2
 '@BASEBOARD_FAB2_LIB.BASEBOARD_FAB2(SCH_1):PAGE189_I53@MSTR_DISCRETE.RES(CHIPS)':
 'B': CDS_PINID='B';
NODE_NAME     R7G21 2
 '@BASEBOARD_FAB2_LIB.BASEBOARD_FAB2(SCH_1):PAGE189_I63@MSTR_DISCRETE.RES(CHIPS)':
 'B': CDS_PINID='B';
NET_NAME
'JTAG_TMS'
 '@BASEBOARD_FAB2_LIB.BASEBOARD_FAB2(SCH_1):JTAG_TMS':
 C_SIGNAL='@baseboard_fab2_lib.baseboard_fab2(sch_1):jtag_tms';
NODE_NAME     R8G11 2
 '@BASEBOARD_FAB2_LIB.BASEBOARD_FAB2(SCH_1):PAGE189_I19@MSTR_DISCRETE.RES(CHIPS)':
 'B': CDS_PINID='B';
NODE_NAME     R8G14 2
 '@BASEBOARD_FAB2_LIB.BASEBOARD_FAB2(SCH_1):PAGE189_I20@MSTR_DISCRETE.RES(CHIPS)':
 'B': CDS_PINID='B';
NODE_NAME     R8G12 2
 '@BASEBOARD_FAB2_LIB.BASEBOARD_FAB2(SCH_1):PAGE189_I21@MSTR_DISCRETE.RES(CHIPS)':
 'B': CDS_PINID='B';
NODE_NAME     R8G21 1
 '@BASEBOARD_FAB2_LIB.BASEBOARD_FAB2(SCH_1):PAGE189_I65@MSTR_DISCRETE.RES(CHIPS)':
 'A': CDS_PINID='A';
NODE_NAME     U1L10 8
 '@BASEBOARD_FAB2_LIB.BASEBOARD_FAB2(SCH_1):PAGE189_I67@MSTR_TTL.TTL3126(CHIPS)'(1):
 'B'<1>: CDS_PINID='B(1)';
NET_NAME
'JTAG_TMS_R'
 '@BASEBOARD_FAB2_LIB.BASEBOARD_FAB2(SCH_1):JTAG_TMS_R':
 C_SIGNAL='@baseboard_fab2_lib.baseboard_fab2(sch_1):jtag_tms_r';
NODE_NAME     J7G2 6
 '@BASEBOARD_FAB2_LIB.BASEBOARD_FAB2(SCH_1):PAGE189_I47@MSTR_CONN.CONN8_C77962004(CHIPS)':
 'IO6': CDS_PINID='IO6';
NODE_NAME     R8G20 2
 '@BASEBOARD_FAB2_LIB.BASEBOARD_FAB2(SCH_1):PAGE189_I50@MSTR_DISCRETE.RES(CHIPS)':
 'B': CDS_PINID='B';
NODE_NAME     R8G21 2
 '@BASEBOARD_FAB2_LIB.BASEBOARD_FAB2(SCH_1):PAGE189_I65@MSTR_DISCRETE.RES(CHIPS)':
 'B': CDS_PINID='B';
NET_NAME
'JTAG_TRST_N'
 '@BASEBOARD_FAB2_LIB.BASEBOARD_FAB2(SCH_1):JTAG_TRST_N':
 C_SIGNAL='@baseboard_fab2_lib.baseboard_fab2(sch_1):jtag_trst_n';
NODE_NAME     R8G10 2
 '@BASEBOARD_FAB2_LIB.BASEBOARD_FAB2(SCH_1):PAGE189_I7@MSTR_DISCRETE.RES(CHIPS)':
 'B': CDS_PINID='B';
NODE_NAME     R8G9 2
 '@BASEBOARD_FAB2_LIB.BASEBOARD_FAB2(SCH_1):PAGE189_I9@MSTR_DISCRETE.RES(CHIPS)':
 'B': CDS_PINID='B';
NODE_NAME     J7G2 4
 '@BASEBOARD_FAB2_LIB.BASEBOARD_FAB2(SCH_1):PAGE189_I47@MSTR_CONN.CONN8_C77962004(CHIPS)':
 'IO4': CDS_PINID='IO4';
NET_NAME
'KR_P0_OCP_RX_C_DN'
 '@BASEBOARD_FAB2_LIB.BASEBOARD_FAB2(SCH_1):KR_P0_OCP_RX_C_DN':
 C_SIGNAL='@baseboard_fab2_lib.baseboard_fab2(sch_1):kr_p0_ocp_rx_c_dn';
NODE_NAME     U7C1 BH31
 '@BASEBOARD_FAB2_LIB.BASEBOARD_FAB2(SCH_1):PAGE118_I73@MSTR_U_PROC.LBG_CORE_QAT_EXT_D(CHIPS)':
 'LAN_RX_P0N': CDS_PINID='LAN_RX_P0N';
NODE_NAME     C8C14 2
 '@BASEBOARD_FAB2_LIB.BASEBOARD_FAB2(SCH_1):PAGE188_I86@DEV_DISCRETE.CAP_A(CHIPS)':
 'B': CDS_PINID='B';
NET_NAME
'KR_P0_OCP_RX_C_DP'
 '@BASEBOARD_FAB2_LIB.BASEBOARD_FAB2(SCH_1):KR_P0_OCP_RX_C_DP':
 C_SIGNAL='@baseboard_fab2_lib.baseboard_fab2(sch_1):kr_p0_ocp_rx_c_dp';
NODE_NAME     U7C1 BF31
 '@BASEBOARD_FAB2_LIB.BASEBOARD_FAB2(SCH_1):PAGE118_I73@MSTR_U_PROC.LBG_CORE_QAT_EXT_D(CHIPS)':
 'LAN_RX_P0P': CDS_PINID='LAN_RX_P0P';
NODE_NAME     C8C15 2
 '@BASEBOARD_FAB2_LIB.BASEBOARD_FAB2(SCH_1):PAGE188_I82@DEV_DISCRETE.CAP_A(CHIPS)':
 'B': CDS_PINID='B';
NET_NAME
'KR_P0_OCP_RX_DN'
 '@BASEBOARD_FAB2_LIB.BASEBOARD_FAB2(SCH_1):KR_P0_OCP_RX_DN':
 C_SIGNAL='@baseboard_fab2_lib.baseboard_fab2(sch_1):kr_p0_ocp_rx_dn';
NODE_NAME     J8E4 53
 '@BASEBOARD_FAB2_LIB.BASEBOARD_FAB2(SCH_1):PAGE188_I27@MSTR_SCONN.SCONN64_H87568002_A(CHIPS)':
 'IO53': CDS_PINID='IO53';
NODE_NAME     C8C14 1
 '@BASEBOARD_FAB2_LIB.BASEBOARD_FAB2(SCH_1):PAGE188_I86@DEV_DISCRETE.CAP_A(CHIPS)':
 'A': CDS_PINID='A';
NET_NAME
'KR_P0_OCP_RX_DP'
 '@BASEBOARD_FAB2_LIB.BASEBOARD_FAB2(SCH_1):KR_P0_OCP_RX_DP':
 C_SIGNAL='@baseboard_fab2_lib.baseboard_fab2(sch_1):kr_p0_ocp_rx_dp';
NODE_NAME     J8E4 52
 '@BASEBOARD_FAB2_LIB.BASEBOARD_FAB2(SCH_1):PAGE188_I27@MSTR_SCONN.SCONN64_H87568002_A(CHIPS)':
 'IO52': CDS_PINID='IO52';
NODE_NAME     C8C15 1
 '@BASEBOARD_FAB2_LIB.BASEBOARD_FAB2(SCH_1):PAGE188_I82@DEV_DISCRETE.CAP_A(CHIPS)':
 'A': CDS_PINID='A';
NET_NAME
'KR_P0_OCP_TX_DN'
 '@BASEBOARD_FAB2_LIB.BASEBOARD_FAB2(SCH_1):KR_P0_OCP_TX_DN':
 C_SIGNAL='@baseboard_fab2_lib.baseboard_fab2(sch_1):kr_p0_ocp_tx_dn';
NODE_NAME     U7C1 BM27
 '@BASEBOARD_FAB2_LIB.BASEBOARD_FAB2(SCH_1):PAGE118_I73@MSTR_U_PROC.LBG_CORE_QAT_EXT_D(CHIPS)':
 'LAN_TX_P0N': CDS_PINID='LAN_TX_P0N';
NODE_NAME     J8E4 41
 '@BASEBOARD_FAB2_LIB.BASEBOARD_FAB2(SCH_1):PAGE188_I27@MSTR_SCONN.SCONN64_H87568002_A(CHIPS)':
 'IO41': CDS_PINID='IO41';
NET_NAME
'KR_P0_OCP_TX_DP'
 '@BASEBOARD_FAB2_LIB.BASEBOARD_FAB2(SCH_1):KR_P0_OCP_TX_DP':
 C_SIGNAL='@baseboard_fab2_lib.baseboard_fab2(sch_1):kr_p0_ocp_tx_dp';
NODE_NAME     U7C1 BR27
 '@BASEBOARD_FAB2_LIB.BASEBOARD_FAB2(SCH_1):PAGE118_I73@MSTR_U_PROC.LBG_CORE_QAT_EXT_D(CHIPS)':
 'LAN_TX_P0P': CDS_PINID='LAN_TX_P0P';
NODE_NAME     J8E4 40
 '@BASEBOARD_FAB2_LIB.BASEBOARD_FAB2(SCH_1):PAGE188_I27@MSTR_SCONN.SCONN64_H87568002_A(CHIPS)':
 'IO40': CDS_PINID='IO40';
NET_NAME
'KR_P1_OCP_RX_C_DN'
 '@BASEBOARD_FAB2_LIB.BASEBOARD_FAB2(SCH_1):KR_P1_OCP_RX_C_DN':
 C_SIGNAL='@baseboard_fab2_lib.baseboard_fab2(sch_1):kr_p1_ocp_rx_c_dn';
NODE_NAME     U7C1 BG29
 '@BASEBOARD_FAB2_LIB.BASEBOARD_FAB2(SCH_1):PAGE118_I73@MSTR_U_PROC.LBG_CORE_QAT_EXT_D(CHIPS)':
 'LAN_RX_P1N': CDS_PINID='LAN_RX_P1N';
NODE_NAME     C8C13 2
 '@BASEBOARD_FAB2_LIB.BASEBOARD_FAB2(SCH_1):PAGE188_I120@DEV_DISCRETE.CAP_A(CHIPS)':
 'B': CDS_PINID='B';
NET_NAME
'KR_P1_OCP_RX_C_DP'
 '@BASEBOARD_FAB2_LIB.BASEBOARD_FAB2(SCH_1):KR_P1_OCP_RX_C_DP':
 C_SIGNAL='@baseboard_fab2_lib.baseboard_fab2(sch_1):kr_p1_ocp_rx_c_dp';
NODE_NAME     U7C1 BJ29
 '@BASEBOARD_FAB2_LIB.BASEBOARD_FAB2(SCH_1):PAGE118_I73@MSTR_U_PROC.LBG_CORE_QAT_EXT_D(CHIPS)':
 'LAN_RX_P1P': CDS_PINID='LAN_RX_P1P';
NODE_NAME     C8C12 2
 '@BASEBOARD_FAB2_LIB.BASEBOARD_FAB2(SCH_1):PAGE188_I121@DEV_DISCRETE.CAP_A(CHIPS)':
 'B': CDS_PINID='B';
NET_NAME
'KR_P1_OCP_RX_DN'
 '@BASEBOARD_FAB2_LIB.BASEBOARD_FAB2(SCH_1):KR_P1_OCP_RX_DN':
 C_SIGNAL='@baseboard_fab2_lib.baseboard_fab2(sch_1):kr_p1_ocp_rx_dn';
NODE_NAME     J8E4 59
 '@BASEBOARD_FAB2_LIB.BASEBOARD_FAB2(SCH_1):PAGE188_I27@MSTR_SCONN.SCONN64_H87568002_A(CHIPS)':
 'IO59': CDS_PINID='IO59';
NODE_NAME     C8C13 1
 '@BASEBOARD_FAB2_LIB.BASEBOARD_FAB2(SCH_1):PAGE188_I120@DEV_DISCRETE.CAP_A(CHIPS)':
 'A': CDS_PINID='A';
NET_NAME
'KR_P1_OCP_RX_DP'
 '@BASEBOARD_FAB2_LIB.BASEBOARD_FAB2(SCH_1):KR_P1_OCP_RX_DP':
 C_SIGNAL='@baseboard_fab2_lib.baseboard_fab2(sch_1):kr_p1_ocp_rx_dp';
NODE_NAME     J8E4 58
 '@BASEBOARD_FAB2_LIB.BASEBOARD_FAB2(SCH_1):PAGE188_I27@MSTR_SCONN.SCONN64_H87568002_A(CHIPS)':
 'IO58': CDS_PINID='IO58';
NODE_NAME     C8C12 1
 '@BASEBOARD_FAB2_LIB.BASEBOARD_FAB2(SCH_1):PAGE188_I121@DEV_DISCRETE.CAP_A(CHIPS)':
 'A': CDS_PINID='A';
NET_NAME
'KR_P1_OCP_TX_DN'
 '@BASEBOARD_FAB2_LIB.BASEBOARD_FAB2(SCH_1):KR_P1_OCP_TX_DN':
 C_SIGNAL='@baseboard_fab2_lib.baseboard_fab2(sch_1):kr_p1_ocp_tx_dn';
NODE_NAME     U7C1 BM24
 '@BASEBOARD_FAB2_LIB.BASEBOARD_FAB2(SCH_1):PAGE118_I73@MSTR_U_PROC.LBG_CORE_QAT_EXT_D(CHIPS)':
 'LAN_TX_P1N': CDS_PINID='LAN_TX_P1N';
NODE_NAME     J8E4 47
 '@BASEBOARD_FAB2_LIB.BASEBOARD_FAB2(SCH_1):PAGE188_I27@MSTR_SCONN.SCONN64_H87568002_A(CHIPS)':
 'IO47': CDS_PINID='IO47';
NET_NAME
'KR_P1_OCP_TX_DP'
 '@BASEBOARD_FAB2_LIB.BASEBOARD_FAB2(SCH_1):KR_P1_OCP_TX_DP':
 C_SIGNAL='@baseboard_fab2_lib.baseboard_fab2(sch_1):kr_p1_ocp_tx_dp';
NODE_NAME     U7C1 BR24
 '@BASEBOARD_FAB2_LIB.BASEBOARD_FAB2(SCH_1):PAGE118_I73@MSTR_U_PROC.LBG_CORE_QAT_EXT_D(CHIPS)':
 'LAN_TX_P1P': CDS_PINID='LAN_TX_P1P';
NODE_NAME     J8E4 46
 '@BASEBOARD_FAB2_LIB.BASEBOARD_FAB2(SCH_1):PAGE188_I27@MSTR_SCONN.SCONN64_H87568002_A(CHIPS)':
 'IO46': CDS_PINID='IO46';
NET_NAME
'L10_100OHM_6INCH_DN'
 '@BASEBOARD_FAB2_LIB.BASEBOARD_FAB2(SCH_1):L10_100OHM_6INCH_DN':
 C_SIGNAL='@baseboard_fab2_lib.baseboard_fab2(sch_1):l10_100ohm_6inch_dn';
NODE_NAME     T1P22 2
 '@BASEBOARD_FAB2_LIB.BASEBOARD_FAB2(SCH_1):PAGE271_I45@W_HDL.TPAD-DIFF-4P-GP(CHIPS)':
 '2': CDS_PINID='\2\';
NET_NAME
'L10_100OHM_6INCH_DP'
 '@BASEBOARD_FAB2_LIB.BASEBOARD_FAB2(SCH_1):L10_100OHM_6INCH_DP':
 C_SIGNAL='@baseboard_fab2_lib.baseboard_fab2(sch_1):l10_100ohm_6inch_dp';
NODE_NAME     T1P22 1
 '@BASEBOARD_FAB2_LIB.BASEBOARD_FAB2(SCH_1):PAGE271_I45@W_HDL.TPAD-DIFF-4P-GP(CHIPS)':
 '1': CDS_PINID='\1\';
NET_NAME
'L10_40OHM_6INCH'
 '@BASEBOARD_FAB2_LIB.BASEBOARD_FAB2(SCH_1):L10_40OHM_6INCH':
 C_SIGNAL='@baseboard_fab2_lib.baseboard_fab2(sch_1):l10_40ohm_6inch';
NODE_NAME     T1P28 1
 '@BASEBOARD_FAB2_LIB.BASEBOARD_FAB2(SCH_1):PAGE271_I60@W_HDL.TPAD-SE-2P-GP(CHIPS)':
 '1': CDS_PINID='\1\';
NET_NAME
'L10_50OHM_6INCH'
 '@BASEBOARD_FAB2_LIB.BASEBOARD_FAB2(SCH_1):L10_50OHM_6INCH':
 C_SIGNAL='@baseboard_fab2_lib.baseboard_fab2(sch_1):l10_50ohm_6inch';
NODE_NAME     T1P34 1
 '@BASEBOARD_FAB2_LIB.BASEBOARD_FAB2(SCH_1):PAGE271_I62@W_HDL.TPAD-SE-2P-GP(CHIPS)':
 '1': CDS_PINID='\1\';
NET_NAME
'L10_73OHM_6INCH_DN'
 '@BASEBOARD_FAB2_LIB.BASEBOARD_FAB2(SCH_1):L10_73OHM_6INCH_DN':
 C_SIGNAL='@baseboard_fab2_lib.baseboard_fab2(sch_1):l10_73ohm_6inch_dn';
NODE_NAME     T1P10 2
 '@BASEBOARD_FAB2_LIB.BASEBOARD_FAB2(SCH_1):PAGE271_I15@W_HDL.TPAD-DIFF-4P-GP(CHIPS)':
 '2': CDS_PINID='\2\';
NET_NAME
'L10_73OHM_6INCH_DP'
 '@BASEBOARD_FAB2_LIB.BASEBOARD_FAB2(SCH_1):L10_73OHM_6INCH_DP':
 C_SIGNAL='@baseboard_fab2_lib.baseboard_fab2(sch_1):l10_73ohm_6inch_dp';
NODE_NAME     T1P10 1
 '@BASEBOARD_FAB2_LIB.BASEBOARD_FAB2(SCH_1):PAGE271_I15@W_HDL.TPAD-DIFF-4P-GP(CHIPS)':
 '1': CDS_PINID='\1\';
NET_NAME
'L10_85OHM_10INCH_DN'
 '@BASEBOARD_FAB2_LIB.BASEBOARD_FAB2(SCH_1):L10_85OHM_10INCH_DN':
 C_SIGNAL='@baseboard_fab2_lib.baseboard_fab2(sch_1):l10_85ohm_10inch_dn';
NODE_NAME     T1D19 2
 '@BASEBOARD_FAB2_LIB.BASEBOARD_FAB2(SCH_1):PAGE272_I23@W_HDL.TEST-PAD-12P-1-GP-U(CHIPS)':
 'DN': CDS_PINID='DN';
NODE_NAME     T1D20 1
 '@BASEBOARD_FAB2_LIB.BASEBOARD_FAB2(SCH_1):PAGE272_I24@W_HDL.TEST-PAD-12P-1-GP-U(CHIPS)':
 'DP': CDS_PINID='DP';
NET_NAME
'L10_85OHM_10INCH_DP'
 '@BASEBOARD_FAB2_LIB.BASEBOARD_FAB2(SCH_1):L10_85OHM_10INCH_DP':
 C_SIGNAL='@baseboard_fab2_lib.baseboard_fab2(sch_1):l10_85ohm_10inch_dp';
NODE_NAME     T1D19 1
 '@BASEBOARD_FAB2_LIB.BASEBOARD_FAB2(SCH_1):PAGE272_I23@W_HDL.TEST-PAD-12P-1-GP-U(CHIPS)':
 'DP': CDS_PINID='DP';
NODE_NAME     T1D20 2
 '@BASEBOARD_FAB2_LIB.BASEBOARD_FAB2(SCH_1):PAGE272_I24@W_HDL.TEST-PAD-12P-1-GP-U(CHIPS)':
 'DN': CDS_PINID='DN';
NET_NAME
'L10_85OHM_5INCH_DN'
 '@BASEBOARD_FAB2_LIB.BASEBOARD_FAB2(SCH_1):L10_85OHM_5INCH_DN':
 C_SIGNAL='@baseboard_fab2_lib.baseboard_fab2(sch_1):l10_85ohm_5inch_dn';
NODE_NAME     T1D8 1
 '@BASEBOARD_FAB2_LIB.BASEBOARD_FAB2(SCH_1):PAGE270_I13@W_HDL.TEST-PAD-12P-1-GP-U(CHIPS)':
 'DP': CDS_PINID='DP';
NODE_NAME     T1D7 2
 '@BASEBOARD_FAB2_LIB.BASEBOARD_FAB2(SCH_1):PAGE270_I16@W_HDL.TEST-PAD-12P-1-GP-U(CHIPS)':
 'DN': CDS_PINID='DN';
NET_NAME
'L10_85OHM_5INCH_DP'
 '@BASEBOARD_FAB2_LIB.BASEBOARD_FAB2(SCH_1):L10_85OHM_5INCH_DP':
 C_SIGNAL='@baseboard_fab2_lib.baseboard_fab2(sch_1):l10_85ohm_5inch_dp';
NODE_NAME     T1D8 2
 '@BASEBOARD_FAB2_LIB.BASEBOARD_FAB2(SCH_1):PAGE270_I13@W_HDL.TEST-PAD-12P-1-GP-U(CHIPS)':
 'DN': CDS_PINID='DN';
NODE_NAME     T1D7 1
 '@BASEBOARD_FAB2_LIB.BASEBOARD_FAB2(SCH_1):PAGE270_I16@W_HDL.TEST-PAD-12P-1-GP-U(CHIPS)':
 'DP': CDS_PINID='DP';
NET_NAME
'L10_85OHM_6INCH_DN'
 '@BASEBOARD_FAB2_LIB.BASEBOARD_FAB2(SCH_1):L10_85OHM_6INCH_DN':
 C_SIGNAL='@baseboard_fab2_lib.baseboard_fab2(sch_1):l10_85ohm_6inch_dn';
NODE_NAME     T1P4 2
 '@BASEBOARD_FAB2_LIB.BASEBOARD_FAB2(SCH_1):PAGE271_I7@W_HDL.TPAD-DIFF-4P-GP(CHIPS)':
 '2': CDS_PINID='\2\';
NET_NAME
'L10_85OHM_6INCH_DP'
 '@BASEBOARD_FAB2_LIB.BASEBOARD_FAB2(SCH_1):L10_85OHM_6INCH_DP':
 C_SIGNAL='@baseboard_fab2_lib.baseboard_fab2(sch_1):l10_85ohm_6inch_dp';
NODE_NAME     T1P4 1
 '@BASEBOARD_FAB2_LIB.BASEBOARD_FAB2(SCH_1):PAGE271_I7@W_HDL.TPAD-DIFF-4P-GP(CHIPS)':
 '1': CDS_PINID='\1\';
NET_NAME
'L12_100OHM_6INCH_DN'
 '@BASEBOARD_FAB2_LIB.BASEBOARD_FAB2(SCH_1):L12_100OHM_6INCH_DN':
 C_SIGNAL='@baseboard_fab2_lib.baseboard_fab2(sch_1):l12_100ohm_6inch_dn';
NODE_NAME     T1P23 2
 '@BASEBOARD_FAB2_LIB.BASEBOARD_FAB2(SCH_1):PAGE271_I47@W_HDL.TPAD-DIFF-4P-GP(CHIPS)':
 '2': CDS_PINID='\2\';
NET_NAME
'L12_100OHM_6INCH_DP'
 '@BASEBOARD_FAB2_LIB.BASEBOARD_FAB2(SCH_1):L12_100OHM_6INCH_DP':
 C_SIGNAL='@baseboard_fab2_lib.baseboard_fab2(sch_1):l12_100ohm_6inch_dp';
NODE_NAME     T1P23 1
 '@BASEBOARD_FAB2_LIB.BASEBOARD_FAB2(SCH_1):PAGE271_I47@W_HDL.TPAD-DIFF-4P-GP(CHIPS)':
 '1': CDS_PINID='\1\';
NET_NAME
'L12_40OHM_6INCH'
 '@BASEBOARD_FAB2_LIB.BASEBOARD_FAB2(SCH_1):L12_40OHM_6INCH':
 C_SIGNAL='@baseboard_fab2_lib.baseboard_fab2(sch_1):l12_40ohm_6inch';
NODE_NAME     T1P29 1
 '@BASEBOARD_FAB2_LIB.BASEBOARD_FAB2(SCH_1):PAGE271_I56@W_HDL.TPAD-SE-2P-GP(CHIPS)':
 '1': CDS_PINID='\1\';
NET_NAME
'L12_50OHM_6INCH'
 '@BASEBOARD_FAB2_LIB.BASEBOARD_FAB2(SCH_1):L12_50OHM_6INCH':
 C_SIGNAL='@baseboard_fab2_lib.baseboard_fab2(sch_1):l12_50ohm_6inch';
NODE_NAME     T1P35 1
 '@BASEBOARD_FAB2_LIB.BASEBOARD_FAB2(SCH_1):PAGE271_I67@W_HDL.TPAD-SE-2P-GP(CHIPS)':
 '1': CDS_PINID='\1\';
NET_NAME
'L12_73OHM_6INCH_DN'
 '@BASEBOARD_FAB2_LIB.BASEBOARD_FAB2(SCH_1):L12_73OHM_6INCH_DN':
 C_SIGNAL='@baseboard_fab2_lib.baseboard_fab2(sch_1):l12_73ohm_6inch_dn';
NODE_NAME     T1P11 2
 '@BASEBOARD_FAB2_LIB.BASEBOARD_FAB2(SCH_1):PAGE271_I23@W_HDL.TPAD-DIFF-4P-GP(CHIPS)':
 '2': CDS_PINID='\2\';
NET_NAME
'L12_73OHM_6INCH_DP'
 '@BASEBOARD_FAB2_LIB.BASEBOARD_FAB2(SCH_1):L12_73OHM_6INCH_DP':
 C_SIGNAL='@baseboard_fab2_lib.baseboard_fab2(sch_1):l12_73ohm_6inch_dp';
NODE_NAME     T1P11 1
 '@BASEBOARD_FAB2_LIB.BASEBOARD_FAB2(SCH_1):PAGE271_I23@W_HDL.TPAD-DIFF-4P-GP(CHIPS)':
 '1': CDS_PINID='\1\';
NET_NAME
'L12_85OHM_10INCH_DN'
 '@BASEBOARD_FAB2_LIB.BASEBOARD_FAB2(SCH_1):L12_85OHM_10INCH_DN':
 C_SIGNAL='@baseboard_fab2_lib.baseboard_fab2(sch_1):l12_85ohm_10inch_dn';
NODE_NAME     T1D21 2
 '@BASEBOARD_FAB2_LIB.BASEBOARD_FAB2(SCH_1):PAGE272_I16@W_HDL.TEST-PAD-12P-1-GP-U(CHIPS)':
 'DN': CDS_PINID='DN';
NODE_NAME     T1D22 1
 '@BASEBOARD_FAB2_LIB.BASEBOARD_FAB2(SCH_1):PAGE272_I21@W_HDL.TEST-PAD-12P-1-GP-U(CHIPS)':
 'DP': CDS_PINID='DP';
NET_NAME
'L12_85OHM_10INCH_DP'
 '@BASEBOARD_FAB2_LIB.BASEBOARD_FAB2(SCH_1):L12_85OHM_10INCH_DP':
 C_SIGNAL='@baseboard_fab2_lib.baseboard_fab2(sch_1):l12_85ohm_10inch_dp';
NODE_NAME     T1D21 1
 '@BASEBOARD_FAB2_LIB.BASEBOARD_FAB2(SCH_1):PAGE272_I16@W_HDL.TEST-PAD-12P-1-GP-U(CHIPS)':
 'DP': CDS_PINID='DP';
NODE_NAME     T1D22 2
 '@BASEBOARD_FAB2_LIB.BASEBOARD_FAB2(SCH_1):PAGE272_I21@W_HDL.TEST-PAD-12P-1-GP-U(CHIPS)':
 'DN': CDS_PINID='DN';
NET_NAME
'L12_85OHM_5INCH_DN'
 '@BASEBOARD_FAB2_LIB.BASEBOARD_FAB2(SCH_1):L12_85OHM_5INCH_DN':
 C_SIGNAL='@baseboard_fab2_lib.baseboard_fab2(sch_1):l12_85ohm_5inch_dn';
NODE_NAME     T1D10 1
 '@BASEBOARD_FAB2_LIB.BASEBOARD_FAB2(SCH_1):PAGE270_I17@W_HDL.TEST-PAD-12P-1-GP-U(CHIPS)':
 'DP': CDS_PINID='DP';
NODE_NAME     T1D9 2
 '@BASEBOARD_FAB2_LIB.BASEBOARD_FAB2(SCH_1):PAGE270_I18@W_HDL.TEST-PAD-12P-1-GP-U(CHIPS)':
 'DN': CDS_PINID='DN';
NET_NAME
'L12_85OHM_5INCH_DP'
 '@BASEBOARD_FAB2_LIB.BASEBOARD_FAB2(SCH_1):L12_85OHM_5INCH_DP':
 C_SIGNAL='@baseboard_fab2_lib.baseboard_fab2(sch_1):l12_85ohm_5inch_dp';
NODE_NAME     T1D10 2
 '@BASEBOARD_FAB2_LIB.BASEBOARD_FAB2(SCH_1):PAGE270_I17@W_HDL.TEST-PAD-12P-1-GP-U(CHIPS)':
 'DN': CDS_PINID='DN';
NODE_NAME     T1D9 1
 '@BASEBOARD_FAB2_LIB.BASEBOARD_FAB2(SCH_1):PAGE270_I18@W_HDL.TEST-PAD-12P-1-GP-U(CHIPS)':
 'DP': CDS_PINID='DP';
NET_NAME
'L12_85OHM_6INCH_DN'
 '@BASEBOARD_FAB2_LIB.BASEBOARD_FAB2(SCH_1):L12_85OHM_6INCH_DN':
 C_SIGNAL='@baseboard_fab2_lib.baseboard_fab2(sch_1):l12_85ohm_6inch_dn';
NODE_NAME     T1P5 2
 '@BASEBOARD_FAB2_LIB.BASEBOARD_FAB2(SCH_1):PAGE271_I11@W_HDL.TPAD-DIFF-4P-GP(CHIPS)':
 '2': CDS_PINID='\2\';
NET_NAME
'L12_85OHM_6INCH_DP'
 '@BASEBOARD_FAB2_LIB.BASEBOARD_FAB2(SCH_1):L12_85OHM_6INCH_DP':
 C_SIGNAL='@baseboard_fab2_lib.baseboard_fab2(sch_1):l12_85ohm_6inch_dp';
NODE_NAME     T1P5 1
 '@BASEBOARD_FAB2_LIB.BASEBOARD_FAB2(SCH_1):PAGE271_I11@W_HDL.TPAD-DIFF-4P-GP(CHIPS)':
 '1': CDS_PINID='\1\';
NET_NAME
'L12_95OHM_6INCH_DN'
 '@BASEBOARD_FAB2_LIB.BASEBOARD_FAB2(SCH_1):L12_95OHM_6INCH_DN':
 C_SIGNAL='@baseboard_fab2_lib.baseboard_fab2(sch_1):l12_95ohm_6inch_dn';
NODE_NAME     T1P17 2
 '@BASEBOARD_FAB2_LIB.BASEBOARD_FAB2(SCH_1):PAGE271_I36@W_HDL.TPAD-DIFF-4P-GP(CHIPS)':
 '2': CDS_PINID='\2\';
NET_NAME
'L12_95OHM_6INCH_DP'
 '@BASEBOARD_FAB2_LIB.BASEBOARD_FAB2(SCH_1):L12_95OHM_6INCH_DP':
 C_SIGNAL='@baseboard_fab2_lib.baseboard_fab2(sch_1):l12_95ohm_6inch_dp';
NODE_NAME     T1P17 1
 '@BASEBOARD_FAB2_LIB.BASEBOARD_FAB2(SCH_1):PAGE271_I36@W_HDL.TPAD-DIFF-4P-GP(CHIPS)':
 '1': CDS_PINID='\1\';
NET_NAME
'L14_100OHM_6INCH_DN'
 '@BASEBOARD_FAB2_LIB.BASEBOARD_FAB2(SCH_1):L14_100OHM_6INCH_DN':
 C_SIGNAL='@baseboard_fab2_lib.baseboard_fab2(sch_1):l14_100ohm_6inch_dn';
NODE_NAME     T1P24 2
 '@BASEBOARD_FAB2_LIB.BASEBOARD_FAB2(SCH_1):PAGE271_I38@W_HDL.TPAD-DIFF-4P-GP(CHIPS)':
 '2': CDS_PINID='\2\';
NET_NAME
'L14_100OHM_6INCH_DP'
 '@BASEBOARD_FAB2_LIB.BASEBOARD_FAB2(SCH_1):L14_100OHM_6INCH_DP':
 C_SIGNAL='@baseboard_fab2_lib.baseboard_fab2(sch_1):l14_100ohm_6inch_dp';
NODE_NAME     T1P24 1
 '@BASEBOARD_FAB2_LIB.BASEBOARD_FAB2(SCH_1):PAGE271_I38@W_HDL.TPAD-DIFF-4P-GP(CHIPS)':
 '1': CDS_PINID='\1\';
NET_NAME
'L14_40OHM_6INCH'
 '@BASEBOARD_FAB2_LIB.BASEBOARD_FAB2(SCH_1):L14_40OHM_6INCH':
 C_SIGNAL='@baseboard_fab2_lib.baseboard_fab2(sch_1):l14_40ohm_6inch';
NODE_NAME     T1P30 1
 '@BASEBOARD_FAB2_LIB.BASEBOARD_FAB2(SCH_1):PAGE271_I61@W_HDL.TPAD-SE-2P-GP(CHIPS)':
 '1': CDS_PINID='\1\';
NET_NAME
'L14_50OHM_6INCH'
 '@BASEBOARD_FAB2_LIB.BASEBOARD_FAB2(SCH_1):L14_50OHM_6INCH':
 C_SIGNAL='@baseboard_fab2_lib.baseboard_fab2(sch_1):l14_50ohm_6inch';
NODE_NAME     T1P36 1
 '@BASEBOARD_FAB2_LIB.BASEBOARD_FAB2(SCH_1):PAGE271_I63@W_HDL.TPAD-SE-2P-GP(CHIPS)':
 '1': CDS_PINID='\1\';
NET_NAME
'L14_73OHM_6INCH_DN'
 '@BASEBOARD_FAB2_LIB.BASEBOARD_FAB2(SCH_1):L14_73OHM_6INCH_DN':
 C_SIGNAL='@baseboard_fab2_lib.baseboard_fab2(sch_1):l14_73ohm_6inch_dn';
NODE_NAME     T1P12 2
 '@BASEBOARD_FAB2_LIB.BASEBOARD_FAB2(SCH_1):PAGE271_I24@W_HDL.TPAD-DIFF-4P-GP(CHIPS)':
 '2': CDS_PINID='\2\';
NET_NAME
'L14_73OHM_6INCH_DP'
 '@BASEBOARD_FAB2_LIB.BASEBOARD_FAB2(SCH_1):L14_73OHM_6INCH_DP':
 C_SIGNAL='@baseboard_fab2_lib.baseboard_fab2(sch_1):l14_73ohm_6inch_dp';
NODE_NAME     T1P12 1
 '@BASEBOARD_FAB2_LIB.BASEBOARD_FAB2(SCH_1):PAGE271_I24@W_HDL.TPAD-DIFF-4P-GP(CHIPS)':
 '1': CDS_PINID='\1\';
NET_NAME
'L14_85OHM_10INCH_DN'
 '@BASEBOARD_FAB2_LIB.BASEBOARD_FAB2(SCH_1):L14_85OHM_10INCH_DN':
 C_SIGNAL='@baseboard_fab2_lib.baseboard_fab2(sch_1):l14_85ohm_10inch_dn';
NODE_NAME     T1D23 2
 '@BASEBOARD_FAB2_LIB.BASEBOARD_FAB2(SCH_1):PAGE272_I9@W_HDL.TEST-PAD-12P-1-GP-U(CHIPS)':
 'DN': CDS_PINID='DN';
NODE_NAME     T1D24 1
 '@BASEBOARD_FAB2_LIB.BASEBOARD_FAB2(SCH_1):PAGE272_I12@W_HDL.TEST-PAD-12P-1-GP-U(CHIPS)':
 'DP': CDS_PINID='DP';
NET_NAME
'L14_85OHM_10INCH_DP'
 '@BASEBOARD_FAB2_LIB.BASEBOARD_FAB2(SCH_1):L14_85OHM_10INCH_DP':
 C_SIGNAL='@baseboard_fab2_lib.baseboard_fab2(sch_1):l14_85ohm_10inch_dp';
NODE_NAME     T1D23 1
 '@BASEBOARD_FAB2_LIB.BASEBOARD_FAB2(SCH_1):PAGE272_I9@W_HDL.TEST-PAD-12P-1-GP-U(CHIPS)':
 'DP': CDS_PINID='DP';
NODE_NAME     T1D24 2
 '@BASEBOARD_FAB2_LIB.BASEBOARD_FAB2(SCH_1):PAGE272_I12@W_HDL.TEST-PAD-12P-1-GP-U(CHIPS)':
 'DN': CDS_PINID='DN';
NET_NAME
'L14_85OHM_5INCH_DN'
 '@BASEBOARD_FAB2_LIB.BASEBOARD_FAB2(SCH_1):L14_85OHM_5INCH_DN':
 C_SIGNAL='@baseboard_fab2_lib.baseboard_fab2(sch_1):l14_85ohm_5inch_dn';
NODE_NAME     T1D12 1
 '@BASEBOARD_FAB2_LIB.BASEBOARD_FAB2(SCH_1):PAGE270_I21@W_HDL.TEST-PAD-12P-1-GP-U(CHIPS)':
 'DP': CDS_PINID='DP';
NODE_NAME     T1D11 2
 '@BASEBOARD_FAB2_LIB.BASEBOARD_FAB2(SCH_1):PAGE270_I24@W_HDL.TEST-PAD-12P-1-GP-U(CHIPS)':
 'DN': CDS_PINID='DN';
NET_NAME
'L14_85OHM_5INCH_DP'
 '@BASEBOARD_FAB2_LIB.BASEBOARD_FAB2(SCH_1):L14_85OHM_5INCH_DP':
 C_SIGNAL='@baseboard_fab2_lib.baseboard_fab2(sch_1):l14_85ohm_5inch_dp';
NODE_NAME     T1D12 2
 '@BASEBOARD_FAB2_LIB.BASEBOARD_FAB2(SCH_1):PAGE270_I21@W_HDL.TEST-PAD-12P-1-GP-U(CHIPS)':
 'DN': CDS_PINID='DN';
NODE_NAME     T1D11 1
 '@BASEBOARD_FAB2_LIB.BASEBOARD_FAB2(SCH_1):PAGE270_I24@W_HDL.TEST-PAD-12P-1-GP-U(CHIPS)':
 'DP': CDS_PINID='DP';
NET_NAME
'L14_85OHM_6INCH_DN'
 '@BASEBOARD_FAB2_LIB.BASEBOARD_FAB2(SCH_1):L14_85OHM_6INCH_DN':
 C_SIGNAL='@baseboard_fab2_lib.baseboard_fab2(sch_1):l14_85ohm_6inch_dn';
NODE_NAME     T1P6 2
 '@BASEBOARD_FAB2_LIB.BASEBOARD_FAB2(SCH_1):PAGE271_I13@W_HDL.TPAD-DIFF-4P-GP(CHIPS)':
 '2': CDS_PINID='\2\';
NET_NAME
'L14_85OHM_6INCH_DP'
 '@BASEBOARD_FAB2_LIB.BASEBOARD_FAB2(SCH_1):L14_85OHM_6INCH_DP':
 C_SIGNAL='@baseboard_fab2_lib.baseboard_fab2(sch_1):l14_85ohm_6inch_dp';
NODE_NAME     T1P6 1
 '@BASEBOARD_FAB2_LIB.BASEBOARD_FAB2(SCH_1):PAGE271_I13@W_HDL.TPAD-DIFF-4P-GP(CHIPS)':
 '1': CDS_PINID='\1\';
NET_NAME
'L1_100OHM_6INCH_DN'
 '@BASEBOARD_FAB2_LIB.BASEBOARD_FAB2(SCH_1):L1_100OHM_6INCH_DN':
 C_SIGNAL='@baseboard_fab2_lib.baseboard_fab2(sch_1):l1_100ohm_6inch_dn';
NODE_NAME     T1P19 2
 '@BASEBOARD_FAB2_LIB.BASEBOARD_FAB2(SCH_1):PAGE271_I39@W_HDL.TPAD-DIFF-4P-GP(CHIPS)':
 '2': CDS_PINID='\2\';
NET_NAME
'L1_100OHM_6INCH_DP'
 '@BASEBOARD_FAB2_LIB.BASEBOARD_FAB2(SCH_1):L1_100OHM_6INCH_DP':
 C_SIGNAL='@baseboard_fab2_lib.baseboard_fab2(sch_1):l1_100ohm_6inch_dp';
NODE_NAME     T1P19 1
 '@BASEBOARD_FAB2_LIB.BASEBOARD_FAB2(SCH_1):PAGE271_I39@W_HDL.TPAD-DIFF-4P-GP(CHIPS)':
 '1': CDS_PINID='\1\';
NET_NAME
'L1_40OHM_6INCH'
 '@BASEBOARD_FAB2_LIB.BASEBOARD_FAB2(SCH_1):L1_40OHM_6INCH':
 C_SIGNAL='@baseboard_fab2_lib.baseboard_fab2(sch_1):l1_40ohm_6inch';
NODE_NAME     T1P25 1
 '@BASEBOARD_FAB2_LIB.BASEBOARD_FAB2(SCH_1):PAGE271_I50@W_HDL.TPAD-SE-2P-GP(CHIPS)':
 '1': CDS_PINID='\1\';
NET_NAME
'L1_50OHM_6INCH'
 '@BASEBOARD_FAB2_LIB.BASEBOARD_FAB2(SCH_1):L1_50OHM_6INCH':
 C_SIGNAL='@baseboard_fab2_lib.baseboard_fab2(sch_1):l1_50ohm_6inch';
NODE_NAME     T1P31 1
 '@BASEBOARD_FAB2_LIB.BASEBOARD_FAB2(SCH_1):PAGE271_I71@W_HDL.TPAD-SE-2P-GP(CHIPS)':
 '1': CDS_PINID='\1\';
NET_NAME
'L1_73OHM_6INCH_DN'
 '@BASEBOARD_FAB2_LIB.BASEBOARD_FAB2(SCH_1):L1_73OHM_6INCH_DN':
 C_SIGNAL='@baseboard_fab2_lib.baseboard_fab2(sch_1):l1_73ohm_6inch_dn';
NODE_NAME     T1P7 2
 '@BASEBOARD_FAB2_LIB.BASEBOARD_FAB2(SCH_1):PAGE271_I17@W_HDL.TPAD-DIFF-4P-GP(CHIPS)':
 '2': CDS_PINID='\2\';
NET_NAME
'L1_73OHM_6INCH_DP'
 '@BASEBOARD_FAB2_LIB.BASEBOARD_FAB2(SCH_1):L1_73OHM_6INCH_DP':
 C_SIGNAL='@baseboard_fab2_lib.baseboard_fab2(sch_1):l1_73ohm_6inch_dp';
NODE_NAME     T1P7 1
 '@BASEBOARD_FAB2_LIB.BASEBOARD_FAB2(SCH_1):PAGE271_I17@W_HDL.TPAD-DIFF-4P-GP(CHIPS)':
 '1': CDS_PINID='\1\';
NET_NAME
'L1_85OHM_10INCH_DN'
 '@BASEBOARD_FAB2_LIB.BASEBOARD_FAB2(SCH_1):L1_85OHM_10INCH_DN':
 C_SIGNAL='@baseboard_fab2_lib.baseboard_fab2(sch_1):l1_85ohm_10inch_dn';
NODE_NAME     T1D13 2
 '@BASEBOARD_FAB2_LIB.BASEBOARD_FAB2(SCH_1):PAGE272_I5@W_HDL.TEST-PAD-12P-1-GP-U(CHIPS)':
 'DN': CDS_PINID='DN';
NODE_NAME     T1D14 1
 '@BASEBOARD_FAB2_LIB.BASEBOARD_FAB2(SCH_1):PAGE272_I22@W_HDL.TEST-PAD-12P-1-GP-U(CHIPS)':
 'DP': CDS_PINID='DP';
NET_NAME
'L1_85OHM_10INCH_DP'
 '@BASEBOARD_FAB2_LIB.BASEBOARD_FAB2(SCH_1):L1_85OHM_10INCH_DP':
 C_SIGNAL='@baseboard_fab2_lib.baseboard_fab2(sch_1):l1_85ohm_10inch_dp';
NODE_NAME     T1D13 1
 '@BASEBOARD_FAB2_LIB.BASEBOARD_FAB2(SCH_1):PAGE272_I5@W_HDL.TEST-PAD-12P-1-GP-U(CHIPS)':
 'DP': CDS_PINID='DP';
NODE_NAME     T1D14 2
 '@BASEBOARD_FAB2_LIB.BASEBOARD_FAB2(SCH_1):PAGE272_I22@W_HDL.TEST-PAD-12P-1-GP-U(CHIPS)':
 'DN': CDS_PINID='DN';
NET_NAME
'L1_85OHM_5INCH_DN'
 '@BASEBOARD_FAB2_LIB.BASEBOARD_FAB2(SCH_1):L1_85OHM_5INCH_DN':
 C_SIGNAL='@baseboard_fab2_lib.baseboard_fab2(sch_1):l1_85ohm_5inch_dn';
NODE_NAME     T1D1 2
 '@BASEBOARD_FAB2_LIB.BASEBOARD_FAB2(SCH_1):PAGE270_I1@W_HDL.TEST-PAD-12P-1-GP-U(CHIPS)':
 'DN': CDS_PINID='DN';
NODE_NAME     T1D2 1
 '@BASEBOARD_FAB2_LIB.BASEBOARD_FAB2(SCH_1):PAGE270_I3@W_HDL.TEST-PAD-12P-1-GP-U(CHIPS)':
 'DP': CDS_PINID='DP';
NET_NAME
'L1_85OHM_5INCH_DP'
 '@BASEBOARD_FAB2_LIB.BASEBOARD_FAB2(SCH_1):L1_85OHM_5INCH_DP':
 C_SIGNAL='@baseboard_fab2_lib.baseboard_fab2(sch_1):l1_85ohm_5inch_dp';
NODE_NAME     T1D1 1
 '@BASEBOARD_FAB2_LIB.BASEBOARD_FAB2(SCH_1):PAGE270_I1@W_HDL.TEST-PAD-12P-1-GP-U(CHIPS)':
 'DP': CDS_PINID='DP';
NODE_NAME     T1D2 2
 '@BASEBOARD_FAB2_LIB.BASEBOARD_FAB2(SCH_1):PAGE270_I3@W_HDL.TEST-PAD-12P-1-GP-U(CHIPS)':
 'DN': CDS_PINID='DN';
NET_NAME
'L1_85OHM_6INCH_DN'
 '@BASEBOARD_FAB2_LIB.BASEBOARD_FAB2(SCH_1):L1_85OHM_6INCH_DN':
 C_SIGNAL='@baseboard_fab2_lib.baseboard_fab2(sch_1):l1_85ohm_6inch_dn';
NODE_NAME     T1P1 2
 '@BASEBOARD_FAB2_LIB.BASEBOARD_FAB2(SCH_1):PAGE271_I3@W_HDL.TPAD-DIFF-4P-GP(CHIPS)':
 '2': CDS_PINID='\2\';
NET_NAME
'L1_85OHM_6INCH_DP'
 '@BASEBOARD_FAB2_LIB.BASEBOARD_FAB2(SCH_1):L1_85OHM_6INCH_DP':
 C_SIGNAL='@baseboard_fab2_lib.baseboard_fab2(sch_1):l1_85ohm_6inch_dp';
NODE_NAME     T1P1 1
 '@BASEBOARD_FAB2_LIB.BASEBOARD_FAB2(SCH_1):PAGE271_I3@W_HDL.TPAD-DIFF-4P-GP(CHIPS)':
 '1': CDS_PINID='\1\';
NET_NAME
'L1_95OHM_6INCH_DN'
 '@BASEBOARD_FAB2_LIB.BASEBOARD_FAB2(SCH_1):L1_95OHM_6INCH_DN':
 C_SIGNAL='@baseboard_fab2_lib.baseboard_fab2(sch_1):l1_95ohm_6inch_dn';
NODE_NAME     T1P14 2
 '@BASEBOARD_FAB2_LIB.BASEBOARD_FAB2(SCH_1):PAGE271_I30@W_HDL.TPAD-DIFF-4P-GP(CHIPS)':
 '2': CDS_PINID='\2\';
NET_NAME
'L1_95OHM_6INCH_DP'
 '@BASEBOARD_FAB2_LIB.BASEBOARD_FAB2(SCH_1):L1_95OHM_6INCH_DP':
 C_SIGNAL='@baseboard_fab2_lib.baseboard_fab2(sch_1):l1_95ohm_6inch_dp';
NODE_NAME     T1P14 1
 '@BASEBOARD_FAB2_LIB.BASEBOARD_FAB2(SCH_1):PAGE271_I30@W_HDL.TPAD-DIFF-4P-GP(CHIPS)':
 '1': CDS_PINID='\1\';
NET_NAME
'L3_40OHM_6INCH'
 '@BASEBOARD_FAB2_LIB.BASEBOARD_FAB2(SCH_1):L3_40OHM_6INCH':
 C_SIGNAL='@baseboard_fab2_lib.baseboard_fab2(sch_1):l3_40ohm_6inch';
NODE_NAME     T1P26 1
 '@BASEBOARD_FAB2_LIB.BASEBOARD_FAB2(SCH_1):PAGE271_I52@W_HDL.TPAD-SE-2P-GP(CHIPS)':
 '1': CDS_PINID='\1\';
NET_NAME
'L3_50OHM_6INCH'
 '@BASEBOARD_FAB2_LIB.BASEBOARD_FAB2(SCH_1):L3_50OHM_6INCH':
 C_SIGNAL='@baseboard_fab2_lib.baseboard_fab2(sch_1):l3_50ohm_6inch';
NODE_NAME     T1P32 1
 '@BASEBOARD_FAB2_LIB.BASEBOARD_FAB2(SCH_1):PAGE271_I72@W_HDL.TPAD-SE-2P-GP(CHIPS)':
 '1': CDS_PINID='\1\';
NET_NAME
'L3_73OHM_6INCH_DN'
 '@BASEBOARD_FAB2_LIB.BASEBOARD_FAB2(SCH_1):L3_73OHM_6INCH_DN':
 C_SIGNAL='@baseboard_fab2_lib.baseboard_fab2(sch_1):l3_73ohm_6inch_dn';
NODE_NAME     T1P8 2
 '@BASEBOARD_FAB2_LIB.BASEBOARD_FAB2(SCH_1):PAGE271_I16@W_HDL.TPAD-DIFF-4P-GP(CHIPS)':
 '2': CDS_PINID='\2\';
NET_NAME
'L3_73OHM_6INCH_DP'
 '@BASEBOARD_FAB2_LIB.BASEBOARD_FAB2(SCH_1):L3_73OHM_6INCH_DP':
 C_SIGNAL='@baseboard_fab2_lib.baseboard_fab2(sch_1):l3_73ohm_6inch_dp';
NODE_NAME     T1P8 1
 '@BASEBOARD_FAB2_LIB.BASEBOARD_FAB2(SCH_1):PAGE271_I16@W_HDL.TPAD-DIFF-4P-GP(CHIPS)':
 '1': CDS_PINID='\1\';
NET_NAME
'L3_85OHM_10INCH_DN'
 '@BASEBOARD_FAB2_LIB.BASEBOARD_FAB2(SCH_1):L3_85OHM_10INCH_DN':
 C_SIGNAL='@baseboard_fab2_lib.baseboard_fab2(sch_1):l3_85ohm_10inch_dn';
NODE_NAME     T1D15 2
 '@BASEBOARD_FAB2_LIB.BASEBOARD_FAB2(SCH_1):PAGE272_I3@W_HDL.TEST-PAD-12P-1-GP-U(CHIPS)':
 'DN': CDS_PINID='DN';
NODE_NAME     T1D16 1
 '@BASEBOARD_FAB2_LIB.BASEBOARD_FAB2(SCH_1):PAGE272_I14@W_HDL.TEST-PAD-12P-1-GP-U(CHIPS)':
 'DP': CDS_PINID='DP';
NET_NAME
'L3_85OHM_10INCH_DP'
 '@BASEBOARD_FAB2_LIB.BASEBOARD_FAB2(SCH_1):L3_85OHM_10INCH_DP':
 C_SIGNAL='@baseboard_fab2_lib.baseboard_fab2(sch_1):l3_85ohm_10inch_dp';
NODE_NAME     T1D15 1
 '@BASEBOARD_FAB2_LIB.BASEBOARD_FAB2(SCH_1):PAGE272_I3@W_HDL.TEST-PAD-12P-1-GP-U(CHIPS)':
 'DP': CDS_PINID='DP';
NODE_NAME     T1D16 2
 '@BASEBOARD_FAB2_LIB.BASEBOARD_FAB2(SCH_1):PAGE272_I14@W_HDL.TEST-PAD-12P-1-GP-U(CHIPS)':
 'DN': CDS_PINID='DN';
NET_NAME
'L3_85OHM_5INCH_DN'
 '@BASEBOARD_FAB2_LIB.BASEBOARD_FAB2(SCH_1):L3_85OHM_5INCH_DN':
 C_SIGNAL='@baseboard_fab2_lib.baseboard_fab2(sch_1):l3_85ohm_5inch_dn';
NODE_NAME     T1D3 2
 '@BASEBOARD_FAB2_LIB.BASEBOARD_FAB2(SCH_1):PAGE270_I5@W_HDL.TEST-PAD-12P-1-GP-U(CHIPS)':
 'DN': CDS_PINID='DN';
NODE_NAME     T1D4 1
 '@BASEBOARD_FAB2_LIB.BASEBOARD_FAB2(SCH_1):PAGE270_I6@W_HDL.TEST-PAD-12P-1-GP-U(CHIPS)':
 'DP': CDS_PINID='DP';
NET_NAME
'L3_85OHM_5INCH_DP'
 '@BASEBOARD_FAB2_LIB.BASEBOARD_FAB2(SCH_1):L3_85OHM_5INCH_DP':
 C_SIGNAL='@baseboard_fab2_lib.baseboard_fab2(sch_1):l3_85ohm_5inch_dp';
NODE_NAME     T1D3 1
 '@BASEBOARD_FAB2_LIB.BASEBOARD_FAB2(SCH_1):PAGE270_I5@W_HDL.TEST-PAD-12P-1-GP-U(CHIPS)':
 'DP': CDS_PINID='DP';
NODE_NAME     T1D4 2
 '@BASEBOARD_FAB2_LIB.BASEBOARD_FAB2(SCH_1):PAGE270_I6@W_HDL.TEST-PAD-12P-1-GP-U(CHIPS)':
 'DN': CDS_PINID='DN';
NET_NAME
'L3_85OHM_6INCH_DN'
 '@BASEBOARD_FAB2_LIB.BASEBOARD_FAB2(SCH_1):L3_85OHM_6INCH_DN':
 C_SIGNAL='@baseboard_fab2_lib.baseboard_fab2(sch_1):l3_85ohm_6inch_dn';
NODE_NAME     T1P2 2
 '@BASEBOARD_FAB2_LIB.BASEBOARD_FAB2(SCH_1):PAGE271_I5@W_HDL.TPAD-DIFF-4P-GP(CHIPS)':
 '2': CDS_PINID='\2\';
NET_NAME
'L3_85OHM_6INCH_DP'
 '@BASEBOARD_FAB2_LIB.BASEBOARD_FAB2(SCH_1):L3_85OHM_6INCH_DP':
 C_SIGNAL='@baseboard_fab2_lib.baseboard_fab2(sch_1):l3_85ohm_6inch_dp';
NODE_NAME     T1P2 1
 '@BASEBOARD_FAB2_LIB.BASEBOARD_FAB2(SCH_1):PAGE271_I5@W_HDL.TPAD-DIFF-4P-GP(CHIPS)':
 '1': CDS_PINID='\1\';
NET_NAME
'L5_40OHM_6INCH'
 '@BASEBOARD_FAB2_LIB.BASEBOARD_FAB2(SCH_1):L5_40OHM_6INCH':
 C_SIGNAL='@baseboard_fab2_lib.baseboard_fab2(sch_1):l5_40ohm_6inch';
NODE_NAME     T1P27 1
 '@BASEBOARD_FAB2_LIB.BASEBOARD_FAB2(SCH_1):PAGE271_I54@W_HDL.TPAD-SE-2P-GP(CHIPS)':
 '1': CDS_PINID='\1\';
NET_NAME
'L5_50OHM_6INCH'
 '@BASEBOARD_FAB2_LIB.BASEBOARD_FAB2(SCH_1):L5_50OHM_6INCH':
 C_SIGNAL='@baseboard_fab2_lib.baseboard_fab2(sch_1):l5_50ohm_6inch';
NODE_NAME     T1P33 1
 '@BASEBOARD_FAB2_LIB.BASEBOARD_FAB2(SCH_1):PAGE271_I73@W_HDL.TPAD-SE-2P-GP(CHIPS)':
 '1': CDS_PINID='\1\';
NET_NAME
'L5_73OHM_6INCH_DN'
 '@BASEBOARD_FAB2_LIB.BASEBOARD_FAB2(SCH_1):L5_73OHM_6INCH_DN':
 C_SIGNAL='@baseboard_fab2_lib.baseboard_fab2(sch_1):l5_73ohm_6inch_dn';
NODE_NAME     T1P9 2
 '@BASEBOARD_FAB2_LIB.BASEBOARD_FAB2(SCH_1):PAGE271_I19@W_HDL.TPAD-DIFF-4P-GP(CHIPS)':
 '2': CDS_PINID='\2\';
NET_NAME
'L5_73OHM_6INCH_DP'
 '@BASEBOARD_FAB2_LIB.BASEBOARD_FAB2(SCH_1):L5_73OHM_6INCH_DP':
 C_SIGNAL='@baseboard_fab2_lib.baseboard_fab2(sch_1):l5_73ohm_6inch_dp';
NODE_NAME     T1P9 1
 '@BASEBOARD_FAB2_LIB.BASEBOARD_FAB2(SCH_1):PAGE271_I19@W_HDL.TPAD-DIFF-4P-GP(CHIPS)':
 '1': CDS_PINID='\1\';
NET_NAME
'L5_85OHM_10INCH_DN'
 '@BASEBOARD_FAB2_LIB.BASEBOARD_FAB2(SCH_1):L5_85OHM_10INCH_DN':
 C_SIGNAL='@baseboard_fab2_lib.baseboard_fab2(sch_1):l5_85ohm_10inch_dn';
NODE_NAME     T1D17 2
 '@BASEBOARD_FAB2_LIB.BASEBOARD_FAB2(SCH_1):PAGE272_I1@W_HDL.TEST-PAD-12P-1-GP-U(CHIPS)':
 'DN': CDS_PINID='DN';
NODE_NAME     T1D18 1
 '@BASEBOARD_FAB2_LIB.BASEBOARD_FAB2(SCH_1):PAGE272_I8@W_HDL.TEST-PAD-12P-1-GP-U(CHIPS)':
 'DP': CDS_PINID='DP';
NET_NAME
'L5_85OHM_10INCH_DP'
 '@BASEBOARD_FAB2_LIB.BASEBOARD_FAB2(SCH_1):L5_85OHM_10INCH_DP':
 C_SIGNAL='@baseboard_fab2_lib.baseboard_fab2(sch_1):l5_85ohm_10inch_dp';
NODE_NAME     T1D17 1
 '@BASEBOARD_FAB2_LIB.BASEBOARD_FAB2(SCH_1):PAGE272_I1@W_HDL.TEST-PAD-12P-1-GP-U(CHIPS)':
 'DP': CDS_PINID='DP';
NODE_NAME     T1D18 2
 '@BASEBOARD_FAB2_LIB.BASEBOARD_FAB2(SCH_1):PAGE272_I8@W_HDL.TEST-PAD-12P-1-GP-U(CHIPS)':
 'DN': CDS_PINID='DN';
NET_NAME
'L5_85OHM_5INCH_DN'
 '@BASEBOARD_FAB2_LIB.BASEBOARD_FAB2(SCH_1):L5_85OHM_5INCH_DN':
 C_SIGNAL='@baseboard_fab2_lib.baseboard_fab2(sch_1):l5_85ohm_5inch_dn';
NODE_NAME     T1D6 1
 '@BASEBOARD_FAB2_LIB.BASEBOARD_FAB2(SCH_1):PAGE270_I9@W_HDL.TEST-PAD-12P-1-GP-U(CHIPS)':
 'DP': CDS_PINID='DP';
NODE_NAME     T1D5 2
 '@BASEBOARD_FAB2_LIB.BASEBOARD_FAB2(SCH_1):PAGE270_I12@W_HDL.TEST-PAD-12P-1-GP-U(CHIPS)':
 'DN': CDS_PINID='DN';
NET_NAME
'L5_85OHM_5INCH_DP'
 '@BASEBOARD_FAB2_LIB.BASEBOARD_FAB2(SCH_1):L5_85OHM_5INCH_DP':
 C_SIGNAL='@baseboard_fab2_lib.baseboard_fab2(sch_1):l5_85ohm_5inch_dp';
NODE_NAME     T1D6 2
 '@BASEBOARD_FAB2_LIB.BASEBOARD_FAB2(SCH_1):PAGE270_I9@W_HDL.TEST-PAD-12P-1-GP-U(CHIPS)':
 'DN': CDS_PINID='DN';
NODE_NAME     T1D5 1
 '@BASEBOARD_FAB2_LIB.BASEBOARD_FAB2(SCH_1):PAGE270_I12@W_HDL.TEST-PAD-12P-1-GP-U(CHIPS)':
 'DP': CDS_PINID='DP';
NET_NAME
'L5_85OHM_6INCH_DN'
 '@BASEBOARD_FAB2_LIB.BASEBOARD_FAB2(SCH_1):L5_85OHM_6INCH_DN':
 C_SIGNAL='@baseboard_fab2_lib.baseboard_fab2(sch_1):l5_85ohm_6inch_dn';
NODE_NAME     T1P3 2
 '@BASEBOARD_FAB2_LIB.BASEBOARD_FAB2(SCH_1):PAGE271_I8@W_HDL.TPAD-DIFF-4P-GP(CHIPS)':
 '2': CDS_PINID='\2\';
NET_NAME
'L5_85OHM_6INCH_DP'
 '@BASEBOARD_FAB2_LIB.BASEBOARD_FAB2(SCH_1):L5_85OHM_6INCH_DP':
 C_SIGNAL='@baseboard_fab2_lib.baseboard_fab2(sch_1):l5_85ohm_6inch_dp';
NODE_NAME     T1P3 1
 '@BASEBOARD_FAB2_LIB.BASEBOARD_FAB2(SCH_1):PAGE271_I8@W_HDL.TPAD-DIFF-4P-GP(CHIPS)':
 '1': CDS_PINID='\1\';
NET_NAME
'LED_GBE_P0_0'
 '@BASEBOARD_FAB2_LIB.BASEBOARD_FAB2(SCH_1):LED_GBE_P0_0':
 C_SIGNAL='@baseboard_fab2_lib.baseboard_fab2(sch_1):led_gbe_p0_0';
NODE_NAME     U7C1 BL1
 '@BASEBOARD_FAB2_LIB.BASEBOARD_FAB2(SCH_1):PAGE120_I147@MSTR_U_PROC.LBG_CORE_QAT_EXT_D(CHIPS)':
 'GPP_J0_LAN_LED_P0_0': CDS_PINID='GPP_J0_LAN_LED_P0_0';
NODE_NAME     J8E4 43
 '@BASEBOARD_FAB2_LIB.BASEBOARD_FAB2(SCH_1):PAGE188_I27@MSTR_SCONN.SCONN64_H87568002_A(CHIPS)':
 'IO43': CDS_PINID='IO43';
NET_NAME
'LED_GBE_P0_1'
 '@BASEBOARD_FAB2_LIB.BASEBOARD_FAB2(SCH_1):LED_GBE_P0_1':
 C_SIGNAL='@baseboard_fab2_lib.baseboard_fab2(sch_1):led_gbe_p0_1';
NODE_NAME     U7C1 BK4
 '@BASEBOARD_FAB2_LIB.BASEBOARD_FAB2(SCH_1):PAGE120_I147@MSTR_U_PROC.LBG_CORE_QAT_EXT_D(CHIPS)':
 'GPP_J1_LAN_LED_P0_1': CDS_PINID='GPP_J1_LAN_LED_P0_1';
NODE_NAME     J8E4 44
 '@BASEBOARD_FAB2_LIB.BASEBOARD_FAB2(SCH_1):PAGE188_I27@MSTR_SCONN.SCONN64_H87568002_A(CHIPS)':
 'IO44': CDS_PINID='IO44';
NET_NAME
'LED_GBE_P1_0'
 '@BASEBOARD_FAB2_LIB.BASEBOARD_FAB2(SCH_1):LED_GBE_P1_0':
 C_SIGNAL='@baseboard_fab2_lib.baseboard_fab2(sch_1):led_gbe_p1_0';
NODE_NAME     U7C1 BP4
 '@BASEBOARD_FAB2_LIB.BASEBOARD_FAB2(SCH_1):PAGE120_I147@MSTR_U_PROC.LBG_CORE_QAT_EXT_D(CHIPS)':
 'GPP_J2_LAN_LED_P1_0': CDS_PINID='GPP_J2_LAN_LED_P1_0';
NODE_NAME     J8E4 8
 '@BASEBOARD_FAB2_LIB.BASEBOARD_FAB2(SCH_1):PAGE188_I27@MSTR_SCONN.SCONN64_H87568002_A(CHIPS)':
 'IO8': CDS_PINID='IO8';
NET_NAME
'LED_GBE_P1_1'
 '@BASEBOARD_FAB2_LIB.BASEBOARD_FAB2(SCH_1):LED_GBE_P1_1':
 C_SIGNAL='@baseboard_fab2_lib.baseboard_fab2(sch_1):led_gbe_p1_1';
NODE_NAME     U7C1 BK2
 '@BASEBOARD_FAB2_LIB.BASEBOARD_FAB2(SCH_1):PAGE120_I147@MSTR_U_PROC.LBG_CORE_QAT_EXT_D(CHIPS)':
 'GPP_J3_LAN_LED_P1_1': CDS_PINID='GPP_J3_LAN_LED_P1_1';
NODE_NAME     J8E4 9
 '@BASEBOARD_FAB2_LIB.BASEBOARD_FAB2(SCH_1):PAGE188_I27@MSTR_SCONN.SCONN64_H87568002_A(CHIPS)':
 'IO9': CDS_PINID='IO9';
NET_NAME
'LED_GBE_P2_0'
 '@BASEBOARD_FAB2_LIB.BASEBOARD_FAB2(SCH_1):LED_GBE_P2_0':
 C_SIGNAL='@baseboard_fab2_lib.baseboard_fab2(sch_1):led_gbe_p2_0';
NODE_NAME     U7C1 BL3
 '@BASEBOARD_FAB2_LIB.BASEBOARD_FAB2(SCH_1):PAGE120_I147@MSTR_U_PROC.LBG_CORE_QAT_EXT_D(CHIPS)':
 'GPP_J4_LAN_LED_P2_0': CDS_PINID='GPP_J4_LAN_LED_P2_0';
NODE_NAME     J8E4 14
 '@BASEBOARD_FAB2_LIB.BASEBOARD_FAB2(SCH_1):PAGE188_I27@MSTR_SCONN.SCONN64_H87568002_A(CHIPS)':
 'IO14': CDS_PINID='IO14';
NET_NAME
'LED_GBE_P2_1'
 '@BASEBOARD_FAB2_LIB.BASEBOARD_FAB2(SCH_1):LED_GBE_P2_1':
 C_SIGNAL='@baseboard_fab2_lib.baseboard_fab2(sch_1):led_gbe_p2_1';
NODE_NAME     U7C1 BU6
 '@BASEBOARD_FAB2_LIB.BASEBOARD_FAB2(SCH_1):PAGE120_I147@MSTR_U_PROC.LBG_CORE_QAT_EXT_D(CHIPS)':
 'GPP_J5_LAN_LED_P2_1': CDS_PINID='GPP_J5_LAN_LED_P2_1';
NODE_NAME     J8E4 15
 '@BASEBOARD_FAB2_LIB.BASEBOARD_FAB2(SCH_1):PAGE188_I27@MSTR_SCONN.SCONN64_H87568002_A(CHIPS)':
 'IO15': CDS_PINID='IO15';
NET_NAME
'LED_GBE_P3_0'
 '@BASEBOARD_FAB2_LIB.BASEBOARD_FAB2(SCH_1):LED_GBE_P3_0':
 C_SIGNAL='@baseboard_fab2_lib.baseboard_fab2(sch_1):led_gbe_p3_0';
NODE_NAME     U7C1 CA13
 '@BASEBOARD_FAB2_LIB.BASEBOARD_FAB2(SCH_1):PAGE120_I147@MSTR_U_PROC.LBG_CORE_QAT_EXT_D(CHIPS)':
 'GPP_J6_LAN_LED_P3_0': CDS_PINID='GPP_J6_LAN_LED_P3_0';
NODE_NAME     J8E4 55
 '@BASEBOARD_FAB2_LIB.BASEBOARD_FAB2(SCH_1):PAGE188_I27@MSTR_SCONN.SCONN64_H87568002_A(CHIPS)':
 'IO55': CDS_PINID='IO55';
NET_NAME
'LED_GBE_P3_1'
 '@BASEBOARD_FAB2_LIB.BASEBOARD_FAB2(SCH_1):LED_GBE_P3_1':
 C_SIGNAL='@baseboard_fab2_lib.baseboard_fab2(sch_1):led_gbe_p3_1';
NODE_NAME     U7C1 BM2
 '@BASEBOARD_FAB2_LIB.BASEBOARD_FAB2(SCH_1):PAGE120_I147@MSTR_U_PROC.LBG_CORE_QAT_EXT_D(CHIPS)':
 'GPP_J7_LAN_LED_P3_1': CDS_PINID='GPP_J7_LAN_LED_P3_1';
NODE_NAME     J8E4 56
 '@BASEBOARD_FAB2_LIB.BASEBOARD_FAB2(SCH_1):PAGE188_I27@MSTR_SCONN.SCONN64_H87568002_A(CHIPS)':
 'IO56': CDS_PINID='IO56';
NET_NAME
'LED_HFI0_CPU0_N'
 '@BASEBOARD_FAB2_LIB.BASEBOARD_FAB2(SCH_1):LED_HFI0_CPU0_N':
 C_SIGNAL='@baseboard_fab2_lib.baseboard_fab2(sch_1):led_hfi0_cpu0_n';
NODE_NAME     U5D1 BK21
 '@BASEBOARD_FAB2_LIB.BASEBOARD_FAB2(SCH_1):PAGE29_I61@CHPSET_LIB.SKX_EXT_B(CHIPS)':
 'CD_HFI0_LED_N': CDS_PINID='CD_HFI0_LED_N';
NODE_NAME     J8B1 5
 '@BASEBOARD_FAB2_LIB.BASEBOARD_FAB2(SCH_1):PAGE91_I1@MSTR_SCONN.SCONN24_H46321001(CHIPS)':
 'IO5': CDS_PINID='IO5';
NODE_NAME     R8B5 2
 '@BASEBOARD_FAB2_LIB.BASEBOARD_FAB2(SCH_1):PAGE91_I22@MSTR_DISCRETE.RES(CHIPS)':
 'B': CDS_PINID='B';
NET_NAME
'LED_HFI1_CPU0_N'
 '@BASEBOARD_FAB2_LIB.BASEBOARD_FAB2(SCH_1):LED_HFI1_CPU0_N':
 C_SIGNAL='@baseboard_fab2_lib.baseboard_fab2(sch_1):led_hfi1_cpu0_n';
NODE_NAME     U5D1 BM23
 '@BASEBOARD_FAB2_LIB.BASEBOARD_FAB2(SCH_1):PAGE29_I61@CHPSET_LIB.SKX_EXT_B(CHIPS)':
 'CD_HFI1_LED_N': CDS_PINID='CD_HFI1_LED_N';
NODE_NAME     J8B1 13
 '@BASEBOARD_FAB2_LIB.BASEBOARD_FAB2(SCH_1):PAGE91_I1@MSTR_SCONN.SCONN24_H46321001(CHIPS)':
 'IO13': CDS_PINID='IO13';
NODE_NAME     R8B18 2
 '@BASEBOARD_FAB2_LIB.BASEBOARD_FAB2(SCH_1):PAGE91_I20@MSTR_DISCRETE.RES(CHIPS)':
 'B': CDS_PINID='B';
NET_NAME
'LED_LAN_0_N'
 '@BASEBOARD_FAB2_LIB.BASEBOARD_FAB2(SCH_1):LED_LAN_0_N':
 C_SIGNAL='@baseboard_fab2_lib.baseboard_fab2(sch_1):led_lan_0_n';
NODE_NAME     EU9E1 31
 '@BASEBOARD_FAB2_LIB.BASEBOARD_FAB2(SCH_1):PAGE139_I72@MSTR_INTEL.SPRINGVILLE(CHIPS)':
 'LED0': CDS_PINID='LED0';
NODE_NAME     R9G3 2
 '@BASEBOARD_FAB2_LIB.BASEBOARD_FAB2(SCH_1):PAGE141_I135@MSTR_DISCRETE.RES(CHIPS)':
 'B': CDS_PINID='B';
NODE_NAME     C9G3 1
 '@BASEBOARD_FAB2_LIB.BASEBOARD_FAB2(SCH_1):PAGE141_I138@MSTR_DISCRETE.CAP(CHIPS)':
 'A': CDS_PINID='A';
NET_NAME
'LED_LAN_0_R_N'
 '@BASEBOARD_FAB2_LIB.BASEBOARD_FAB2(SCH_1):LED_LAN_0_R_N':
 C_SIGNAL='@baseboard_fab2_lib.baseboard_fab2(sch_1):led_lan_0_r_n';
NODE_NAME     JA9G1 L2
 '@BASEBOARD_FAB2_LIB.BASEBOARD_FAB2(SCH_1):PAGE141_I129@W_HDL.SKT-RJ45-LED-XFOR-1-GP(CHIPS)':
 'L2': CDS_PINID='L2';
NODE_NAME     R9G3 1
 '@BASEBOARD_FAB2_LIB.BASEBOARD_FAB2(SCH_1):PAGE141_I135@MSTR_DISCRETE.RES(CHIPS)':
 'A': CDS_PINID='A';
NET_NAME
'LED_LAN_1_N'
 '@BASEBOARD_FAB2_LIB.BASEBOARD_FAB2(SCH_1):LED_LAN_1_N':
 C_SIGNAL='@baseboard_fab2_lib.baseboard_fab2(sch_1):led_lan_1_n';
NODE_NAME     EU9E1 30
 '@BASEBOARD_FAB2_LIB.BASEBOARD_FAB2(SCH_1):PAGE139_I72@MSTR_INTEL.SPRINGVILLE(CHIPS)':
 'LED1': CDS_PINID='LED1';
NODE_NAME     R9G1 1
 '@BASEBOARD_FAB2_LIB.BASEBOARD_FAB2(SCH_1):PAGE141_I157@MSTR_DISCRETE.RES(CHIPS)':
 'A': CDS_PINID='A';
NODE_NAME     C9F22 1
 '@BASEBOARD_FAB2_LIB.BASEBOARD_FAB2(SCH_1):PAGE141_I159@MSTR_DISCRETE.CAP(CHIPS)':
 'A': CDS_PINID='A';
NET_NAME
'LED_LAN_1_R_N'
 '@BASEBOARD_FAB2_LIB.BASEBOARD_FAB2(SCH_1):LED_LAN_1_R_N':
 C_SIGNAL='@baseboard_fab2_lib.baseboard_fab2(sch_1):led_lan_1_r_n';
NODE_NAME     JA9G1 L3
 '@BASEBOARD_FAB2_LIB.BASEBOARD_FAB2(SCH_1):PAGE141_I129@W_HDL.SKT-RJ45-LED-XFOR-1-GP(CHIPS)':
 'L3': CDS_PINID='L3';
NODE_NAME     R9G1 2
 '@BASEBOARD_FAB2_LIB.BASEBOARD_FAB2(SCH_1):PAGE141_I157@MSTR_DISCRETE.RES(CHIPS)':
 'B': CDS_PINID='B';
NET_NAME
'LED_LAN_2_N'
 '@BASEBOARD_FAB2_LIB.BASEBOARD_FAB2(SCH_1):LED_LAN_2_N':
 C_SIGNAL='@baseboard_fab2_lib.baseboard_fab2(sch_1):led_lan_2_n';
NODE_NAME     EU9E1 33
 '@BASEBOARD_FAB2_LIB.BASEBOARD_FAB2(SCH_1):PAGE139_I72@MSTR_INTEL.SPRINGVILLE(CHIPS)':
 'LED2': CDS_PINID='LED2';
NODE_NAME     R9G2 2
 '@BASEBOARD_FAB2_LIB.BASEBOARD_FAB2(SCH_1):PAGE141_I134@MSTR_DISCRETE.RES(CHIPS)':
 'B': CDS_PINID='B';
NODE_NAME     C9G1 1
 '@BASEBOARD_FAB2_LIB.BASEBOARD_FAB2(SCH_1):PAGE141_I140@MSTR_DISCRETE.CAP(CHIPS)':
 'A': CDS_PINID='A';
NET_NAME
'LED_LAN_2_R_N'
 '@BASEBOARD_FAB2_LIB.BASEBOARD_FAB2(SCH_1):LED_LAN_2_R_N':
 C_SIGNAL='@baseboard_fab2_lib.baseboard_fab2(sch_1):led_lan_2_r_n';
NODE_NAME     JA9G1 L1
 '@BASEBOARD_FAB2_LIB.BASEBOARD_FAB2(SCH_1):PAGE141_I129@W_HDL.SKT-RJ45-LED-XFOR-1-GP(CHIPS)':
 'L1': CDS_PINID='L1';
NODE_NAME     R9G2 1
 '@BASEBOARD_FAB2_LIB.BASEBOARD_FAB2(SCH_1):PAGE141_I134@MSTR_DISCRETE.RES(CHIPS)':
 'A': CDS_PINID='A';
NET_NAME
'LED_P5V_STBY'
 '@BASEBOARD_FAB2_LIB.BASEBOARD_FAB2(SCH_1):LED_P5V_STBY':
 C_SIGNAL='@baseboard_fab2_lib.baseboard_fab2(sch_1):led_p5v_stby';
NODE_NAME     DS9A6 1
 '@BASEBOARD_FAB2_LIB.BASEBOARD_FAB2(SCH_1):PAGE177_I31@MSTR_DISCRETE.LED(CHIPS)':
 'A': CDS_PINID='A';
NODE_NAME     R1L37 2
 '@BASEBOARD_FAB2_LIB.BASEBOARD_FAB2(SCH_1):PAGE177_I33@MSTR_DISCRETE.RES(CHIPS)':
 'B': CDS_PINID='B';
NET_NAME
'LED_PCH_SATA_HDD_N'
 '@BASEBOARD_FAB2_LIB.BASEBOARD_FAB2(SCH_1):LED_PCH_SATA_HDD_N':
 C_SIGNAL='@baseboard_fab2_lib.baseboard_fab2(sch_1):led_pch_sata_hdd_n';
NODE_NAME     U7C1 AV56
 '@BASEBOARD_FAB2_LIB.BASEBOARD_FAB2(SCH_1):PAGE120_I147@MSTR_U_PROC.LBG_CORE_QAT_EXT_D(CHIPS)':
 'GPP_E8_SATA_LED_N': CDS_PINID='GPP_E8_SATA_LED_N';
NODE_NAME     R1M10 1
 '@BASEBOARD_FAB2_LIB.BASEBOARD_FAB2(SCH_1):PAGE177_I6@MSTR_DISCRETE.RES(CHIPS)':
 'A': CDS_PINID='A';
NET_NAME
'LED_PCH_SSATA_HDD_N'
 '@BASEBOARD_FAB2_LIB.BASEBOARD_FAB2(SCH_1):LED_PCH_SSATA_HDD_N':
 C_SIGNAL='@baseboard_fab2_lib.baseboard_fab2(sch_1):led_pch_ssata_hdd_n';
NODE_NAME     U7C1 AL11
 '@BASEBOARD_FAB2_LIB.BASEBOARD_FAB2(SCH_1):PAGE120_I147@MSTR_U_PROC.LBG_CORE_QAT_EXT_D(CHIPS)':
 'GPP_F14_SSATA_LED_N': CDS_PINID='GPP_F14_SSATA_LED_N';
NODE_NAME     R1M13 1
 '@BASEBOARD_FAB2_LIB.BASEBOARD_FAB2(SCH_1):PAGE177_I3@MSTR_DISCRETE.RES(CHIPS)':
 'A': CDS_PINID='A';
NET_NAME
'LED_POSTCODE_0'
 '@BASEBOARD_FAB2_LIB.BASEBOARD_FAB2(SCH_1):LED_POSTCODE_0':
 C_SIGNAL='@baseboard_fab2_lib.baseboard_fab2(sch_1):led_postcode_0';
NODE_NAME     R1L32 1
 '@BASEBOARD_FAB2_LIB.BASEBOARD_FAB2(SCH_1):PAGE155_I65@MSTR_DISCRETE.RES(CHIPS)':
 'A': CDS_PINID='A';
NODE_NAME     U25W4 A18
 '@BASEBOARD_FAB2_LIB.BASEBOARD_FAB2(SCH_1):PAGE146_I104@W_HDL.AST2520A1-GP-GP(CHIPS)':
 'GPIOH0_NCTS6': CDS_PINID='GPIOH0_NCTS6';
NET_NAME
'LED_POSTCODE_0_R'
 '@BASEBOARD_FAB2_LIB.BASEBOARD_FAB2(SCH_1):LED_POSTCODE_0_R':
 C_SIGNAL='@baseboard_fab2_lib.baseboard_fab2(sch_1):led_postcode_0_r';
NODE_NAME     R1L32 2
 '@BASEBOARD_FAB2_LIB.BASEBOARD_FAB2(SCH_1):PAGE155_I65@MSTR_DISCRETE.RES(CHIPS)':
 'B': CDS_PINID='B';
NODE_NAME     J9A2 1
 '@BASEBOARD_FAB2_LIB.BASEBOARD_FAB2(SCH_1):PAGE155_I171@MSTR_CONN.CONN14_H54902001(CHIPS)':
 'IO1': CDS_PINID='IO1';
NODE_NAME     U6W1 4
 '@BASEBOARD_FAB2_LIB.BASEBOARD_FAB2(SCH_1):PAGE247_I120@W_HDL.TCA9555PWR-GP(CHIPS)':
 'P00': CDS_PINID='P00';
NET_NAME
'LED_POSTCODE_1'
 '@BASEBOARD_FAB2_LIB.BASEBOARD_FAB2(SCH_1):LED_POSTCODE_1':
 C_SIGNAL='@baseboard_fab2_lib.baseboard_fab2(sch_1):led_postcode_1';
NODE_NAME     R1L30 1
 '@BASEBOARD_FAB2_LIB.BASEBOARD_FAB2(SCH_1):PAGE155_I66@MSTR_DISCRETE.RES(CHIPS)':
 'A': CDS_PINID='A';
NODE_NAME     U25W4 B18
 '@BASEBOARD_FAB2_LIB.BASEBOARD_FAB2(SCH_1):PAGE146_I104@W_HDL.AST2520A1-GP-GP(CHIPS)':
 'GPIOH1_NDCD6': CDS_PINID='GPIOH1_NDCD6';
NET_NAME
'LED_POSTCODE_1_R'
 '@BASEBOARD_FAB2_LIB.BASEBOARD_FAB2(SCH_1):LED_POSTCODE_1_R':
 C_SIGNAL='@baseboard_fab2_lib.baseboard_fab2(sch_1):led_postcode_1_r';
NODE_NAME     R1L30 2
 '@BASEBOARD_FAB2_LIB.BASEBOARD_FAB2(SCH_1):PAGE155_I66@MSTR_DISCRETE.RES(CHIPS)':
 'B': CDS_PINID='B';
NODE_NAME     J9A2 2
 '@BASEBOARD_FAB2_LIB.BASEBOARD_FAB2(SCH_1):PAGE155_I171@MSTR_CONN.CONN14_H54902001(CHIPS)':
 'IO2': CDS_PINID='IO2';
NODE_NAME     U6W1 5
 '@BASEBOARD_FAB2_LIB.BASEBOARD_FAB2(SCH_1):PAGE247_I120@W_HDL.TCA9555PWR-GP(CHIPS)':
 'P01': CDS_PINID='P01';
NET_NAME
'LED_POSTCODE_2'
 '@BASEBOARD_FAB2_LIB.BASEBOARD_FAB2(SCH_1):LED_POSTCODE_2':
 C_SIGNAL='@baseboard_fab2_lib.baseboard_fab2(sch_1):led_postcode_2';
NODE_NAME     R1L25 1
 '@BASEBOARD_FAB2_LIB.BASEBOARD_FAB2(SCH_1):PAGE155_I67@MSTR_DISCRETE.RES(CHIPS)':
 'A': CDS_PINID='A';
NODE_NAME     U25W4 D17
 '@BASEBOARD_FAB2_LIB.BASEBOARD_FAB2(SCH_1):PAGE146_I104@W_HDL.AST2520A1-GP-GP(CHIPS)':
 'GPIOH2_NDSR6': CDS_PINID='GPIOH2_NDSR6';
NET_NAME
'LED_POSTCODE_2_R'
 '@BASEBOARD_FAB2_LIB.BASEBOARD_FAB2(SCH_1):LED_POSTCODE_2_R':
 C_SIGNAL='@baseboard_fab2_lib.baseboard_fab2(sch_1):led_postcode_2_r';
NODE_NAME     R1L25 2
 '@BASEBOARD_FAB2_LIB.BASEBOARD_FAB2(SCH_1):PAGE155_I67@MSTR_DISCRETE.RES(CHIPS)':
 'B': CDS_PINID='B';
NODE_NAME     J9A2 3
 '@BASEBOARD_FAB2_LIB.BASEBOARD_FAB2(SCH_1):PAGE155_I171@MSTR_CONN.CONN14_H54902001(CHIPS)':
 'IO3': CDS_PINID='IO3';
NODE_NAME     U6W1 6
 '@BASEBOARD_FAB2_LIB.BASEBOARD_FAB2(SCH_1):PAGE247_I120@W_HDL.TCA9555PWR-GP(CHIPS)':
 'P02': CDS_PINID='P02';
NET_NAME
'LED_POSTCODE_3'
 '@BASEBOARD_FAB2_LIB.BASEBOARD_FAB2(SCH_1):LED_POSTCODE_3':
 C_SIGNAL='@baseboard_fab2_lib.baseboard_fab2(sch_1):led_postcode_3';
NODE_NAME     R1L24 1
 '@BASEBOARD_FAB2_LIB.BASEBOARD_FAB2(SCH_1):PAGE155_I68@MSTR_DISCRETE.RES(CHIPS)':
 'A': CDS_PINID='A';
NODE_NAME     U25W4 C17
 '@BASEBOARD_FAB2_LIB.BASEBOARD_FAB2(SCH_1):PAGE146_I104@W_HDL.AST2520A1-GP-GP(CHIPS)':
 'GPIOH3_NRI6': CDS_PINID='GPIOH3_NRI6';
NET_NAME
'LED_POSTCODE_3_R'
 '@BASEBOARD_FAB2_LIB.BASEBOARD_FAB2(SCH_1):LED_POSTCODE_3_R':
 C_SIGNAL='@baseboard_fab2_lib.baseboard_fab2(sch_1):led_postcode_3_r';
NODE_NAME     R1L24 2
 '@BASEBOARD_FAB2_LIB.BASEBOARD_FAB2(SCH_1):PAGE155_I68@MSTR_DISCRETE.RES(CHIPS)':
 'B': CDS_PINID='B';
NODE_NAME     J9A2 4
 '@BASEBOARD_FAB2_LIB.BASEBOARD_FAB2(SCH_1):PAGE155_I171@MSTR_CONN.CONN14_H54902001(CHIPS)':
 'IO4': CDS_PINID='IO4';
NODE_NAME     U6W1 7
 '@BASEBOARD_FAB2_LIB.BASEBOARD_FAB2(SCH_1):PAGE247_I120@W_HDL.TCA9555PWR-GP(CHIPS)':
 'P03': CDS_PINID='P03';
NET_NAME
'LED_POSTCODE_4'
 '@BASEBOARD_FAB2_LIB.BASEBOARD_FAB2(SCH_1):LED_POSTCODE_4':
 C_SIGNAL='@baseboard_fab2_lib.baseboard_fab2(sch_1):led_postcode_4';
NODE_NAME     R1L20 1
 '@BASEBOARD_FAB2_LIB.BASEBOARD_FAB2(SCH_1):PAGE155_I73@MSTR_DISCRETE.RES(CHIPS)':
 'A': CDS_PINID='A';
NODE_NAME     U25W4 A17
 '@BASEBOARD_FAB2_LIB.BASEBOARD_FAB2(SCH_1):PAGE146_I104@W_HDL.AST2520A1-GP-GP(CHIPS)':
 'GPIOH4_NDTR6': CDS_PINID='GPIOH4_NDTR6';
NET_NAME
'LED_POSTCODE_4_R'
 '@BASEBOARD_FAB2_LIB.BASEBOARD_FAB2(SCH_1):LED_POSTCODE_4_R':
 C_SIGNAL='@baseboard_fab2_lib.baseboard_fab2(sch_1):led_postcode_4_r';
NODE_NAME     R1L20 2
 '@BASEBOARD_FAB2_LIB.BASEBOARD_FAB2(SCH_1):PAGE155_I73@MSTR_DISCRETE.RES(CHIPS)':
 'B': CDS_PINID='B';
NODE_NAME     J9A2 5
 '@BASEBOARD_FAB2_LIB.BASEBOARD_FAB2(SCH_1):PAGE155_I171@MSTR_CONN.CONN14_H54902001(CHIPS)':
 'IO5': CDS_PINID='IO5';
NODE_NAME     U6W1 8
 '@BASEBOARD_FAB2_LIB.BASEBOARD_FAB2(SCH_1):PAGE247_I120@W_HDL.TCA9555PWR-GP(CHIPS)':
 'P04': CDS_PINID='P04';
NET_NAME
'LED_POSTCODE_5'
 '@BASEBOARD_FAB2_LIB.BASEBOARD_FAB2(SCH_1):LED_POSTCODE_5':
 C_SIGNAL='@baseboard_fab2_lib.baseboard_fab2(sch_1):led_postcode_5';
NODE_NAME     R1L18 1
 '@BASEBOARD_FAB2_LIB.BASEBOARD_FAB2(SCH_1):PAGE155_I74@MSTR_DISCRETE.RES(CHIPS)':
 'A': CDS_PINID='A';
NODE_NAME     U25W4 B17
 '@BASEBOARD_FAB2_LIB.BASEBOARD_FAB2(SCH_1):PAGE146_I104@W_HDL.AST2520A1-GP-GP(CHIPS)':
 'GPIOH5_NRTS6': CDS_PINID='GPIOH5_NRTS6';
NET_NAME
'LED_POSTCODE_5_R'
 '@BASEBOARD_FAB2_LIB.BASEBOARD_FAB2(SCH_1):LED_POSTCODE_5_R':
 C_SIGNAL='@baseboard_fab2_lib.baseboard_fab2(sch_1):led_postcode_5_r';
NODE_NAME     R1L18 2
 '@BASEBOARD_FAB2_LIB.BASEBOARD_FAB2(SCH_1):PAGE155_I74@MSTR_DISCRETE.RES(CHIPS)':
 'B': CDS_PINID='B';
NODE_NAME     J9A2 6
 '@BASEBOARD_FAB2_LIB.BASEBOARD_FAB2(SCH_1):PAGE155_I171@MSTR_CONN.CONN14_H54902001(CHIPS)':
 'IO6': CDS_PINID='IO6';
NODE_NAME     U6W1 9
 '@BASEBOARD_FAB2_LIB.BASEBOARD_FAB2(SCH_1):PAGE247_I120@W_HDL.TCA9555PWR-GP(CHIPS)':
 'P05': CDS_PINID='P05';
NET_NAME
'LED_POSTCODE_6'
 '@BASEBOARD_FAB2_LIB.BASEBOARD_FAB2(SCH_1):LED_POSTCODE_6':
 C_SIGNAL='@baseboard_fab2_lib.baseboard_fab2(sch_1):led_postcode_6';
NODE_NAME     R1L14 1
 '@BASEBOARD_FAB2_LIB.BASEBOARD_FAB2(SCH_1):PAGE155_I75@MSTR_DISCRETE.RES(CHIPS)':
 'A': CDS_PINID='A';
NODE_NAME     U25W4 A16
 '@BASEBOARD_FAB2_LIB.BASEBOARD_FAB2(SCH_1):PAGE146_I104@W_HDL.AST2520A1-GP-GP(CHIPS)':
 'GPIOH6_TXD6': CDS_PINID='GPIOH6_TXD6';
NET_NAME
'LED_POSTCODE_6_R'
 '@BASEBOARD_FAB2_LIB.BASEBOARD_FAB2(SCH_1):LED_POSTCODE_6_R':
 C_SIGNAL='@baseboard_fab2_lib.baseboard_fab2(sch_1):led_postcode_6_r';
NODE_NAME     R1L14 2
 '@BASEBOARD_FAB2_LIB.BASEBOARD_FAB2(SCH_1):PAGE155_I75@MSTR_DISCRETE.RES(CHIPS)':
 'B': CDS_PINID='B';
NODE_NAME     J9A2 7
 '@BASEBOARD_FAB2_LIB.BASEBOARD_FAB2(SCH_1):PAGE155_I171@MSTR_CONN.CONN14_H54902001(CHIPS)':
 'IO7': CDS_PINID='IO7';
NODE_NAME     U6W1 10
 '@BASEBOARD_FAB2_LIB.BASEBOARD_FAB2(SCH_1):PAGE247_I120@W_HDL.TCA9555PWR-GP(CHIPS)':
 'P06': CDS_PINID='P06';
NET_NAME
'LED_POSTCODE_7'
 '@BASEBOARD_FAB2_LIB.BASEBOARD_FAB2(SCH_1):LED_POSTCODE_7':
 C_SIGNAL='@baseboard_fab2_lib.baseboard_fab2(sch_1):led_postcode_7';
NODE_NAME     R1L11 1
 '@BASEBOARD_FAB2_LIB.BASEBOARD_FAB2(SCH_1):PAGE155_I76@MSTR_DISCRETE.RES(CHIPS)':
 'A': CDS_PINID='A';
NODE_NAME     U25W4 D18
 '@BASEBOARD_FAB2_LIB.BASEBOARD_FAB2(SCH_1):PAGE146_I104@W_HDL.AST2520A1-GP-GP(CHIPS)':
 'GPIOH7_RXD6': CDS_PINID='GPIOH7_RXD6';
NET_NAME
'LED_POSTCODE_7_R'
 '@BASEBOARD_FAB2_LIB.BASEBOARD_FAB2(SCH_1):LED_POSTCODE_7_R':
 C_SIGNAL='@baseboard_fab2_lib.baseboard_fab2(sch_1):led_postcode_7_r';
NODE_NAME     R1L11 2
 '@BASEBOARD_FAB2_LIB.BASEBOARD_FAB2(SCH_1):PAGE155_I76@MSTR_DISCRETE.RES(CHIPS)':
 'B': CDS_PINID='B';
NODE_NAME     J9A2 8
 '@BASEBOARD_FAB2_LIB.BASEBOARD_FAB2(SCH_1):PAGE155_I171@MSTR_CONN.CONN14_H54902001(CHIPS)':
 'IO8': CDS_PINID='IO8';
NODE_NAME     U6W1 11
 '@BASEBOARD_FAB2_LIB.BASEBOARD_FAB2(SCH_1):PAGE247_I120@W_HDL.TCA9555PWR-GP(CHIPS)':
 'P07': CDS_PINID='P07';
NET_NAME
'LED_SAS_ACT_R_N'
 '@BASEBOARD_FAB2_LIB.BASEBOARD_FAB2(SCH_1):LED_SAS_ACT_R_N':
 C_SIGNAL='@baseboard_fab2_lib.baseboard_fab2(sch_1):led_sas_act_r_n';
NODE_NAME     R1M13 2
 '@BASEBOARD_FAB2_LIB.BASEBOARD_FAB2(SCH_1):PAGE177_I3@MSTR_DISCRETE.RES(CHIPS)':
 'B': CDS_PINID='B';
NODE_NAME     R1M12 2
 '@BASEBOARD_FAB2_LIB.BASEBOARD_FAB2(SCH_1):PAGE177_I8@MSTR_DISCRETE.RES(CHIPS)':
 'B': CDS_PINID='B';
NODE_NAME     U1M1 2
 '@BASEBOARD_FAB2_LIB.BASEBOARD_FAB2(SCH_1):PAGE177_I70@MSTR_TTL.TTL1G08(CHIPS)':
 'B'<0>: CDS_PINID='B(0)';
NET_NAME
'LED_SATA_ACT_R_N'
 '@BASEBOARD_FAB2_LIB.BASEBOARD_FAB2(SCH_1):LED_SATA_ACT_R_N':
 C_SIGNAL='@baseboard_fab2_lib.baseboard_fab2(sch_1):led_sata_act_r_n';
NODE_NAME     R1M10 2
 '@BASEBOARD_FAB2_LIB.BASEBOARD_FAB2(SCH_1):PAGE177_I6@MSTR_DISCRETE.RES(CHIPS)':
 'B': CDS_PINID='B';
NODE_NAME     R1M11 2
 '@BASEBOARD_FAB2_LIB.BASEBOARD_FAB2(SCH_1):PAGE177_I9@MSTR_DISCRETE.RES(CHIPS)':
 'B': CDS_PINID='B';
NODE_NAME     U1M1 1
 '@BASEBOARD_FAB2_LIB.BASEBOARD_FAB2(SCH_1):PAGE177_I70@MSTR_TTL.TTL1G08(CHIPS)':
 'A'<0>: CDS_PINID='A(0)';
NET_NAME
'LPC_LAD0_IO0'
 '@BASEBOARD_FAB2_LIB.BASEBOARD_FAB2(SCH_1):LPC_LAD0_IO0':
 C_SIGNAL='@baseboard_fab2_lib.baseboard_fab2(sch_1):lpc_lad0_io0';
NODE_NAME     U7C1 Y3
 '@BASEBOARD_FAB2_LIB.BASEBOARD_FAB2(SCH_1):PAGE119_I115@MSTR_U_PROC.LBG_CORE_QAT_EXT_D(CHIPS)':
 'GPP_A1_LAD0_ESPI_IO0': CDS_PINID='GPP_A1_LAD0_ESPI_IO0';
NODE_NAME     R3N26 1
 '@BASEBOARD_FAB2_LIB.BASEBOARD_FAB2(SCH_1):PAGE146_I75@MSTR_DISCRETE.RES(CHIPS)':
 'A': CDS_PINID='A';
NET_NAME
'LPC_LAD0_IO0_R'
 '@BASEBOARD_FAB2_LIB.BASEBOARD_FAB2(SCH_1):LPC_LAD0_IO0_R':
 C_SIGNAL='@baseboard_fab2_lib.baseboard_fab2(sch_1):lpc_lad0_io0_r';
NODE_NAME     R3N26 2
 '@BASEBOARD_FAB2_LIB.BASEBOARD_FAB2(SCH_1):PAGE146_I75@MSTR_DISCRETE.RES(CHIPS)':
 'B': CDS_PINID='B';
NODE_NAME     U25W4 G21
 '@BASEBOARD_FAB2_LIB.BASEBOARD_FAB2(SCH_1):PAGE146_I105@W_HDL.AST2520A1-GP-GP(CHIPS)':
 'GPIOAC0_ESPID0_LAD0': CDS_PINID='GPIOAC0_ESPID0_LAD0';
NET_NAME
'LPC_LAD1_IO1'
 '@BASEBOARD_FAB2_LIB.BASEBOARD_FAB2(SCH_1):LPC_LAD1_IO1':
 C_SIGNAL='@baseboard_fab2_lib.baseboard_fab2(sch_1):lpc_lad1_io1';
NODE_NAME     U7C1 N1
 '@BASEBOARD_FAB2_LIB.BASEBOARD_FAB2(SCH_1):PAGE119_I115@MSTR_U_PROC.LBG_CORE_QAT_EXT_D(CHIPS)':
 'GPP_A2_LAD1_ESPI_IO1': CDS_PINID='GPP_A2_LAD1_ESPI_IO1';
NODE_NAME     R25W69 1
 '@BASEBOARD_FAB2_LIB.BASEBOARD_FAB2(SCH_1):PAGE146_I85@MSTR_DISCRETE.RES(CHIPS)':
 'A': CDS_PINID='A';
NET_NAME
'LPC_LAD1_IO1_R'
 '@BASEBOARD_FAB2_LIB.BASEBOARD_FAB2(SCH_1):LPC_LAD1_IO1_R':
 C_SIGNAL='@baseboard_fab2_lib.baseboard_fab2(sch_1):lpc_lad1_io1_r';
NODE_NAME     R25W69 2
 '@BASEBOARD_FAB2_LIB.BASEBOARD_FAB2(SCH_1):PAGE146_I85@MSTR_DISCRETE.RES(CHIPS)':
 'B': CDS_PINID='B';
NODE_NAME     U25W4 G20
 '@BASEBOARD_FAB2_LIB.BASEBOARD_FAB2(SCH_1):PAGE146_I105@W_HDL.AST2520A1-GP-GP(CHIPS)':
 'GPIOAC1_ESPID1_LAD1': CDS_PINID='GPIOAC1_ESPID1_LAD1';
NET_NAME
'LPC_LAD2_IO2'
 '@BASEBOARD_FAB2_LIB.BASEBOARD_FAB2(SCH_1):LPC_LAD2_IO2':
 C_SIGNAL='@baseboard_fab2_lib.baseboard_fab2(sch_1):lpc_lad2_io2';
NODE_NAME     U7C1 W2
 '@BASEBOARD_FAB2_LIB.BASEBOARD_FAB2(SCH_1):PAGE119_I115@MSTR_U_PROC.LBG_CORE_QAT_EXT_D(CHIPS)':
 'GPP_A3_LAD2_ESPI_IO2': CDS_PINID='GPP_A3_LAD2_ESPI_IO2';
NODE_NAME     R3N24 1
 '@BASEBOARD_FAB2_LIB.BASEBOARD_FAB2(SCH_1):PAGE146_I74@MSTR_DISCRETE.RES(CHIPS)':
 'A': CDS_PINID='A';
NET_NAME
'LPC_LAD2_IO2_R'
 '@BASEBOARD_FAB2_LIB.BASEBOARD_FAB2(SCH_1):LPC_LAD2_IO2_R':
 C_SIGNAL='@baseboard_fab2_lib.baseboard_fab2(sch_1):lpc_lad2_io2_r';
NODE_NAME     R3N24 2
 '@BASEBOARD_FAB2_LIB.BASEBOARD_FAB2(SCH_1):PAGE146_I74@MSTR_DISCRETE.RES(CHIPS)':
 'B': CDS_PINID='B';
NODE_NAME     U25W4 D22
 '@BASEBOARD_FAB2_LIB.BASEBOARD_FAB2(SCH_1):PAGE146_I105@W_HDL.AST2520A1-GP-GP(CHIPS)':
 'GPIOAC2_ESPID2_LAD2': CDS_PINID='GPIOAC2_ESPID2_LAD2';
NET_NAME
'LPC_LAD3_IO3'
 '@BASEBOARD_FAB2_LIB.BASEBOARD_FAB2(SCH_1):LPC_LAD3_IO3':
 C_SIGNAL='@baseboard_fab2_lib.baseboard_fab2(sch_1):lpc_lad3_io3';
NODE_NAME     U7C1 Y1
 '@BASEBOARD_FAB2_LIB.BASEBOARD_FAB2(SCH_1):PAGE119_I115@MSTR_U_PROC.LBG_CORE_QAT_EXT_D(CHIPS)':
 'GPP_A4_LAD3_ESPI_IO3': CDS_PINID='GPP_A4_LAD3_ESPI_IO3';
NODE_NAME     R25W68 1
 '@BASEBOARD_FAB2_LIB.BASEBOARD_FAB2(SCH_1):PAGE146_I84@MSTR_DISCRETE.RES(CHIPS)':
 'A': CDS_PINID='A';
NET_NAME
'LPC_LAD3_IO3_R'
 '@BASEBOARD_FAB2_LIB.BASEBOARD_FAB2(SCH_1):LPC_LAD3_IO3_R':
 C_SIGNAL='@baseboard_fab2_lib.baseboard_fab2(sch_1):lpc_lad3_io3_r';
NODE_NAME     R25W68 2
 '@BASEBOARD_FAB2_LIB.BASEBOARD_FAB2(SCH_1):PAGE146_I84@MSTR_DISCRETE.RES(CHIPS)':
 'B': CDS_PINID='B';
NODE_NAME     U25W4 E22
 '@BASEBOARD_FAB2_LIB.BASEBOARD_FAB2(SCH_1):PAGE146_I105@W_HDL.AST2520A1-GP-GP(CHIPS)':
 'GPIOAC3_ESPID3_LAD3': CDS_PINID='GPIOAC3_ESPID3_LAD3';
NET_NAME
'LPC_LFRAME_N_CS0_N'
 '@BASEBOARD_FAB2_LIB.BASEBOARD_FAB2(SCH_1):LPC_LFRAME_N_CS0_N':
 C_SIGNAL='@baseboard_fab2_lib.baseboard_fab2(sch_1):lpc_lframe_n_cs0_n';
NODE_NAME     U7C1 P4
 '@BASEBOARD_FAB2_LIB.BASEBOARD_FAB2(SCH_1):PAGE119_I115@MSTR_U_PROC.LBG_CORE_QAT_EXT_D(CHIPS)':
 'GPP_A5_LFRAME_N_ESPI_CS0_N': CDS_PINID='GPP_A5_LFRAME_N_ESPI_CS0_N';
NODE_NAME     R25W72 1
 '@BASEBOARD_FAB2_LIB.BASEBOARD_FAB2(SCH_1):PAGE146_I71@MSTR_DISCRETE.RES(CHIPS)':
 'A': CDS_PINID='A';
NET_NAME
'LPC_LFRAME_N_CS0_R_N'
 '@BASEBOARD_FAB2_LIB.BASEBOARD_FAB2(SCH_1):LPC_LFRAME_N_CS0_R_N':
 C_SIGNAL='@baseboard_fab2_lib.baseboard_fab2(sch_1):lpc_lframe_n_cs0_r_n';
NODE_NAME     R25W72 2
 '@BASEBOARD_FAB2_LIB.BASEBOARD_FAB2(SCH_1):PAGE146_I71@MSTR_DISCRETE.RES(CHIPS)':
 'B': CDS_PINID='B';
NODE_NAME     U25W4 F21
 '@BASEBOARD_FAB2_LIB.BASEBOARD_FAB2(SCH_1):PAGE146_I105@W_HDL.AST2520A1-GP-GP(CHIPS)':
 'GPIOAC5_ESPICS#_LFRAME#': CDS_PINID='\gpioac5_espics#_lframe#\';
NET_NAME
'M_ABC_RST_N'
 '@BASEBOARD_FAB2_LIB.BASEBOARD_FAB2(SCH_1):M_ABC_RST_N':
 C_SIGNAL='@baseboard_fab2_lib.baseboard_fab2(sch_1):m_abc_rst_n';
NODE_NAME     U5D1 U64
 '@BASEBOARD_FAB2_LIB.BASEBOARD_FAB2(SCH_1):PAGE21_I259@CHPSET_LIB.SKX_EXT_B(CHIPS)':
 'DDR012_RESET_N': CDS_PINID='DDR012_RESET_N';
NODE_NAME     J4G1 58
 '@BASEBOARD_FAB2_LIB.BASEBOARD_FAB2(SCH_1):PAGE43_I1@MSTR_SCONN.SCONN288_H44441004(CHIPS)':
 'RESET_N': CDS_PINID='RESET_N';
NODE_NAME     J6T1 58
 '@BASEBOARD_FAB2_LIB.BASEBOARD_FAB2(SCH_1):PAGE44_I13@MSTR_SCONN.SCONN288_H44441003(CHIPS)':
 'RESET_N': CDS_PINID='RESET_N';
NODE_NAME     J4G2 58
 '@BASEBOARD_FAB2_LIB.BASEBOARD_FAB2(SCH_1):PAGE45_I111@MSTR_SCONN.SCONN288_H44441004(CHIPS)':
 'RESET_N': CDS_PINID='RESET_N';
NODE_NAME     J6U1 58
 '@BASEBOARD_FAB2_LIB.BASEBOARD_FAB2(SCH_1):PAGE46_I14@MSTR_SCONN.SCONN288_H44441003(CHIPS)':
 'RESET_N': CDS_PINID='RESET_N';
NODE_NAME     J4G3 58
 '@BASEBOARD_FAB2_LIB.BASEBOARD_FAB2(SCH_1):PAGE47_I111@MSTR_SCONN.SCONN288_H44441004(CHIPS)':
 'RESET_N': CDS_PINID='RESET_N';
NODE_NAME     J6U2 58
 '@BASEBOARD_FAB2_LIB.BASEBOARD_FAB2(SCH_1):PAGE48_I111@MSTR_SCONN.SCONN288_H44441003(CHIPS)':
 'RESET_N': CDS_PINID='RESET_N';
NET_NAME
'M_A_ACT_N'
 '@BASEBOARD_FAB2_LIB.BASEBOARD_FAB2(SCH_1):M_A_ACT_N':
 C_SIGNAL='@baseboard_fab2_lib.baseboard_fab2(sch_1):m_a_act_n';
NODE_NAME     U5D1 J60
 '@BASEBOARD_FAB2_LIB.BASEBOARD_FAB2(SCH_1):PAGE23_I172@CHPSET_LIB.SKX_EXT_B(CHIPS)':
 'DDR0_ACT_N': CDS_PINID='DDR0_ACT_N';
NODE_NAME     J4G1 62
 '@BASEBOARD_FAB2_LIB.BASEBOARD_FAB2(SCH_1):PAGE43_I1@MSTR_SCONN.SCONN288_H44441004(CHIPS)':
 'ACT_N': CDS_PINID='ACT_N';
NODE_NAME     J6T1 62
 '@BASEBOARD_FAB2_LIB.BASEBOARD_FAB2(SCH_1):PAGE44_I13@MSTR_SCONN.SCONN288_H44441003(CHIPS)':
 'ACT_N': CDS_PINID='ACT_N';
NET_NAME
'M_A_ALERT_N'
 '@BASEBOARD_FAB2_LIB.BASEBOARD_FAB2(SCH_1):M_A_ALERT_N':
 C_SIGNAL='@baseboard_fab2_lib.baseboard_fab2(sch_1):m_a_alert_n';
NODE_NAME     U5D1 B61
 '@BASEBOARD_FAB2_LIB.BASEBOARD_FAB2(SCH_1):PAGE23_I172@CHPSET_LIB.SKX_EXT_B(CHIPS)':
 'DDR0_ALERT_N': CDS_PINID='DDR0_ALERT_N';
NODE_NAME     J4G1 208
 '@BASEBOARD_FAB2_LIB.BASEBOARD_FAB2(SCH_1):PAGE43_I1@MSTR_SCONN.SCONN288_H44441004(CHIPS)':
 'ALERT_N': CDS_PINID='ALERT_N';
NODE_NAME     J6T1 208
 '@BASEBOARD_FAB2_LIB.BASEBOARD_FAB2(SCH_1):PAGE44_I13@MSTR_SCONN.SCONN288_H44441003(CHIPS)':
 'ALERT_N': CDS_PINID='ALERT_N';
NET_NAME
'M_A_BA<0>'
 '@BASEBOARD_FAB2_LIB.BASEBOARD_FAB2(SCH_1):M_A_BA'<0>:
 C_SIGNAL='@baseboard_fab2_lib.baseboard_fab2(sch_1):m_a_ba(0)';
NODE_NAME     U5D1 C52
 '@BASEBOARD_FAB2_LIB.BASEBOARD_FAB2(SCH_1):PAGE23_I172@CHPSET_LIB.SKX_EXT_B(CHIPS)':
 'DDR0_BA'<0>: CDS_PINID='DDR0_BA(0)';
NODE_NAME     J4G1 81
 '@BASEBOARD_FAB2_LIB.BASEBOARD_FAB2(SCH_1):PAGE43_I1@MSTR_SCONN.SCONN288_H44441004(CHIPS)':
 'BA'<0>: CDS_PINID='BA(0)';
NODE_NAME     J6T1 81
 '@BASEBOARD_FAB2_LIB.BASEBOARD_FAB2(SCH_1):PAGE44_I13@MSTR_SCONN.SCONN288_H44441003(CHIPS)':
 'BA'<0>: CDS_PINID='BA(0)';
NET_NAME
'M_A_BA<1>'
 '@BASEBOARD_FAB2_LIB.BASEBOARD_FAB2(SCH_1):M_A_BA'<1>:
 C_SIGNAL='@baseboard_fab2_lib.baseboard_fab2(sch_1):m_a_ba(1)';
NODE_NAME     U5D1 G54
 '@BASEBOARD_FAB2_LIB.BASEBOARD_FAB2(SCH_1):PAGE23_I172@CHPSET_LIB.SKX_EXT_B(CHIPS)':
 'DDR0_BA'<1>: CDS_PINID='DDR0_BA(1)';
NODE_NAME     J4G1 224
 '@BASEBOARD_FAB2_LIB.BASEBOARD_FAB2(SCH_1):PAGE43_I1@MSTR_SCONN.SCONN288_H44441004(CHIPS)':
 'BA'<1>: CDS_PINID='BA(1)';
NODE_NAME     J6T1 224
 '@BASEBOARD_FAB2_LIB.BASEBOARD_FAB2(SCH_1):PAGE44_I13@MSTR_SCONN.SCONN288_H44441003(CHIPS)':
 'BA'<1>: CDS_PINID='BA(1)';
NET_NAME
'M_A_BG<0>'
 '@BASEBOARD_FAB2_LIB.BASEBOARD_FAB2(SCH_1):M_A_BG'<0>:
 C_SIGNAL='@baseboard_fab2_lib.baseboard_fab2(sch_1):m_a_bg(0)';
NODE_NAME     U5D1 D61
 '@BASEBOARD_FAB2_LIB.BASEBOARD_FAB2(SCH_1):PAGE23_I172@CHPSET_LIB.SKX_EXT_B(CHIPS)':
 'DDR0_BG'<0>: CDS_PINID='DDR0_BG(0)';
NODE_NAME     J4G1 63
 '@BASEBOARD_FAB2_LIB.BASEBOARD_FAB2(SCH_1):PAGE43_I1@MSTR_SCONN.SCONN288_H44441004(CHIPS)':
 'BG'<0>: CDS_PINID='BG(0)';
NODE_NAME     J6T1 63
 '@BASEBOARD_FAB2_LIB.BASEBOARD_FAB2(SCH_1):PAGE44_I13@MSTR_SCONN.SCONN288_H44441003(CHIPS)':
 'BG'<0>: CDS_PINID='BG(0)';
NET_NAME
'M_A_BG<1>'
 '@BASEBOARD_FAB2_LIB.BASEBOARD_FAB2(SCH_1):M_A_BG'<1>:
 C_SIGNAL='@baseboard_fab2_lib.baseboard_fab2(sch_1):m_a_bg(1)';
NODE_NAME     U5D1 F63
 '@BASEBOARD_FAB2_LIB.BASEBOARD_FAB2(SCH_1):PAGE23_I172@CHPSET_LIB.SKX_EXT_B(CHIPS)':
 'DDR0_BG'<1>: CDS_PINID='DDR0_BG(1)';
NODE_NAME     J4G1 207
 '@BASEBOARD_FAB2_LIB.BASEBOARD_FAB2(SCH_1):PAGE43_I1@MSTR_SCONN.SCONN288_H44441004(CHIPS)':
 'BG'<1>: CDS_PINID='BG(1)';
NODE_NAME     J6T1 207
 '@BASEBOARD_FAB2_LIB.BASEBOARD_FAB2(SCH_1):PAGE44_I13@MSTR_SCONN.SCONN288_H44441003(CHIPS)':
 'BG'<1>: CDS_PINID='BG(1)';
NET_NAME
'M_A_C<2>'
 '@BASEBOARD_FAB2_LIB.BASEBOARD_FAB2(SCH_1):M_A_C'<2>:
 C_SIGNAL='@baseboard_fab2_lib.baseboard_fab2(sch_1):m_a_c(2)';
NODE_NAME     U5D1 G46
 '@BASEBOARD_FAB2_LIB.BASEBOARD_FAB2(SCH_1):PAGE23_I172@CHPSET_LIB.SKX_EXT_B(CHIPS)':
 'DDR0_CID'<2>: CDS_PINID='DDR0_CID(2)';
NODE_NAME     J4G1 235
 '@BASEBOARD_FAB2_LIB.BASEBOARD_FAB2(SCH_1):PAGE43_I1@MSTR_SCONN.SCONN288_H44441004(CHIPS)':
 'C'<2>: CDS_PINID='C(2)';
NODE_NAME     J6T1 235
 '@BASEBOARD_FAB2_LIB.BASEBOARD_FAB2(SCH_1):PAGE44_I13@MSTR_SCONN.SCONN288_H44441003(CHIPS)':
 'C'<2>: CDS_PINID='C(2)';
NET_NAME
'M_A_CKE<0>'
 '@BASEBOARD_FAB2_LIB.BASEBOARD_FAB2(SCH_1):M_A_CKE'<0>:
 C_SIGNAL='@baseboard_fab2_lib.baseboard_fab2(sch_1):m_a_cke(0)';
NODE_NAME     U5D1 C62
 '@BASEBOARD_FAB2_LIB.BASEBOARD_FAB2(SCH_1):PAGE23_I172@CHPSET_LIB.SKX_EXT_B(CHIPS)':
 'DDR0_CKE'<0>: CDS_PINID='DDR0_CKE(0)';
NODE_NAME     J4G1 60
 '@BASEBOARD_FAB2_LIB.BASEBOARD_FAB2(SCH_1):PAGE43_I1@MSTR_SCONN.SCONN288_H44441004(CHIPS)':
 'CKE'<0>: CDS_PINID='CKE(0)';
NET_NAME
'M_A_CKE<1>'
 '@BASEBOARD_FAB2_LIB.BASEBOARD_FAB2(SCH_1):M_A_CKE'<1>:
 C_SIGNAL='@baseboard_fab2_lib.baseboard_fab2(sch_1):m_a_cke(1)';
NODE_NAME     U5D1 C64
 '@BASEBOARD_FAB2_LIB.BASEBOARD_FAB2(SCH_1):PAGE23_I172@CHPSET_LIB.SKX_EXT_B(CHIPS)':
 'DDR0_CKE'<1>: CDS_PINID='DDR0_CKE(1)';
NODE_NAME     J4G1 203
 '@BASEBOARD_FAB2_LIB.BASEBOARD_FAB2(SCH_1):PAGE43_I1@MSTR_SCONN.SCONN288_H44441004(CHIPS)':
 'CKE'<1>: CDS_PINID='CKE(1)';
NET_NAME
'M_A_CKE<2>'
 '@BASEBOARD_FAB2_LIB.BASEBOARD_FAB2(SCH_1):M_A_CKE'<2>:
 C_SIGNAL='@baseboard_fab2_lib.baseboard_fab2(sch_1):m_a_cke(2)';
NODE_NAME     U5D1 B63
 '@BASEBOARD_FAB2_LIB.BASEBOARD_FAB2(SCH_1):PAGE23_I172@CHPSET_LIB.SKX_EXT_B(CHIPS)':
 'DDR0_CKE'<2>: CDS_PINID='DDR0_CKE(2)';
NODE_NAME     J6T1 60
 '@BASEBOARD_FAB2_LIB.BASEBOARD_FAB2(SCH_1):PAGE44_I13@MSTR_SCONN.SCONN288_H44441003(CHIPS)':
 'CKE'<0>: CDS_PINID='CKE(0)';
NET_NAME
'M_A_CKE<3>'
 '@BASEBOARD_FAB2_LIB.BASEBOARD_FAB2(SCH_1):M_A_CKE'<3>:
 C_SIGNAL='@baseboard_fab2_lib.baseboard_fab2(sch_1):m_a_cke(3)';
NODE_NAME     U5D1 D63
 '@BASEBOARD_FAB2_LIB.BASEBOARD_FAB2(SCH_1):PAGE23_I172@CHPSET_LIB.SKX_EXT_B(CHIPS)':
 'DDR0_CKE'<3>: CDS_PINID='DDR0_CKE(3)';
NODE_NAME     J6T1 203
 '@BASEBOARD_FAB2_LIB.BASEBOARD_FAB2(SCH_1):PAGE44_I13@MSTR_SCONN.SCONN288_H44441003(CHIPS)':
 'CKE'<1>: CDS_PINID='CKE(1)';
NET_NAME
'M_A_CLK_DN<0>'
 '@BASEBOARD_FAB2_LIB.BASEBOARD_FAB2(SCH_1):M_A_CLK_DN'<0>:
 C_SIGNAL='@baseboard_fab2_lib.baseboard_fab2(sch_1):m_a_clk_dn(0)';
NODE_NAME     U5D1 F55
 '@BASEBOARD_FAB2_LIB.BASEBOARD_FAB2(SCH_1):PAGE23_I172@CHPSET_LIB.SKX_EXT_B(CHIPS)':
 'DDR0_CLK_DN'<0>: CDS_PINID='DDR0_CLK_DN(0)';
NODE_NAME     J4G1 75
 '@BASEBOARD_FAB2_LIB.BASEBOARD_FAB2(SCH_1):PAGE43_I1@MSTR_SCONN.SCONN288_H44441004(CHIPS)':
 'CK0N': CDS_PINID='CK0N';
NET_NAME
'M_A_CLK_DN<1>'
 '@BASEBOARD_FAB2_LIB.BASEBOARD_FAB2(SCH_1):M_A_CLK_DN'<1>:
 C_SIGNAL='@baseboard_fab2_lib.baseboard_fab2(sch_1):m_a_clk_dn(1)';
NODE_NAME     U5D1 C54
 '@BASEBOARD_FAB2_LIB.BASEBOARD_FAB2(SCH_1):PAGE23_I172@CHPSET_LIB.SKX_EXT_B(CHIPS)':
 'DDR0_CLK_DN'<1>: CDS_PINID='DDR0_CLK_DN(1)';
NODE_NAME     J4G1 219
 '@BASEBOARD_FAB2_LIB.BASEBOARD_FAB2(SCH_1):PAGE43_I1@MSTR_SCONN.SCONN288_H44441004(CHIPS)':
 'CK1N': CDS_PINID='CK1N';
NET_NAME
'M_A_CLK_DN<2>'
 '@BASEBOARD_FAB2_LIB.BASEBOARD_FAB2(SCH_1):M_A_CLK_DN'<2>:
 C_SIGNAL='@baseboard_fab2_lib.baseboard_fab2(sch_1):m_a_clk_dn(2)';
NODE_NAME     U5D1 J56
 '@BASEBOARD_FAB2_LIB.BASEBOARD_FAB2(SCH_1):PAGE23_I172@CHPSET_LIB.SKX_EXT_B(CHIPS)':
 'DDR0_CLK_DN'<2>: CDS_PINID='DDR0_CLK_DN(2)';
NODE_NAME     J6T1 75
 '@BASEBOARD_FAB2_LIB.BASEBOARD_FAB2(SCH_1):PAGE44_I13@MSTR_SCONN.SCONN288_H44441003(CHIPS)':
 'CK0N': CDS_PINID='CK0N';
NET_NAME
'M_A_CLK_DN<3>'
 '@BASEBOARD_FAB2_LIB.BASEBOARD_FAB2(SCH_1):M_A_CLK_DN'<3>:
 C_SIGNAL='@baseboard_fab2_lib.baseboard_fab2(sch_1):m_a_clk_dn(3)';
NODE_NAME     U5D1 C56
 '@BASEBOARD_FAB2_LIB.BASEBOARD_FAB2(SCH_1):PAGE23_I172@CHPSET_LIB.SKX_EXT_B(CHIPS)':
 'DDR0_CLK_DN'<3>: CDS_PINID='DDR0_CLK_DN(3)';
NODE_NAME     J6T1 219
 '@BASEBOARD_FAB2_LIB.BASEBOARD_FAB2(SCH_1):PAGE44_I13@MSTR_SCONN.SCONN288_H44441003(CHIPS)':
 'CK1N': CDS_PINID='CK1N';
NET_NAME
'M_A_CLK_DP<0>'
 '@BASEBOARD_FAB2_LIB.BASEBOARD_FAB2(SCH_1):M_A_CLK_DP'<0>:
 C_SIGNAL='@baseboard_fab2_lib.baseboard_fab2(sch_1):m_a_clk_dp(0)';
NODE_NAME     U5D1 D55
 '@BASEBOARD_FAB2_LIB.BASEBOARD_FAB2(SCH_1):PAGE23_I172@CHPSET_LIB.SKX_EXT_B(CHIPS)':
 'DDR0_CLK_DP'<0>: CDS_PINID='DDR0_CLK_DP(0)';
NODE_NAME     J4G1 74
 '@BASEBOARD_FAB2_LIB.BASEBOARD_FAB2(SCH_1):PAGE43_I1@MSTR_SCONN.SCONN288_H44441004(CHIPS)':
 'CK0P': CDS_PINID='CK0P';
NET_NAME
'M_A_CLK_DP<1>'
 '@BASEBOARD_FAB2_LIB.BASEBOARD_FAB2(SCH_1):M_A_CLK_DP'<1>:
 C_SIGNAL='@baseboard_fab2_lib.baseboard_fab2(sch_1):m_a_clk_dp(1)';
NODE_NAME     U5D1 B55
 '@BASEBOARD_FAB2_LIB.BASEBOARD_FAB2(SCH_1):PAGE23_I172@CHPSET_LIB.SKX_EXT_B(CHIPS)':
 'DDR0_CLK_DP'<1>: CDS_PINID='DDR0_CLK_DP(1)';
NODE_NAME     J4G1 218
 '@BASEBOARD_FAB2_LIB.BASEBOARD_FAB2(SCH_1):PAGE43_I1@MSTR_SCONN.SCONN288_H44441004(CHIPS)':
 'CK1P': CDS_PINID='CK1P';
NET_NAME
'M_A_CLK_DP<2>'
 '@BASEBOARD_FAB2_LIB.BASEBOARD_FAB2(SCH_1):M_A_CLK_DP'<2>:
 C_SIGNAL='@baseboard_fab2_lib.baseboard_fab2(sch_1):m_a_clk_dp(2)';
NODE_NAME     U5D1 G56
 '@BASEBOARD_FAB2_LIB.BASEBOARD_FAB2(SCH_1):PAGE23_I172@CHPSET_LIB.SKX_EXT_B(CHIPS)':
 'DDR0_CLK_DP'<2>: CDS_PINID='DDR0_CLK_DP(2)';
NODE_NAME     J6T1 74
 '@BASEBOARD_FAB2_LIB.BASEBOARD_FAB2(SCH_1):PAGE44_I13@MSTR_SCONN.SCONN288_H44441003(CHIPS)':
 'CK0P': CDS_PINID='CK0P';
NET_NAME
'M_A_CLK_DP<3>'
 '@BASEBOARD_FAB2_LIB.BASEBOARD_FAB2(SCH_1):M_A_CLK_DP'<3>:
 C_SIGNAL='@baseboard_fab2_lib.baseboard_fab2(sch_1):m_a_clk_dp(3)';
NODE_NAME     U5D1 B57
 '@BASEBOARD_FAB2_LIB.BASEBOARD_FAB2(SCH_1):PAGE23_I172@CHPSET_LIB.SKX_EXT_B(CHIPS)':
 'DDR0_CLK_DP'<3>: CDS_PINID='DDR0_CLK_DP(3)';
NODE_NAME     J6T1 218
 '@BASEBOARD_FAB2_LIB.BASEBOARD_FAB2(SCH_1):PAGE44_I13@MSTR_SCONN.SCONN288_H44441003(CHIPS)':
 'CK1P': CDS_PINID='CK1P';
NET_NAME
'M_A_CPU_VREF'
 '@BASEBOARD_FAB2_LIB.BASEBOARD_FAB2(SCH_1):M_A_CPU_VREF':
 C_SIGNAL='@baseboard_fab2_lib.baseboard_fab2(sch_1):m_a_cpu_vref';
NODE_NAME     U5D1 AJ64
 '@BASEBOARD_FAB2_LIB.BASEBOARD_FAB2(SCH_1):PAGE21_I259@CHPSET_LIB.SKX_EXT_B(CHIPS)':
 'DDR0_CAVREF': CDS_PINID='DDR0_CAVREF';
NODE_NAME     R4F3 1
 '@BASEBOARD_FAB2_LIB.BASEBOARD_FAB2(SCH_1):PAGE98_I5@MSTR_DISCRETE.RES(CHIPS)':
 'A': CDS_PINID='A';
NODE_NAME     C4F9 1
 '@BASEBOARD_FAB2_LIB.BASEBOARD_FAB2(SCH_1):PAGE98_I7@DEV_DISCRETE.CAP_A(CHIPS)':
 'A': CDS_PINID='A';
NET_NAME
'M_A_CS_N<0>'
 '@BASEBOARD_FAB2_LIB.BASEBOARD_FAB2(SCH_1):M_A_CS_N'<0>:
 C_SIGNAL='@baseboard_fab2_lib.baseboard_fab2(sch_1):m_a_cs_n(0)';
NODE_NAME     U5D1 G52
 '@BASEBOARD_FAB2_LIB.BASEBOARD_FAB2(SCH_1):PAGE23_I172@CHPSET_LIB.SKX_EXT_B(CHIPS)':
 'DDR0_CS_N'<0>: CDS_PINID='DDR0_CS_N(0)';
NODE_NAME     J4G1 84
 '@BASEBOARD_FAB2_LIB.BASEBOARD_FAB2(SCH_1):PAGE43_I1@MSTR_SCONN.SCONN288_H44441004(CHIPS)':
 'S0_N': CDS_PINID='S0_N';
NET_NAME
'M_A_CS_N<1>'
 '@BASEBOARD_FAB2_LIB.BASEBOARD_FAB2(SCH_1):M_A_CS_N'<1>:
 C_SIGNAL='@baseboard_fab2_lib.baseboard_fab2(sch_1):m_a_cs_n(1)';
NODE_NAME     U5D1 F49
 '@BASEBOARD_FAB2_LIB.BASEBOARD_FAB2(SCH_1):PAGE23_I172@CHPSET_LIB.SKX_EXT_B(CHIPS)':
 'DDR0_CS_N'<1>: CDS_PINID='DDR0_CS_N(1)';
NODE_NAME     J4G1 89
 '@BASEBOARD_FAB2_LIB.BASEBOARD_FAB2(SCH_1):PAGE43_I1@MSTR_SCONN.SCONN288_H44441004(CHIPS)':
 'S1_N': CDS_PINID='S1_N';
NET_NAME
'M_A_CS_N<2>'
 '@BASEBOARD_FAB2_LIB.BASEBOARD_FAB2(SCH_1):M_A_CS_N'<2>:
 C_SIGNAL='@baseboard_fab2_lib.baseboard_fab2(sch_1):m_a_cs_n(2)';
NODE_NAME     U5D1 D47
 '@BASEBOARD_FAB2_LIB.BASEBOARD_FAB2(SCH_1):PAGE23_I172@CHPSET_LIB.SKX_EXT_B(CHIPS)':
 'DDR0_CS_N'<2>: CDS_PINID='DDR0_CS_N(2)';
NODE_NAME     J4G1 93
 '@BASEBOARD_FAB2_LIB.BASEBOARD_FAB2(SCH_1):PAGE43_I1@MSTR_SCONN.SCONN288_H44441004(CHIPS)':
 'S2_N_C'<0>: CDS_PINID='S2_N_C(0)';
NET_NAME
'M_A_CS_N<3>'
 '@BASEBOARD_FAB2_LIB.BASEBOARD_FAB2(SCH_1):M_A_CS_N'<3>:
 C_SIGNAL='@baseboard_fab2_lib.baseboard_fab2(sch_1):m_a_cs_n(3)';
NODE_NAME     U5D1 F47
 '@BASEBOARD_FAB2_LIB.BASEBOARD_FAB2(SCH_1):PAGE23_I172@CHPSET_LIB.SKX_EXT_B(CHIPS)':
 'DDR0_CS_N'<3>: CDS_PINID='DDR0_CS_N(3)';
NODE_NAME     J4G1 237
 '@BASEBOARD_FAB2_LIB.BASEBOARD_FAB2(SCH_1):PAGE43_I1@MSTR_SCONN.SCONN288_H44441004(CHIPS)':
 'S3_N_C'<1>: CDS_PINID='S3_N_C(1)';
NET_NAME
'M_A_CS_N<4>'
 '@BASEBOARD_FAB2_LIB.BASEBOARD_FAB2(SCH_1):M_A_CS_N'<4>:
 C_SIGNAL='@baseboard_fab2_lib.baseboard_fab2(sch_1):m_a_cs_n(4)';
NODE_NAME     U5D1 B51
 '@BASEBOARD_FAB2_LIB.BASEBOARD_FAB2(SCH_1):PAGE23_I172@CHPSET_LIB.SKX_EXT_B(CHIPS)':
 'DDR0_CS_N'<4>: CDS_PINID='DDR0_CS_N(4)';
NODE_NAME     J6T1 84
 '@BASEBOARD_FAB2_LIB.BASEBOARD_FAB2(SCH_1):PAGE44_I13@MSTR_SCONN.SCONN288_H44441003(CHIPS)':
 'S0_N': CDS_PINID='S0_N';
NET_NAME
'M_A_CS_N<5>'
 '@BASEBOARD_FAB2_LIB.BASEBOARD_FAB2(SCH_1):M_A_CS_N'<5>:
 C_SIGNAL='@baseboard_fab2_lib.baseboard_fab2(sch_1):m_a_cs_n(5)';
NODE_NAME     U5D1 D49
 '@BASEBOARD_FAB2_LIB.BASEBOARD_FAB2(SCH_1):PAGE23_I172@CHPSET_LIB.SKX_EXT_B(CHIPS)':
 'DDR0_CS_N'<5>: CDS_PINID='DDR0_CS_N(5)';
NODE_NAME     J6T1 89
 '@BASEBOARD_FAB2_LIB.BASEBOARD_FAB2(SCH_1):PAGE44_I13@MSTR_SCONN.SCONN288_H44441003(CHIPS)':
 'S1_N': CDS_PINID='S1_N';
NET_NAME
'M_A_CS_N<6>'
 '@BASEBOARD_FAB2_LIB.BASEBOARD_FAB2(SCH_1):M_A_CS_N'<6>:
 C_SIGNAL='@baseboard_fab2_lib.baseboard_fab2(sch_1):m_a_cs_n(6)';
NODE_NAME     U5D1 F45
 '@BASEBOARD_FAB2_LIB.BASEBOARD_FAB2(SCH_1):PAGE23_I172@CHPSET_LIB.SKX_EXT_B(CHIPS)':
 'DDR0_CS_N'<6>: CDS_PINID='DDR0_CS_N(6)';
NODE_NAME     J6T1 93
 '@BASEBOARD_FAB2_LIB.BASEBOARD_FAB2(SCH_1):PAGE44_I13@MSTR_SCONN.SCONN288_H44441003(CHIPS)':
 'S2_N_C'<0>: CDS_PINID='S2_N_C(0)';
NET_NAME
'M_A_CS_N<7>'
 '@BASEBOARD_FAB2_LIB.BASEBOARD_FAB2(SCH_1):M_A_CS_N'<7>:
 C_SIGNAL='@baseboard_fab2_lib.baseboard_fab2(sch_1):m_a_cs_n(7)';
NODE_NAME     U5D1 K45
 '@BASEBOARD_FAB2_LIB.BASEBOARD_FAB2(SCH_1):PAGE23_I172@CHPSET_LIB.SKX_EXT_B(CHIPS)':
 'DDR0_CS_N'<7>: CDS_PINID='DDR0_CS_N(7)';
NODE_NAME     J6T1 237
 '@BASEBOARD_FAB2_LIB.BASEBOARD_FAB2(SCH_1):PAGE44_I13@MSTR_SCONN.SCONN288_H44441003(CHIPS)':
 'S3_N_C'<1>: CDS_PINID='S3_N_C(1)';
NET_NAME
'M_A_DQ<0>'
 '@BASEBOARD_FAB2_LIB.BASEBOARD_FAB2(SCH_1):M_A_DQ'<0>:
 C_SIGNAL='@baseboard_fab2_lib.baseboard_fab2(sch_1):m_a_dq(0)';
NODE_NAME     U5D1 AN86
 '@BASEBOARD_FAB2_LIB.BASEBOARD_FAB2(SCH_1):PAGE23_I172@CHPSET_LIB.SKX_EXT_B(CHIPS)':
 'DDR0_DQ'<0>: CDS_PINID='DDR0_DQ(0)';
NODE_NAME     J4G1 150
 '@BASEBOARD_FAB2_LIB.BASEBOARD_FAB2(SCH_1):PAGE43_I1@MSTR_SCONN.SCONN288_H44441004(CHIPS)':
 'DQ'<1>: CDS_PINID='DQ(1)';
NODE_NAME     J6T1 5
 '@BASEBOARD_FAB2_LIB.BASEBOARD_FAB2(SCH_1):PAGE44_I13@MSTR_SCONN.SCONN288_H44441003(CHIPS)':
 'DQ'<0>: CDS_PINID='DQ(0)';
NET_NAME
'M_A_DQ<10>'
 '@BASEBOARD_FAB2_LIB.BASEBOARD_FAB2(SCH_1):M_A_DQ'<10>:
 C_SIGNAL='@baseboard_fab2_lib.baseboard_fab2(sch_1):m_a_dq(10)';
NODE_NAME     U5D1 L86
 '@BASEBOARD_FAB2_LIB.BASEBOARD_FAB2(SCH_1):PAGE23_I172@CHPSET_LIB.SKX_EXT_B(CHIPS)':
 'DDR0_DQ'<10>: CDS_PINID='DDR0_DQ(10)';
NODE_NAME     J4G1 168
 '@BASEBOARD_FAB2_LIB.BASEBOARD_FAB2(SCH_1):PAGE43_I1@MSTR_SCONN.SCONN288_H44441004(CHIPS)':
 'DQ'<11>: CDS_PINID='DQ(11)';
NODE_NAME     J6T1 23
 '@BASEBOARD_FAB2_LIB.BASEBOARD_FAB2(SCH_1):PAGE44_I13@MSTR_SCONN.SCONN288_H44441003(CHIPS)':
 'DQ'<10>: CDS_PINID='DQ(10)';
NET_NAME
'M_A_DQ<11>'
 '@BASEBOARD_FAB2_LIB.BASEBOARD_FAB2(SCH_1):M_A_DQ'<11>:
 C_SIGNAL='@baseboard_fab2_lib.baseboard_fab2(sch_1):m_a_dq(11)';
NODE_NAME     U5D1 L84
 '@BASEBOARD_FAB2_LIB.BASEBOARD_FAB2(SCH_1):PAGE23_I172@CHPSET_LIB.SKX_EXT_B(CHIPS)':
 'DDR0_DQ'<11>: CDS_PINID='DDR0_DQ(11)';
NODE_NAME     J4G1 23
 '@BASEBOARD_FAB2_LIB.BASEBOARD_FAB2(SCH_1):PAGE43_I1@MSTR_SCONN.SCONN288_H44441004(CHIPS)':
 'DQ'<10>: CDS_PINID='DQ(10)';
NODE_NAME     J6T1 168
 '@BASEBOARD_FAB2_LIB.BASEBOARD_FAB2(SCH_1):PAGE44_I13@MSTR_SCONN.SCONN288_H44441003(CHIPS)':
 'DQ'<11>: CDS_PINID='DQ(11)';
NET_NAME
'M_A_DQ<12>'
 '@BASEBOARD_FAB2_LIB.BASEBOARD_FAB2(SCH_1):M_A_DQ'<12>:
 C_SIGNAL='@baseboard_fab2_lib.baseboard_fab2(sch_1):m_a_dq(12)';
NODE_NAME     U5D1 AA86
 '@BASEBOARD_FAB2_LIB.BASEBOARD_FAB2(SCH_1):PAGE23_I172@CHPSET_LIB.SKX_EXT_B(CHIPS)':
 'DDR0_DQ'<12>: CDS_PINID='DDR0_DQ(12)';
NODE_NAME     J4G1 159
 '@BASEBOARD_FAB2_LIB.BASEBOARD_FAB2(SCH_1):PAGE43_I1@MSTR_SCONN.SCONN288_H44441004(CHIPS)':
 'DQ'<13>: CDS_PINID='DQ(13)';
NODE_NAME     J6T1 14
 '@BASEBOARD_FAB2_LIB.BASEBOARD_FAB2(SCH_1):PAGE44_I13@MSTR_SCONN.SCONN288_H44441003(CHIPS)':
 'DQ'<12>: CDS_PINID='DQ(12)';
NET_NAME
'M_A_DQ<13>'
 '@BASEBOARD_FAB2_LIB.BASEBOARD_FAB2(SCH_1):M_A_DQ'<13>:
 C_SIGNAL='@baseboard_fab2_lib.baseboard_fab2(sch_1):m_a_dq(13)';
NODE_NAME     U5D1 AA84
 '@BASEBOARD_FAB2_LIB.BASEBOARD_FAB2(SCH_1):PAGE23_I172@CHPSET_LIB.SKX_EXT_B(CHIPS)':
 'DDR0_DQ'<13>: CDS_PINID='DDR0_DQ(13)';
NODE_NAME     J4G1 14
 '@BASEBOARD_FAB2_LIB.BASEBOARD_FAB2(SCH_1):PAGE43_I1@MSTR_SCONN.SCONN288_H44441004(CHIPS)':
 'DQ'<12>: CDS_PINID='DQ(12)';
NODE_NAME     J6T1 159
 '@BASEBOARD_FAB2_LIB.BASEBOARD_FAB2(SCH_1):PAGE44_I13@MSTR_SCONN.SCONN288_H44441003(CHIPS)':
 'DQ'<13>: CDS_PINID='DQ(13)';
NET_NAME
'M_A_DQ<14>'
 '@BASEBOARD_FAB2_LIB.BASEBOARD_FAB2(SCH_1):M_A_DQ'<14>:
 C_SIGNAL='@baseboard_fab2_lib.baseboard_fab2(sch_1):m_a_dq(14)';
NODE_NAME     U5D1 N86
 '@BASEBOARD_FAB2_LIB.BASEBOARD_FAB2(SCH_1):PAGE23_I172@CHPSET_LIB.SKX_EXT_B(CHIPS)':
 'DDR0_DQ'<14>: CDS_PINID='DDR0_DQ(14)';
NODE_NAME     J4G1 166
 '@BASEBOARD_FAB2_LIB.BASEBOARD_FAB2(SCH_1):PAGE43_I1@MSTR_SCONN.SCONN288_H44441004(CHIPS)':
 'DQ'<15>: CDS_PINID='DQ(15)';
NODE_NAME     J6T1 21
 '@BASEBOARD_FAB2_LIB.BASEBOARD_FAB2(SCH_1):PAGE44_I13@MSTR_SCONN.SCONN288_H44441003(CHIPS)':
 'DQ'<14>: CDS_PINID='DQ(14)';
NET_NAME
'M_A_DQ<15>'
 '@BASEBOARD_FAB2_LIB.BASEBOARD_FAB2(SCH_1):M_A_DQ'<15>:
 C_SIGNAL='@baseboard_fab2_lib.baseboard_fab2(sch_1):m_a_dq(15)';
NODE_NAME     U5D1 N84
 '@BASEBOARD_FAB2_LIB.BASEBOARD_FAB2(SCH_1):PAGE23_I172@CHPSET_LIB.SKX_EXT_B(CHIPS)':
 'DDR0_DQ'<15>: CDS_PINID='DDR0_DQ(15)';
NODE_NAME     J4G1 21
 '@BASEBOARD_FAB2_LIB.BASEBOARD_FAB2(SCH_1):PAGE43_I1@MSTR_SCONN.SCONN288_H44441004(CHIPS)':
 'DQ'<14>: CDS_PINID='DQ(14)';
NODE_NAME     J6T1 166
 '@BASEBOARD_FAB2_LIB.BASEBOARD_FAB2(SCH_1):PAGE44_I13@MSTR_SCONN.SCONN288_H44441003(CHIPS)':
 'DQ'<15>: CDS_PINID='DQ(15)';
NET_NAME
'M_A_DQ<16>'
 '@BASEBOARD_FAB2_LIB.BASEBOARD_FAB2(SCH_1):M_A_DQ'<16>:
 C_SIGNAL='@baseboard_fab2_lib.baseboard_fab2(sch_1):m_a_dq(16)';
NODE_NAME     U5D1 V81
 '@BASEBOARD_FAB2_LIB.BASEBOARD_FAB2(SCH_1):PAGE23_I172@CHPSET_LIB.SKX_EXT_B(CHIPS)':
 'DDR0_DQ'<16>: CDS_PINID='DDR0_DQ(16)';
NODE_NAME     J4G1 172
 '@BASEBOARD_FAB2_LIB.BASEBOARD_FAB2(SCH_1):PAGE43_I1@MSTR_SCONN.SCONN288_H44441004(CHIPS)':
 'DQ'<17>: CDS_PINID='DQ(17)';
NODE_NAME     J6T1 27
 '@BASEBOARD_FAB2_LIB.BASEBOARD_FAB2(SCH_1):PAGE44_I13@MSTR_SCONN.SCONN288_H44441003(CHIPS)':
 'DQ'<16>: CDS_PINID='DQ(16)';
NET_NAME
'M_A_DQ<17>'
 '@BASEBOARD_FAB2_LIB.BASEBOARD_FAB2(SCH_1):M_A_DQ'<17>:
 C_SIGNAL='@baseboard_fab2_lib.baseboard_fab2(sch_1):m_a_dq(17)';
NODE_NAME     U5D1 T79
 '@BASEBOARD_FAB2_LIB.BASEBOARD_FAB2(SCH_1):PAGE23_I172@CHPSET_LIB.SKX_EXT_B(CHIPS)':
 'DDR0_DQ'<17>: CDS_PINID='DDR0_DQ(17)';
NODE_NAME     J4G1 27
 '@BASEBOARD_FAB2_LIB.BASEBOARD_FAB2(SCH_1):PAGE43_I1@MSTR_SCONN.SCONN288_H44441004(CHIPS)':
 'DQ'<16>: CDS_PINID='DQ(16)';
NODE_NAME     J6T1 172
 '@BASEBOARD_FAB2_LIB.BASEBOARD_FAB2(SCH_1):PAGE44_I13@MSTR_SCONN.SCONN288_H44441003(CHIPS)':
 'DQ'<17>: CDS_PINID='DQ(17)';
NET_NAME
'M_A_DQ<18>'
 '@BASEBOARD_FAB2_LIB.BASEBOARD_FAB2(SCH_1):M_A_DQ'<18>:
 C_SIGNAL='@baseboard_fab2_lib.baseboard_fab2(sch_1):m_a_dq(18)';
NODE_NAME     U5D1 N82
 '@BASEBOARD_FAB2_LIB.BASEBOARD_FAB2(SCH_1):PAGE23_I172@CHPSET_LIB.SKX_EXT_B(CHIPS)':
 'DDR0_DQ'<18>: CDS_PINID='DDR0_DQ(18)';
NODE_NAME     J4G1 179
 '@BASEBOARD_FAB2_LIB.BASEBOARD_FAB2(SCH_1):PAGE43_I1@MSTR_SCONN.SCONN288_H44441004(CHIPS)':
 'DQ'<19>: CDS_PINID='DQ(19)';
NODE_NAME     J6T1 34
 '@BASEBOARD_FAB2_LIB.BASEBOARD_FAB2(SCH_1):PAGE44_I13@MSTR_SCONN.SCONN288_H44441003(CHIPS)':
 'DQ'<18>: CDS_PINID='DQ(18)';
NET_NAME
'M_A_DQ<19>'
 '@BASEBOARD_FAB2_LIB.BASEBOARD_FAB2(SCH_1):M_A_DQ'<19>:
 C_SIGNAL='@baseboard_fab2_lib.baseboard_fab2(sch_1):m_a_dq(19)';
NODE_NAME     U5D1 M81
 '@BASEBOARD_FAB2_LIB.BASEBOARD_FAB2(SCH_1):PAGE23_I172@CHPSET_LIB.SKX_EXT_B(CHIPS)':
 'DDR0_DQ'<19>: CDS_PINID='DDR0_DQ(19)';
NODE_NAME     J4G1 34
 '@BASEBOARD_FAB2_LIB.BASEBOARD_FAB2(SCH_1):PAGE43_I1@MSTR_SCONN.SCONN288_H44441004(CHIPS)':
 'DQ'<18>: CDS_PINID='DQ(18)';
NODE_NAME     J6T1 179
 '@BASEBOARD_FAB2_LIB.BASEBOARD_FAB2(SCH_1):PAGE44_I13@MSTR_SCONN.SCONN288_H44441003(CHIPS)':
 'DQ'<19>: CDS_PINID='DQ(19)';
NET_NAME
'M_A_DQ<1>'
 '@BASEBOARD_FAB2_LIB.BASEBOARD_FAB2(SCH_1):M_A_DQ'<1>:
 C_SIGNAL='@baseboard_fab2_lib.baseboard_fab2(sch_1):m_a_dq(1)';
NODE_NAME     U5D1 AN84
 '@BASEBOARD_FAB2_LIB.BASEBOARD_FAB2(SCH_1):PAGE23_I172@CHPSET_LIB.SKX_EXT_B(CHIPS)':
 'DDR0_DQ'<1>: CDS_PINID='DDR0_DQ(1)';
NODE_NAME     J4G1 5
 '@BASEBOARD_FAB2_LIB.BASEBOARD_FAB2(SCH_1):PAGE43_I1@MSTR_SCONN.SCONN288_H44441004(CHIPS)':
 'DQ'<0>: CDS_PINID='DQ(0)';
NODE_NAME     J6T1 150
 '@BASEBOARD_FAB2_LIB.BASEBOARD_FAB2(SCH_1):PAGE44_I13@MSTR_SCONN.SCONN288_H44441003(CHIPS)':
 'DQ'<1>: CDS_PINID='DQ(1)';
NET_NAME
'M_A_DQ<20>'
 '@BASEBOARD_FAB2_LIB.BASEBOARD_FAB2(SCH_1):M_A_DQ'<20>:
 C_SIGNAL='@baseboard_fab2_lib.baseboard_fab2(sch_1):m_a_dq(20)';
NODE_NAME     U5D1 W80
 '@BASEBOARD_FAB2_LIB.BASEBOARD_FAB2(SCH_1):PAGE23_I172@CHPSET_LIB.SKX_EXT_B(CHIPS)':
 'DDR0_DQ'<20>: CDS_PINID='DDR0_DQ(20)';
NODE_NAME     J4G1 170
 '@BASEBOARD_FAB2_LIB.BASEBOARD_FAB2(SCH_1):PAGE43_I1@MSTR_SCONN.SCONN288_H44441004(CHIPS)':
 'DQ'<21>: CDS_PINID='DQ(21)';
NODE_NAME     J6T1 25
 '@BASEBOARD_FAB2_LIB.BASEBOARD_FAB2(SCH_1):PAGE44_I13@MSTR_SCONN.SCONN288_H44441003(CHIPS)':
 'DQ'<20>: CDS_PINID='DQ(20)';
NET_NAME
'M_A_DQ<21>'
 '@BASEBOARD_FAB2_LIB.BASEBOARD_FAB2(SCH_1):M_A_DQ'<21>:
 C_SIGNAL='@baseboard_fab2_lib.baseboard_fab2(sch_1):m_a_dq(21)';
NODE_NAME     U5D1 V79
 '@BASEBOARD_FAB2_LIB.BASEBOARD_FAB2(SCH_1):PAGE23_I172@CHPSET_LIB.SKX_EXT_B(CHIPS)':
 'DDR0_DQ'<21>: CDS_PINID='DDR0_DQ(21)';
NODE_NAME     J4G1 25
 '@BASEBOARD_FAB2_LIB.BASEBOARD_FAB2(SCH_1):PAGE43_I1@MSTR_SCONN.SCONN288_H44441004(CHIPS)':
 'DQ'<20>: CDS_PINID='DQ(20)';
NODE_NAME     J6T1 170
 '@BASEBOARD_FAB2_LIB.BASEBOARD_FAB2(SCH_1):PAGE44_I13@MSTR_SCONN.SCONN288_H44441003(CHIPS)':
 'DQ'<21>: CDS_PINID='DQ(21)';
NET_NAME
'M_A_DQ<22>'
 '@BASEBOARD_FAB2_LIB.BASEBOARD_FAB2(SCH_1):M_A_DQ'<22>:
 C_SIGNAL='@baseboard_fab2_lib.baseboard_fab2(sch_1):m_a_dq(22)';
NODE_NAME     U5D1 R82
 '@BASEBOARD_FAB2_LIB.BASEBOARD_FAB2(SCH_1):PAGE23_I172@CHPSET_LIB.SKX_EXT_B(CHIPS)':
 'DDR0_DQ'<22>: CDS_PINID='DDR0_DQ(22)';
NODE_NAME     J4G1 177
 '@BASEBOARD_FAB2_LIB.BASEBOARD_FAB2(SCH_1):PAGE43_I1@MSTR_SCONN.SCONN288_H44441004(CHIPS)':
 'DQ'<23>: CDS_PINID='DQ(23)';
NODE_NAME     J6T1 32
 '@BASEBOARD_FAB2_LIB.BASEBOARD_FAB2(SCH_1):PAGE44_I13@MSTR_SCONN.SCONN288_H44441003(CHIPS)':
 'DQ'<22>: CDS_PINID='DQ(22)';
NET_NAME
'M_A_DQ<23>'
 '@BASEBOARD_FAB2_LIB.BASEBOARD_FAB2(SCH_1):M_A_DQ'<23>:
 C_SIGNAL='@baseboard_fab2_lib.baseboard_fab2(sch_1):m_a_dq(23)';
NODE_NAME     U5D1 N80
 '@BASEBOARD_FAB2_LIB.BASEBOARD_FAB2(SCH_1):PAGE23_I172@CHPSET_LIB.SKX_EXT_B(CHIPS)':
 'DDR0_DQ'<23>: CDS_PINID='DDR0_DQ(23)';
NODE_NAME     J4G1 32
 '@BASEBOARD_FAB2_LIB.BASEBOARD_FAB2(SCH_1):PAGE43_I1@MSTR_SCONN.SCONN288_H44441004(CHIPS)':
 'DQ'<22>: CDS_PINID='DQ(22)';
NODE_NAME     J6T1 177
 '@BASEBOARD_FAB2_LIB.BASEBOARD_FAB2(SCH_1):PAGE44_I13@MSTR_SCONN.SCONN288_H44441003(CHIPS)':
 'DQ'<23>: CDS_PINID='DQ(23)';
NET_NAME
'M_A_DQ<24>'
 '@BASEBOARD_FAB2_LIB.BASEBOARD_FAB2(SCH_1):M_A_DQ'<24>:
 C_SIGNAL='@baseboard_fab2_lib.baseboard_fab2(sch_1):m_a_dq(24)';
NODE_NAME     U5D1 L76
 '@BASEBOARD_FAB2_LIB.BASEBOARD_FAB2(SCH_1):PAGE23_I172@CHPSET_LIB.SKX_EXT_B(CHIPS)':
 'DDR0_DQ'<24>: CDS_PINID='DDR0_DQ(24)';
NODE_NAME     J4G1 183
 '@BASEBOARD_FAB2_LIB.BASEBOARD_FAB2(SCH_1):PAGE43_I1@MSTR_SCONN.SCONN288_H44441004(CHIPS)':
 'DQ'<25>: CDS_PINID='DQ(25)';
NODE_NAME     J6T1 38
 '@BASEBOARD_FAB2_LIB.BASEBOARD_FAB2(SCH_1):PAGE44_I13@MSTR_SCONN.SCONN288_H44441003(CHIPS)':
 'DQ'<24>: CDS_PINID='DQ(24)';
NET_NAME
'M_A_DQ<25>'
 '@BASEBOARD_FAB2_LIB.BASEBOARD_FAB2(SCH_1):M_A_DQ'<25>:
 C_SIGNAL='@baseboard_fab2_lib.baseboard_fab2(sch_1):m_a_dq(25)';
NODE_NAME     U5D1 R76
 '@BASEBOARD_FAB2_LIB.BASEBOARD_FAB2(SCH_1):PAGE23_I172@CHPSET_LIB.SKX_EXT_B(CHIPS)':
 'DDR0_DQ'<25>: CDS_PINID='DDR0_DQ(25)';
NODE_NAME     J4G1 38
 '@BASEBOARD_FAB2_LIB.BASEBOARD_FAB2(SCH_1):PAGE43_I1@MSTR_SCONN.SCONN288_H44441004(CHIPS)':
 'DQ'<24>: CDS_PINID='DQ(24)';
NODE_NAME     J6T1 183
 '@BASEBOARD_FAB2_LIB.BASEBOARD_FAB2(SCH_1):PAGE44_I13@MSTR_SCONN.SCONN288_H44441003(CHIPS)':
 'DQ'<25>: CDS_PINID='DQ(25)';
NET_NAME
'M_A_DQ<26>'
 '@BASEBOARD_FAB2_LIB.BASEBOARD_FAB2(SCH_1):M_A_DQ'<26>:
 C_SIGNAL='@baseboard_fab2_lib.baseboard_fab2(sch_1):m_a_dq(26)';
NODE_NAME     U5D1 M73
 '@BASEBOARD_FAB2_LIB.BASEBOARD_FAB2(SCH_1):PAGE23_I172@CHPSET_LIB.SKX_EXT_B(CHIPS)':
 'DDR0_DQ'<26>: CDS_PINID='DDR0_DQ(26)';
NODE_NAME     J4G1 190
 '@BASEBOARD_FAB2_LIB.BASEBOARD_FAB2(SCH_1):PAGE43_I1@MSTR_SCONN.SCONN288_H44441004(CHIPS)':
 'DQ'<27>: CDS_PINID='DQ(27)';
NODE_NAME     J6T1 45
 '@BASEBOARD_FAB2_LIB.BASEBOARD_FAB2(SCH_1):PAGE44_I13@MSTR_SCONN.SCONN288_H44441003(CHIPS)':
 'DQ'<26>: CDS_PINID='DQ(26)';
NET_NAME
'M_A_DQ<27>'
 '@BASEBOARD_FAB2_LIB.BASEBOARD_FAB2(SCH_1):M_A_DQ'<27>:
 C_SIGNAL='@baseboard_fab2_lib.baseboard_fab2(sch_1):m_a_dq(27)';
NODE_NAME     U5D1 P73
 '@BASEBOARD_FAB2_LIB.BASEBOARD_FAB2(SCH_1):PAGE23_I172@CHPSET_LIB.SKX_EXT_B(CHIPS)':
 'DDR0_DQ'<27>: CDS_PINID='DDR0_DQ(27)';
NODE_NAME     J4G1 45
 '@BASEBOARD_FAB2_LIB.BASEBOARD_FAB2(SCH_1):PAGE43_I1@MSTR_SCONN.SCONN288_H44441004(CHIPS)':
 'DQ'<26>: CDS_PINID='DQ(26)';
NODE_NAME     J6T1 190
 '@BASEBOARD_FAB2_LIB.BASEBOARD_FAB2(SCH_1):PAGE44_I13@MSTR_SCONN.SCONN288_H44441003(CHIPS)':
 'DQ'<27>: CDS_PINID='DQ(27)';
NET_NAME
'M_A_DQ<28>'
 '@BASEBOARD_FAB2_LIB.BASEBOARD_FAB2(SCH_1):M_A_DQ'<28>:
 C_SIGNAL='@baseboard_fab2_lib.baseboard_fab2(sch_1):m_a_dq(28)';
NODE_NAME     U5D1 M77
 '@BASEBOARD_FAB2_LIB.BASEBOARD_FAB2(SCH_1):PAGE23_I172@CHPSET_LIB.SKX_EXT_B(CHIPS)':
 'DDR0_DQ'<28>: CDS_PINID='DDR0_DQ(28)';
NODE_NAME     J4G1 181
 '@BASEBOARD_FAB2_LIB.BASEBOARD_FAB2(SCH_1):PAGE43_I1@MSTR_SCONN.SCONN288_H44441004(CHIPS)':
 'DQ'<29>: CDS_PINID='DQ(29)';
NODE_NAME     J6T1 36
 '@BASEBOARD_FAB2_LIB.BASEBOARD_FAB2(SCH_1):PAGE44_I13@MSTR_SCONN.SCONN288_H44441003(CHIPS)':
 'DQ'<28>: CDS_PINID='DQ(28)';
NET_NAME
'M_A_DQ<29>'
 '@BASEBOARD_FAB2_LIB.BASEBOARD_FAB2(SCH_1):M_A_DQ'<29>:
 C_SIGNAL='@baseboard_fab2_lib.baseboard_fab2(sch_1):m_a_dq(29)';
NODE_NAME     U5D1 P77
 '@BASEBOARD_FAB2_LIB.BASEBOARD_FAB2(SCH_1):PAGE23_I172@CHPSET_LIB.SKX_EXT_B(CHIPS)':
 'DDR0_DQ'<29>: CDS_PINID='DDR0_DQ(29)';
NODE_NAME     J4G1 36
 '@BASEBOARD_FAB2_LIB.BASEBOARD_FAB2(SCH_1):PAGE43_I1@MSTR_SCONN.SCONN288_H44441004(CHIPS)':
 'DQ'<28>: CDS_PINID='DQ(28)';
NODE_NAME     J6T1 181
 '@BASEBOARD_FAB2_LIB.BASEBOARD_FAB2(SCH_1):PAGE44_I13@MSTR_SCONN.SCONN288_H44441003(CHIPS)':
 'DQ'<29>: CDS_PINID='DQ(29)';
NET_NAME
'M_A_DQ<2>'
 '@BASEBOARD_FAB2_LIB.BASEBOARD_FAB2(SCH_1):M_A_DQ'<2>:
 C_SIGNAL='@baseboard_fab2_lib.baseboard_fab2(sch_1):m_a_dq(2)';
NODE_NAME     U5D1 AE86
 '@BASEBOARD_FAB2_LIB.BASEBOARD_FAB2(SCH_1):PAGE23_I172@CHPSET_LIB.SKX_EXT_B(CHIPS)':
 'DDR0_DQ'<2>: CDS_PINID='DDR0_DQ(2)';
NODE_NAME     J4G1 157
 '@BASEBOARD_FAB2_LIB.BASEBOARD_FAB2(SCH_1):PAGE43_I1@MSTR_SCONN.SCONN288_H44441004(CHIPS)':
 'DQ'<3>: CDS_PINID='DQ(3)';
NODE_NAME     J6T1 12
 '@BASEBOARD_FAB2_LIB.BASEBOARD_FAB2(SCH_1):PAGE44_I13@MSTR_SCONN.SCONN288_H44441003(CHIPS)':
 'DQ'<2>: CDS_PINID='DQ(2)';
NET_NAME
'M_A_DQ<30>'
 '@BASEBOARD_FAB2_LIB.BASEBOARD_FAB2(SCH_1):M_A_DQ'<30>:
 C_SIGNAL='@baseboard_fab2_lib.baseboard_fab2(sch_1):m_a_dq(30)';
NODE_NAME     U5D1 L74
 '@BASEBOARD_FAB2_LIB.BASEBOARD_FAB2(SCH_1):PAGE23_I172@CHPSET_LIB.SKX_EXT_B(CHIPS)':
 'DDR0_DQ'<30>: CDS_PINID='DDR0_DQ(30)';
NODE_NAME     J4G1 188
 '@BASEBOARD_FAB2_LIB.BASEBOARD_FAB2(SCH_1):PAGE43_I1@MSTR_SCONN.SCONN288_H44441004(CHIPS)':
 'DQ'<31>: CDS_PINID='DQ(31)';
NODE_NAME     J6T1 43
 '@BASEBOARD_FAB2_LIB.BASEBOARD_FAB2(SCH_1):PAGE44_I13@MSTR_SCONN.SCONN288_H44441003(CHIPS)':
 'DQ'<30>: CDS_PINID='DQ(30)';
NET_NAME
'M_A_DQ<31>'
 '@BASEBOARD_FAB2_LIB.BASEBOARD_FAB2(SCH_1):M_A_DQ'<31>:
 C_SIGNAL='@baseboard_fab2_lib.baseboard_fab2(sch_1):m_a_dq(31)';
NODE_NAME     U5D1 R74
 '@BASEBOARD_FAB2_LIB.BASEBOARD_FAB2(SCH_1):PAGE23_I172@CHPSET_LIB.SKX_EXT_B(CHIPS)':
 'DDR0_DQ'<31>: CDS_PINID='DDR0_DQ(31)';
NODE_NAME     J4G1 43
 '@BASEBOARD_FAB2_LIB.BASEBOARD_FAB2(SCH_1):PAGE43_I1@MSTR_SCONN.SCONN288_H44441004(CHIPS)':
 'DQ'<30>: CDS_PINID='DQ(30)';
NODE_NAME     J6T1 188
 '@BASEBOARD_FAB2_LIB.BASEBOARD_FAB2(SCH_1):PAGE44_I13@MSTR_SCONN.SCONN288_H44441003(CHIPS)':
 'DQ'<31>: CDS_PINID='DQ(31)';
NET_NAME
'M_A_DQ<32>'
 '@BASEBOARD_FAB2_LIB.BASEBOARD_FAB2(SCH_1):M_A_DQ'<32>:
 C_SIGNAL='@baseboard_fab2_lib.baseboard_fab2(sch_1):m_a_dq(32)';
NODE_NAME     U5D1 C42
 '@BASEBOARD_FAB2_LIB.BASEBOARD_FAB2(SCH_1):PAGE23_I172@CHPSET_LIB.SKX_EXT_B(CHIPS)':
 'DDR0_DQ'<32>: CDS_PINID='DDR0_DQ(32)';
NODE_NAME     J4G1 242
 '@BASEBOARD_FAB2_LIB.BASEBOARD_FAB2(SCH_1):PAGE43_I1@MSTR_SCONN.SCONN288_H44441004(CHIPS)':
 'DQ'<33>: CDS_PINID='DQ(33)';
NODE_NAME     J6T1 97
 '@BASEBOARD_FAB2_LIB.BASEBOARD_FAB2(SCH_1):PAGE44_I13@MSTR_SCONN.SCONN288_H44441003(CHIPS)':
 'DQ'<32>: CDS_PINID='DQ(32)';
NET_NAME
'M_A_DQ<33>'
 '@BASEBOARD_FAB2_LIB.BASEBOARD_FAB2(SCH_1):M_A_DQ'<33>:
 C_SIGNAL='@baseboard_fab2_lib.baseboard_fab2(sch_1):m_a_dq(33)';
NODE_NAME     U5D1 B41
 '@BASEBOARD_FAB2_LIB.BASEBOARD_FAB2(SCH_1):PAGE23_I172@CHPSET_LIB.SKX_EXT_B(CHIPS)':
 'DDR0_DQ'<33>: CDS_PINID='DDR0_DQ(33)';
NODE_NAME     J4G1 97
 '@BASEBOARD_FAB2_LIB.BASEBOARD_FAB2(SCH_1):PAGE43_I1@MSTR_SCONN.SCONN288_H44441004(CHIPS)':
 'DQ'<32>: CDS_PINID='DQ(32)';
NODE_NAME     J6T1 242
 '@BASEBOARD_FAB2_LIB.BASEBOARD_FAB2(SCH_1):PAGE44_I13@MSTR_SCONN.SCONN288_H44441003(CHIPS)':
 'DQ'<33>: CDS_PINID='DQ(33)';
NET_NAME
'M_A_DQ<34>'
 '@BASEBOARD_FAB2_LIB.BASEBOARD_FAB2(SCH_1):M_A_DQ'<34>:
 C_SIGNAL='@baseboard_fab2_lib.baseboard_fab2(sch_1):m_a_dq(34)';
NODE_NAME     U5D1 C38
 '@BASEBOARD_FAB2_LIB.BASEBOARD_FAB2(SCH_1):PAGE23_I172@CHPSET_LIB.SKX_EXT_B(CHIPS)':
 'DDR0_DQ'<34>: CDS_PINID='DDR0_DQ(34)';
NODE_NAME     J4G1 249
 '@BASEBOARD_FAB2_LIB.BASEBOARD_FAB2(SCH_1):PAGE43_I1@MSTR_SCONN.SCONN288_H44441004(CHIPS)':
 'DQ'<35>: CDS_PINID='DQ(35)';
NODE_NAME     J6T1 104
 '@BASEBOARD_FAB2_LIB.BASEBOARD_FAB2(SCH_1):PAGE44_I13@MSTR_SCONN.SCONN288_H44441003(CHIPS)':
 'DQ'<34>: CDS_PINID='DQ(34)';
NET_NAME
'M_A_DQ<35>'
 '@BASEBOARD_FAB2_LIB.BASEBOARD_FAB2(SCH_1):M_A_DQ'<35>:
 C_SIGNAL='@baseboard_fab2_lib.baseboard_fab2(sch_1):m_a_dq(35)';
NODE_NAME     U5D1 E38
 '@BASEBOARD_FAB2_LIB.BASEBOARD_FAB2(SCH_1):PAGE23_I172@CHPSET_LIB.SKX_EXT_B(CHIPS)':
 'DDR0_DQ'<35>: CDS_PINID='DDR0_DQ(35)';
NODE_NAME     J4G1 104
 '@BASEBOARD_FAB2_LIB.BASEBOARD_FAB2(SCH_1):PAGE43_I1@MSTR_SCONN.SCONN288_H44441004(CHIPS)':
 'DQ'<34>: CDS_PINID='DQ(34)';
NODE_NAME     J6T1 249
 '@BASEBOARD_FAB2_LIB.BASEBOARD_FAB2(SCH_1):PAGE44_I13@MSTR_SCONN.SCONN288_H44441003(CHIPS)':
 'DQ'<35>: CDS_PINID='DQ(35)';
NET_NAME
'M_A_DQ<36>'
 '@BASEBOARD_FAB2_LIB.BASEBOARD_FAB2(SCH_1):M_A_DQ'<36>:
 C_SIGNAL='@baseboard_fab2_lib.baseboard_fab2(sch_1):m_a_dq(36)';
NODE_NAME     U5D1 E42
 '@BASEBOARD_FAB2_LIB.BASEBOARD_FAB2(SCH_1):PAGE23_I172@CHPSET_LIB.SKX_EXT_B(CHIPS)':
 'DDR0_DQ'<36>: CDS_PINID='DDR0_DQ(36)';
NODE_NAME     J4G1 240
 '@BASEBOARD_FAB2_LIB.BASEBOARD_FAB2(SCH_1):PAGE43_I1@MSTR_SCONN.SCONN288_H44441004(CHIPS)':
 'DQ'<37>: CDS_PINID='DQ(37)';
NODE_NAME     J6T1 95
 '@BASEBOARD_FAB2_LIB.BASEBOARD_FAB2(SCH_1):PAGE44_I13@MSTR_SCONN.SCONN288_H44441003(CHIPS)':
 'DQ'<36>: CDS_PINID='DQ(36)';
NET_NAME
'M_A_DQ<37>'
 '@BASEBOARD_FAB2_LIB.BASEBOARD_FAB2(SCH_1):M_A_DQ'<37>:
 C_SIGNAL='@baseboard_fab2_lib.baseboard_fab2(sch_1):m_a_dq(37)';
NODE_NAME     U5D1 F41
 '@BASEBOARD_FAB2_LIB.BASEBOARD_FAB2(SCH_1):PAGE23_I172@CHPSET_LIB.SKX_EXT_B(CHIPS)':
 'DDR0_DQ'<37>: CDS_PINID='DDR0_DQ(37)';
NODE_NAME     J4G1 95
 '@BASEBOARD_FAB2_LIB.BASEBOARD_FAB2(SCH_1):PAGE43_I1@MSTR_SCONN.SCONN288_H44441004(CHIPS)':
 'DQ'<36>: CDS_PINID='DQ(36)';
NODE_NAME     J6T1 240
 '@BASEBOARD_FAB2_LIB.BASEBOARD_FAB2(SCH_1):PAGE44_I13@MSTR_SCONN.SCONN288_H44441003(CHIPS)':
 'DQ'<37>: CDS_PINID='DQ(37)';
NET_NAME
'M_A_DQ<38>'
 '@BASEBOARD_FAB2_LIB.BASEBOARD_FAB2(SCH_1):M_A_DQ'<38>:
 C_SIGNAL='@baseboard_fab2_lib.baseboard_fab2(sch_1):m_a_dq(38)';
NODE_NAME     U5D1 B39
 '@BASEBOARD_FAB2_LIB.BASEBOARD_FAB2(SCH_1):PAGE23_I172@CHPSET_LIB.SKX_EXT_B(CHIPS)':
 'DDR0_DQ'<38>: CDS_PINID='DDR0_DQ(38)';
NODE_NAME     J4G1 247
 '@BASEBOARD_FAB2_LIB.BASEBOARD_FAB2(SCH_1):PAGE43_I1@MSTR_SCONN.SCONN288_H44441004(CHIPS)':
 'DQ'<39>: CDS_PINID='DQ(39)';
NODE_NAME     J6T1 102
 '@BASEBOARD_FAB2_LIB.BASEBOARD_FAB2(SCH_1):PAGE44_I13@MSTR_SCONN.SCONN288_H44441003(CHIPS)':
 'DQ'<38>: CDS_PINID='DQ(38)';
NET_NAME
'M_A_DQ<39>'
 '@BASEBOARD_FAB2_LIB.BASEBOARD_FAB2(SCH_1):M_A_DQ'<39>:
 C_SIGNAL='@baseboard_fab2_lib.baseboard_fab2(sch_1):m_a_dq(39)';
NODE_NAME     U5D1 F39
 '@BASEBOARD_FAB2_LIB.BASEBOARD_FAB2(SCH_1):PAGE23_I172@CHPSET_LIB.SKX_EXT_B(CHIPS)':
 'DDR0_DQ'<39>: CDS_PINID='DDR0_DQ(39)';
NODE_NAME     J4G1 102
 '@BASEBOARD_FAB2_LIB.BASEBOARD_FAB2(SCH_1):PAGE43_I1@MSTR_SCONN.SCONN288_H44441004(CHIPS)':
 'DQ'<38>: CDS_PINID='DQ(38)';
NODE_NAME     J6T1 247
 '@BASEBOARD_FAB2_LIB.BASEBOARD_FAB2(SCH_1):PAGE44_I13@MSTR_SCONN.SCONN288_H44441003(CHIPS)':
 'DQ'<39>: CDS_PINID='DQ(39)';
NET_NAME
'M_A_DQ<3>'
 '@BASEBOARD_FAB2_LIB.BASEBOARD_FAB2(SCH_1):M_A_DQ'<3>:
 C_SIGNAL='@baseboard_fab2_lib.baseboard_fab2(sch_1):m_a_dq(3)';
NODE_NAME     U5D1 AE84
 '@BASEBOARD_FAB2_LIB.BASEBOARD_FAB2(SCH_1):PAGE23_I172@CHPSET_LIB.SKX_EXT_B(CHIPS)':
 'DDR0_DQ'<3>: CDS_PINID='DDR0_DQ(3)';
NODE_NAME     J4G1 12
 '@BASEBOARD_FAB2_LIB.BASEBOARD_FAB2(SCH_1):PAGE43_I1@MSTR_SCONN.SCONN288_H44441004(CHIPS)':
 'DQ'<2>: CDS_PINID='DQ(2)';
NODE_NAME     J6T1 157
 '@BASEBOARD_FAB2_LIB.BASEBOARD_FAB2(SCH_1):PAGE44_I13@MSTR_SCONN.SCONN288_H44441003(CHIPS)':
 'DQ'<3>: CDS_PINID='DQ(3)';
NET_NAME
'M_A_DQ<40>'
 '@BASEBOARD_FAB2_LIB.BASEBOARD_FAB2(SCH_1):M_A_DQ'<40>:
 C_SIGNAL='@baseboard_fab2_lib.baseboard_fab2(sch_1):m_a_dq(40)';
NODE_NAME     U5D1 K37
 '@BASEBOARD_FAB2_LIB.BASEBOARD_FAB2(SCH_1):PAGE23_I172@CHPSET_LIB.SKX_EXT_B(CHIPS)':
 'DDR0_DQ'<40>: CDS_PINID='DDR0_DQ(40)';
NODE_NAME     J4G1 253
 '@BASEBOARD_FAB2_LIB.BASEBOARD_FAB2(SCH_1):PAGE43_I1@MSTR_SCONN.SCONN288_H44441004(CHIPS)':
 'DQ'<41>: CDS_PINID='DQ(41)';
NODE_NAME     J6T1 108
 '@BASEBOARD_FAB2_LIB.BASEBOARD_FAB2(SCH_1):PAGE44_I13@MSTR_SCONN.SCONN288_H44441003(CHIPS)':
 'DQ'<40>: CDS_PINID='DQ(40)';
NET_NAME
'M_A_DQ<41>'
 '@BASEBOARD_FAB2_LIB.BASEBOARD_FAB2(SCH_1):M_A_DQ'<41>:
 C_SIGNAL='@baseboard_fab2_lib.baseboard_fab2(sch_1):m_a_dq(41)';
NODE_NAME     U5D1 P37
 '@BASEBOARD_FAB2_LIB.BASEBOARD_FAB2(SCH_1):PAGE23_I172@CHPSET_LIB.SKX_EXT_B(CHIPS)':
 'DDR0_DQ'<41>: CDS_PINID='DDR0_DQ(41)';
NODE_NAME     J4G1 108
 '@BASEBOARD_FAB2_LIB.BASEBOARD_FAB2(SCH_1):PAGE43_I1@MSTR_SCONN.SCONN288_H44441004(CHIPS)':
 'DQ'<40>: CDS_PINID='DQ(40)';
NODE_NAME     J6T1 253
 '@BASEBOARD_FAB2_LIB.BASEBOARD_FAB2(SCH_1):PAGE44_I13@MSTR_SCONN.SCONN288_H44441003(CHIPS)':
 'DQ'<41>: CDS_PINID='DQ(41)';
NET_NAME
'M_A_DQ<42>'
 '@BASEBOARD_FAB2_LIB.BASEBOARD_FAB2(SCH_1):M_A_DQ'<42>:
 C_SIGNAL='@baseboard_fab2_lib.baseboard_fab2(sch_1):m_a_dq(42)';
NODE_NAME     U5D1 L34
 '@BASEBOARD_FAB2_LIB.BASEBOARD_FAB2(SCH_1):PAGE23_I172@CHPSET_LIB.SKX_EXT_B(CHIPS)':
 'DDR0_DQ'<42>: CDS_PINID='DDR0_DQ(42)';
NODE_NAME     J4G1 260
 '@BASEBOARD_FAB2_LIB.BASEBOARD_FAB2(SCH_1):PAGE43_I1@MSTR_SCONN.SCONN288_H44441004(CHIPS)':
 'DQ'<43>: CDS_PINID='DQ(43)';
NODE_NAME     J6T1 115
 '@BASEBOARD_FAB2_LIB.BASEBOARD_FAB2(SCH_1):PAGE44_I13@MSTR_SCONN.SCONN288_H44441003(CHIPS)':
 'DQ'<42>: CDS_PINID='DQ(42)';
NET_NAME
'M_A_DQ<43>'
 '@BASEBOARD_FAB2_LIB.BASEBOARD_FAB2(SCH_1):M_A_DQ'<43>:
 C_SIGNAL='@baseboard_fab2_lib.baseboard_fab2(sch_1):m_a_dq(43)';
NODE_NAME     U5D1 N34
 '@BASEBOARD_FAB2_LIB.BASEBOARD_FAB2(SCH_1):PAGE23_I172@CHPSET_LIB.SKX_EXT_B(CHIPS)':
 'DDR0_DQ'<43>: CDS_PINID='DDR0_DQ(43)';
NODE_NAME     J4G1 115
 '@BASEBOARD_FAB2_LIB.BASEBOARD_FAB2(SCH_1):PAGE43_I1@MSTR_SCONN.SCONN288_H44441004(CHIPS)':
 'DQ'<42>: CDS_PINID='DQ(42)';
NODE_NAME     J6T1 260
 '@BASEBOARD_FAB2_LIB.BASEBOARD_FAB2(SCH_1):PAGE44_I13@MSTR_SCONN.SCONN288_H44441003(CHIPS)':
 'DQ'<43>: CDS_PINID='DQ(43)';
NET_NAME
'M_A_DQ<44>'
 '@BASEBOARD_FAB2_LIB.BASEBOARD_FAB2(SCH_1):M_A_DQ'<44>:
 C_SIGNAL='@baseboard_fab2_lib.baseboard_fab2(sch_1):m_a_dq(44)';
NODE_NAME     U5D1 L38
 '@BASEBOARD_FAB2_LIB.BASEBOARD_FAB2(SCH_1):PAGE23_I172@CHPSET_LIB.SKX_EXT_B(CHIPS)':
 'DDR0_DQ'<44>: CDS_PINID='DDR0_DQ(44)';
NODE_NAME     J4G1 251
 '@BASEBOARD_FAB2_LIB.BASEBOARD_FAB2(SCH_1):PAGE43_I1@MSTR_SCONN.SCONN288_H44441004(CHIPS)':
 'DQ'<45>: CDS_PINID='DQ(45)';
NODE_NAME     J6T1 106
 '@BASEBOARD_FAB2_LIB.BASEBOARD_FAB2(SCH_1):PAGE44_I13@MSTR_SCONN.SCONN288_H44441003(CHIPS)':
 'DQ'<44>: CDS_PINID='DQ(44)';
NET_NAME
'M_A_DQ<45>'
 '@BASEBOARD_FAB2_LIB.BASEBOARD_FAB2(SCH_1):M_A_DQ'<45>:
 C_SIGNAL='@baseboard_fab2_lib.baseboard_fab2(sch_1):m_a_dq(45)';
NODE_NAME     U5D1 N38
 '@BASEBOARD_FAB2_LIB.BASEBOARD_FAB2(SCH_1):PAGE23_I172@CHPSET_LIB.SKX_EXT_B(CHIPS)':
 'DDR0_DQ'<45>: CDS_PINID='DDR0_DQ(45)';
NODE_NAME     J4G1 106
 '@BASEBOARD_FAB2_LIB.BASEBOARD_FAB2(SCH_1):PAGE43_I1@MSTR_SCONN.SCONN288_H44441004(CHIPS)':
 'DQ'<44>: CDS_PINID='DQ(44)';
NODE_NAME     J6T1 251
 '@BASEBOARD_FAB2_LIB.BASEBOARD_FAB2(SCH_1):PAGE44_I13@MSTR_SCONN.SCONN288_H44441003(CHIPS)':
 'DQ'<45>: CDS_PINID='DQ(45)';
NET_NAME
'M_A_DQ<46>'
 '@BASEBOARD_FAB2_LIB.BASEBOARD_FAB2(SCH_1):M_A_DQ'<46>:
 C_SIGNAL='@baseboard_fab2_lib.baseboard_fab2(sch_1):m_a_dq(46)';
NODE_NAME     U5D1 K35
 '@BASEBOARD_FAB2_LIB.BASEBOARD_FAB2(SCH_1):PAGE23_I172@CHPSET_LIB.SKX_EXT_B(CHIPS)':
 'DDR0_DQ'<46>: CDS_PINID='DDR0_DQ(46)';
NODE_NAME     J4G1 258
 '@BASEBOARD_FAB2_LIB.BASEBOARD_FAB2(SCH_1):PAGE43_I1@MSTR_SCONN.SCONN288_H44441004(CHIPS)':
 'DQ'<47>: CDS_PINID='DQ(47)';
NODE_NAME     J6T1 113
 '@BASEBOARD_FAB2_LIB.BASEBOARD_FAB2(SCH_1):PAGE44_I13@MSTR_SCONN.SCONN288_H44441003(CHIPS)':
 'DQ'<46>: CDS_PINID='DQ(46)';
NET_NAME
'M_A_DQ<47>'
 '@BASEBOARD_FAB2_LIB.BASEBOARD_FAB2(SCH_1):M_A_DQ'<47>:
 C_SIGNAL='@baseboard_fab2_lib.baseboard_fab2(sch_1):m_a_dq(47)';
NODE_NAME     U5D1 P35
 '@BASEBOARD_FAB2_LIB.BASEBOARD_FAB2(SCH_1):PAGE23_I172@CHPSET_LIB.SKX_EXT_B(CHIPS)':
 'DDR0_DQ'<47>: CDS_PINID='DDR0_DQ(47)';
NODE_NAME     J4G1 113
 '@BASEBOARD_FAB2_LIB.BASEBOARD_FAB2(SCH_1):PAGE43_I1@MSTR_SCONN.SCONN288_H44441004(CHIPS)':
 'DQ'<46>: CDS_PINID='DQ(46)';
NODE_NAME     J6T1 258
 '@BASEBOARD_FAB2_LIB.BASEBOARD_FAB2(SCH_1):PAGE44_I13@MSTR_SCONN.SCONN288_H44441003(CHIPS)':
 'DQ'<47>: CDS_PINID='DQ(47)';
NET_NAME
'M_A_DQ<48>'
 '@BASEBOARD_FAB2_LIB.BASEBOARD_FAB2(SCH_1):M_A_DQ'<48>:
 C_SIGNAL='@baseboard_fab2_lib.baseboard_fab2(sch_1):m_a_dq(48)';
NODE_NAME     U5D1 K31
 '@BASEBOARD_FAB2_LIB.BASEBOARD_FAB2(SCH_1):PAGE23_I172@CHPSET_LIB.SKX_EXT_B(CHIPS)':
 'DDR0_DQ'<48>: CDS_PINID='DDR0_DQ(48)';
NODE_NAME     J4G1 264
 '@BASEBOARD_FAB2_LIB.BASEBOARD_FAB2(SCH_1):PAGE43_I1@MSTR_SCONN.SCONN288_H44441004(CHIPS)':
 'DQ'<49>: CDS_PINID='DQ(49)';
NODE_NAME     J6T1 119
 '@BASEBOARD_FAB2_LIB.BASEBOARD_FAB2(SCH_1):PAGE44_I13@MSTR_SCONN.SCONN288_H44441003(CHIPS)':
 'DQ'<48>: CDS_PINID='DQ(48)';
NET_NAME
'M_A_DQ<49>'
 '@BASEBOARD_FAB2_LIB.BASEBOARD_FAB2(SCH_1):M_A_DQ'<49>:
 C_SIGNAL='@baseboard_fab2_lib.baseboard_fab2(sch_1):m_a_dq(49)';
NODE_NAME     U5D1 P31
 '@BASEBOARD_FAB2_LIB.BASEBOARD_FAB2(SCH_1):PAGE23_I172@CHPSET_LIB.SKX_EXT_B(CHIPS)':
 'DDR0_DQ'<49>: CDS_PINID='DDR0_DQ(49)';
NODE_NAME     J4G1 119
 '@BASEBOARD_FAB2_LIB.BASEBOARD_FAB2(SCH_1):PAGE43_I1@MSTR_SCONN.SCONN288_H44441004(CHIPS)':
 'DQ'<48>: CDS_PINID='DQ(48)';
NODE_NAME     J6T1 264
 '@BASEBOARD_FAB2_LIB.BASEBOARD_FAB2(SCH_1):PAGE44_I13@MSTR_SCONN.SCONN288_H44441003(CHIPS)':
 'DQ'<49>: CDS_PINID='DQ(49)';
NET_NAME
'M_A_DQ<4>'
 '@BASEBOARD_FAB2_LIB.BASEBOARD_FAB2(SCH_1):M_A_DQ'<4>:
 C_SIGNAL='@baseboard_fab2_lib.baseboard_fab2(sch_1):m_a_dq(4)';
NODE_NAME     U5D1 AR86
 '@BASEBOARD_FAB2_LIB.BASEBOARD_FAB2(SCH_1):PAGE23_I172@CHPSET_LIB.SKX_EXT_B(CHIPS)':
 'DDR0_DQ'<4>: CDS_PINID='DDR0_DQ(4)';
NODE_NAME     J4G1 148
 '@BASEBOARD_FAB2_LIB.BASEBOARD_FAB2(SCH_1):PAGE43_I1@MSTR_SCONN.SCONN288_H44441004(CHIPS)':
 'DQ'<5>: CDS_PINID='DQ(5)';
NODE_NAME     J6T1 3
 '@BASEBOARD_FAB2_LIB.BASEBOARD_FAB2(SCH_1):PAGE44_I13@MSTR_SCONN.SCONN288_H44441003(CHIPS)':
 'DQ'<4>: CDS_PINID='DQ(4)';
NET_NAME
'M_A_DQ<50>'
 '@BASEBOARD_FAB2_LIB.BASEBOARD_FAB2(SCH_1):M_A_DQ'<50>:
 C_SIGNAL='@baseboard_fab2_lib.baseboard_fab2(sch_1):m_a_dq(50)';
NODE_NAME     U5D1 L28
 '@BASEBOARD_FAB2_LIB.BASEBOARD_FAB2(SCH_1):PAGE23_I172@CHPSET_LIB.SKX_EXT_B(CHIPS)':
 'DDR0_DQ'<50>: CDS_PINID='DDR0_DQ(50)';
NODE_NAME     J4G1 271
 '@BASEBOARD_FAB2_LIB.BASEBOARD_FAB2(SCH_1):PAGE43_I1@MSTR_SCONN.SCONN288_H44441004(CHIPS)':
 'DQ'<51>: CDS_PINID='DQ(51)';
NODE_NAME     J6T1 126
 '@BASEBOARD_FAB2_LIB.BASEBOARD_FAB2(SCH_1):PAGE44_I13@MSTR_SCONN.SCONN288_H44441003(CHIPS)':
 'DQ'<50>: CDS_PINID='DQ(50)';
NET_NAME
'M_A_DQ<51>'
 '@BASEBOARD_FAB2_LIB.BASEBOARD_FAB2(SCH_1):M_A_DQ'<51>:
 C_SIGNAL='@baseboard_fab2_lib.baseboard_fab2(sch_1):m_a_dq(51)';
NODE_NAME     U5D1 N28
 '@BASEBOARD_FAB2_LIB.BASEBOARD_FAB2(SCH_1):PAGE23_I172@CHPSET_LIB.SKX_EXT_B(CHIPS)':
 'DDR0_DQ'<51>: CDS_PINID='DDR0_DQ(51)';
NODE_NAME     J4G1 126
 '@BASEBOARD_FAB2_LIB.BASEBOARD_FAB2(SCH_1):PAGE43_I1@MSTR_SCONN.SCONN288_H44441004(CHIPS)':
 'DQ'<50>: CDS_PINID='DQ(50)';
NODE_NAME     J6T1 271
 '@BASEBOARD_FAB2_LIB.BASEBOARD_FAB2(SCH_1):PAGE44_I13@MSTR_SCONN.SCONN288_H44441003(CHIPS)':
 'DQ'<51>: CDS_PINID='DQ(51)';
NET_NAME
'M_A_DQ<52>'
 '@BASEBOARD_FAB2_LIB.BASEBOARD_FAB2(SCH_1):M_A_DQ'<52>:
 C_SIGNAL='@baseboard_fab2_lib.baseboard_fab2(sch_1):m_a_dq(52)';
NODE_NAME     U5D1 L32
 '@BASEBOARD_FAB2_LIB.BASEBOARD_FAB2(SCH_1):PAGE23_I172@CHPSET_LIB.SKX_EXT_B(CHIPS)':
 'DDR0_DQ'<52>: CDS_PINID='DDR0_DQ(52)';
NODE_NAME     J4G1 262
 '@BASEBOARD_FAB2_LIB.BASEBOARD_FAB2(SCH_1):PAGE43_I1@MSTR_SCONN.SCONN288_H44441004(CHIPS)':
 'DQ'<53>: CDS_PINID='DQ(53)';
NODE_NAME     J6T1 117
 '@BASEBOARD_FAB2_LIB.BASEBOARD_FAB2(SCH_1):PAGE44_I13@MSTR_SCONN.SCONN288_H44441003(CHIPS)':
 'DQ'<52>: CDS_PINID='DQ(52)';
NET_NAME
'M_A_DQ<53>'
 '@BASEBOARD_FAB2_LIB.BASEBOARD_FAB2(SCH_1):M_A_DQ'<53>:
 C_SIGNAL='@baseboard_fab2_lib.baseboard_fab2(sch_1):m_a_dq(53)';
NODE_NAME     U5D1 N32
 '@BASEBOARD_FAB2_LIB.BASEBOARD_FAB2(SCH_1):PAGE23_I172@CHPSET_LIB.SKX_EXT_B(CHIPS)':
 'DDR0_DQ'<53>: CDS_PINID='DDR0_DQ(53)';
NODE_NAME     J4G1 117
 '@BASEBOARD_FAB2_LIB.BASEBOARD_FAB2(SCH_1):PAGE43_I1@MSTR_SCONN.SCONN288_H44441004(CHIPS)':
 'DQ'<52>: CDS_PINID='DQ(52)';
NODE_NAME     J6T1 262
 '@BASEBOARD_FAB2_LIB.BASEBOARD_FAB2(SCH_1):PAGE44_I13@MSTR_SCONN.SCONN288_H44441003(CHIPS)':
 'DQ'<53>: CDS_PINID='DQ(53)';
NET_NAME
'M_A_DQ<54>'
 '@BASEBOARD_FAB2_LIB.BASEBOARD_FAB2(SCH_1):M_A_DQ'<54>:
 C_SIGNAL='@baseboard_fab2_lib.baseboard_fab2(sch_1):m_a_dq(54)';
NODE_NAME     U5D1 K29
 '@BASEBOARD_FAB2_LIB.BASEBOARD_FAB2(SCH_1):PAGE23_I172@CHPSET_LIB.SKX_EXT_B(CHIPS)':
 'DDR0_DQ'<54>: CDS_PINID='DDR0_DQ(54)';
NODE_NAME     J4G1 269
 '@BASEBOARD_FAB2_LIB.BASEBOARD_FAB2(SCH_1):PAGE43_I1@MSTR_SCONN.SCONN288_H44441004(CHIPS)':
 'DQ'<55>: CDS_PINID='DQ(55)';
NODE_NAME     J6T1 124
 '@BASEBOARD_FAB2_LIB.BASEBOARD_FAB2(SCH_1):PAGE44_I13@MSTR_SCONN.SCONN288_H44441003(CHIPS)':
 'DQ'<54>: CDS_PINID='DQ(54)';
NET_NAME
'M_A_DQ<55>'
 '@BASEBOARD_FAB2_LIB.BASEBOARD_FAB2(SCH_1):M_A_DQ'<55>:
 C_SIGNAL='@baseboard_fab2_lib.baseboard_fab2(sch_1):m_a_dq(55)';
NODE_NAME     U5D1 P29
 '@BASEBOARD_FAB2_LIB.BASEBOARD_FAB2(SCH_1):PAGE23_I172@CHPSET_LIB.SKX_EXT_B(CHIPS)':
 'DDR0_DQ'<55>: CDS_PINID='DDR0_DQ(55)';
NODE_NAME     J4G1 124
 '@BASEBOARD_FAB2_LIB.BASEBOARD_FAB2(SCH_1):PAGE43_I1@MSTR_SCONN.SCONN288_H44441004(CHIPS)':
 'DQ'<54>: CDS_PINID='DQ(54)';
NODE_NAME     J6T1 269
 '@BASEBOARD_FAB2_LIB.BASEBOARD_FAB2(SCH_1):PAGE44_I13@MSTR_SCONN.SCONN288_H44441003(CHIPS)':
 'DQ'<55>: CDS_PINID='DQ(55)';
NET_NAME
'M_A_DQ<56>'
 '@BASEBOARD_FAB2_LIB.BASEBOARD_FAB2(SCH_1):M_A_DQ'<56>:
 C_SIGNAL='@baseboard_fab2_lib.baseboard_fab2(sch_1):m_a_dq(56)';
NODE_NAME     U5D1 K25
 '@BASEBOARD_FAB2_LIB.BASEBOARD_FAB2(SCH_1):PAGE23_I172@CHPSET_LIB.SKX_EXT_B(CHIPS)':
 'DDR0_DQ'<56>: CDS_PINID='DDR0_DQ(56)';
NODE_NAME     J4G1 275
 '@BASEBOARD_FAB2_LIB.BASEBOARD_FAB2(SCH_1):PAGE43_I1@MSTR_SCONN.SCONN288_H44441004(CHIPS)':
 'DQ'<57>: CDS_PINID='DQ(57)';
NODE_NAME     J6T1 130
 '@BASEBOARD_FAB2_LIB.BASEBOARD_FAB2(SCH_1):PAGE44_I13@MSTR_SCONN.SCONN288_H44441003(CHIPS)':
 'DQ'<56>: CDS_PINID='DQ(56)';
NET_NAME
'M_A_DQ<57>'
 '@BASEBOARD_FAB2_LIB.BASEBOARD_FAB2(SCH_1):M_A_DQ'<57>:
 C_SIGNAL='@baseboard_fab2_lib.baseboard_fab2(sch_1):m_a_dq(57)';
NODE_NAME     U5D1 P25
 '@BASEBOARD_FAB2_LIB.BASEBOARD_FAB2(SCH_1):PAGE23_I172@CHPSET_LIB.SKX_EXT_B(CHIPS)':
 'DDR0_DQ'<57>: CDS_PINID='DDR0_DQ(57)';
NODE_NAME     J4G1 130
 '@BASEBOARD_FAB2_LIB.BASEBOARD_FAB2(SCH_1):PAGE43_I1@MSTR_SCONN.SCONN288_H44441004(CHIPS)':
 'DQ'<56>: CDS_PINID='DQ(56)';
NODE_NAME     J6T1 275
 '@BASEBOARD_FAB2_LIB.BASEBOARD_FAB2(SCH_1):PAGE44_I13@MSTR_SCONN.SCONN288_H44441003(CHIPS)':
 'DQ'<57>: CDS_PINID='DQ(57)';
NET_NAME
'M_A_DQ<58>'
 '@BASEBOARD_FAB2_LIB.BASEBOARD_FAB2(SCH_1):M_A_DQ'<58>:
 C_SIGNAL='@baseboard_fab2_lib.baseboard_fab2(sch_1):m_a_dq(58)';
NODE_NAME     U5D1 P23
 '@BASEBOARD_FAB2_LIB.BASEBOARD_FAB2(SCH_1):PAGE23_I172@CHPSET_LIB.SKX_EXT_B(CHIPS)':
 'DDR0_DQ'<58>: CDS_PINID='DDR0_DQ(58)';
NODE_NAME     J4G1 282
 '@BASEBOARD_FAB2_LIB.BASEBOARD_FAB2(SCH_1):PAGE43_I1@MSTR_SCONN.SCONN288_H44441004(CHIPS)':
 'DQ'<59>: CDS_PINID='DQ(59)';
NODE_NAME     J6T1 137
 '@BASEBOARD_FAB2_LIB.BASEBOARD_FAB2(SCH_1):PAGE44_I13@MSTR_SCONN.SCONN288_H44441003(CHIPS)':
 'DQ'<58>: CDS_PINID='DQ(58)';
NET_NAME
'M_A_DQ<59>'
 '@BASEBOARD_FAB2_LIB.BASEBOARD_FAB2(SCH_1):M_A_DQ'<59>:
 C_SIGNAL='@baseboard_fab2_lib.baseboard_fab2(sch_1):m_a_dq(59)';
NODE_NAME     U5D1 T23
 '@BASEBOARD_FAB2_LIB.BASEBOARD_FAB2(SCH_1):PAGE23_I172@CHPSET_LIB.SKX_EXT_B(CHIPS)':
 'DDR0_DQ'<59>: CDS_PINID='DDR0_DQ(59)';
NODE_NAME     J4G1 137
 '@BASEBOARD_FAB2_LIB.BASEBOARD_FAB2(SCH_1):PAGE43_I1@MSTR_SCONN.SCONN288_H44441004(CHIPS)':
 'DQ'<58>: CDS_PINID='DQ(58)';
NODE_NAME     J6T1 282
 '@BASEBOARD_FAB2_LIB.BASEBOARD_FAB2(SCH_1):PAGE44_I13@MSTR_SCONN.SCONN288_H44441003(CHIPS)':
 'DQ'<59>: CDS_PINID='DQ(59)';
NET_NAME
'M_A_DQ<5>'
 '@BASEBOARD_FAB2_LIB.BASEBOARD_FAB2(SCH_1):M_A_DQ'<5>:
 C_SIGNAL='@baseboard_fab2_lib.baseboard_fab2(sch_1):m_a_dq(5)';
NODE_NAME     U5D1 AR84
 '@BASEBOARD_FAB2_LIB.BASEBOARD_FAB2(SCH_1):PAGE23_I172@CHPSET_LIB.SKX_EXT_B(CHIPS)':
 'DDR0_DQ'<5>: CDS_PINID='DDR0_DQ(5)';
NODE_NAME     J4G1 3
 '@BASEBOARD_FAB2_LIB.BASEBOARD_FAB2(SCH_1):PAGE43_I1@MSTR_SCONN.SCONN288_H44441004(CHIPS)':
 'DQ'<4>: CDS_PINID='DQ(4)';
NODE_NAME     J6T1 148
 '@BASEBOARD_FAB2_LIB.BASEBOARD_FAB2(SCH_1):PAGE44_I13@MSTR_SCONN.SCONN288_H44441003(CHIPS)':
 'DQ'<5>: CDS_PINID='DQ(5)';
NET_NAME
'M_A_DQ<60>'
 '@BASEBOARD_FAB2_LIB.BASEBOARD_FAB2(SCH_1):M_A_DQ'<60>:
 C_SIGNAL='@baseboard_fab2_lib.baseboard_fab2(sch_1):m_a_dq(60)';
NODE_NAME     U5D1 L26
 '@BASEBOARD_FAB2_LIB.BASEBOARD_FAB2(SCH_1):PAGE23_I172@CHPSET_LIB.SKX_EXT_B(CHIPS)':
 'DDR0_DQ'<60>: CDS_PINID='DDR0_DQ(60)';
NODE_NAME     J4G1 273
 '@BASEBOARD_FAB2_LIB.BASEBOARD_FAB2(SCH_1):PAGE43_I1@MSTR_SCONN.SCONN288_H44441004(CHIPS)':
 'DQ'<61>: CDS_PINID='DQ(61)';
NODE_NAME     J6T1 128
 '@BASEBOARD_FAB2_LIB.BASEBOARD_FAB2(SCH_1):PAGE44_I13@MSTR_SCONN.SCONN288_H44441003(CHIPS)':
 'DQ'<60>: CDS_PINID='DQ(60)';
NET_NAME
'M_A_DQ<61>'
 '@BASEBOARD_FAB2_LIB.BASEBOARD_FAB2(SCH_1):M_A_DQ'<61>:
 C_SIGNAL='@baseboard_fab2_lib.baseboard_fab2(sch_1):m_a_dq(61)';
NODE_NAME     U5D1 N26
 '@BASEBOARD_FAB2_LIB.BASEBOARD_FAB2(SCH_1):PAGE23_I172@CHPSET_LIB.SKX_EXT_B(CHIPS)':
 'DDR0_DQ'<61>: CDS_PINID='DDR0_DQ(61)';
NODE_NAME     J4G1 128
 '@BASEBOARD_FAB2_LIB.BASEBOARD_FAB2(SCH_1):PAGE43_I1@MSTR_SCONN.SCONN288_H44441004(CHIPS)':
 'DQ'<60>: CDS_PINID='DQ(60)';
NODE_NAME     J6T1 273
 '@BASEBOARD_FAB2_LIB.BASEBOARD_FAB2(SCH_1):PAGE44_I13@MSTR_SCONN.SCONN288_H44441003(CHIPS)':
 'DQ'<61>: CDS_PINID='DQ(61)';
NET_NAME
'M_A_DQ<62>'
 '@BASEBOARD_FAB2_LIB.BASEBOARD_FAB2(SCH_1):M_A_DQ'<62>:
 C_SIGNAL='@baseboard_fab2_lib.baseboard_fab2(sch_1):m_a_dq(62)';
NODE_NAME     U5D1 H23
 '@BASEBOARD_FAB2_LIB.BASEBOARD_FAB2(SCH_1):PAGE23_I172@CHPSET_LIB.SKX_EXT_B(CHIPS)':
 'DDR0_DQ'<62>: CDS_PINID='DDR0_DQ(62)';
NODE_NAME     J4G1 280
 '@BASEBOARD_FAB2_LIB.BASEBOARD_FAB2(SCH_1):PAGE43_I1@MSTR_SCONN.SCONN288_H44441004(CHIPS)':
 'DQ'<63>: CDS_PINID='DQ(63)';
NODE_NAME     J6T1 135
 '@BASEBOARD_FAB2_LIB.BASEBOARD_FAB2(SCH_1):PAGE44_I13@MSTR_SCONN.SCONN288_H44441003(CHIPS)':
 'DQ'<62>: CDS_PINID='DQ(62)';
NET_NAME
'M_A_DQ<63>'
 '@BASEBOARD_FAB2_LIB.BASEBOARD_FAB2(SCH_1):M_A_DQ'<63>:
 C_SIGNAL='@baseboard_fab2_lib.baseboard_fab2(sch_1):m_a_dq(63)';
NODE_NAME     U5D1 K23
 '@BASEBOARD_FAB2_LIB.BASEBOARD_FAB2(SCH_1):PAGE23_I172@CHPSET_LIB.SKX_EXT_B(CHIPS)':
 'DDR0_DQ'<63>: CDS_PINID='DDR0_DQ(63)';
NODE_NAME     J4G1 135
 '@BASEBOARD_FAB2_LIB.BASEBOARD_FAB2(SCH_1):PAGE43_I1@MSTR_SCONN.SCONN288_H44441004(CHIPS)':
 'DQ'<62>: CDS_PINID='DQ(62)';
NODE_NAME     J6T1 280
 '@BASEBOARD_FAB2_LIB.BASEBOARD_FAB2(SCH_1):PAGE44_I13@MSTR_SCONN.SCONN288_H44441003(CHIPS)':
 'DQ'<63>: CDS_PINID='DQ(63)';
NET_NAME
'M_A_DQ<6>'
 '@BASEBOARD_FAB2_LIB.BASEBOARD_FAB2(SCH_1):M_A_DQ'<6>:
 C_SIGNAL='@baseboard_fab2_lib.baseboard_fab2(sch_1):m_a_dq(6)';
NODE_NAME     U5D1 AG86
 '@BASEBOARD_FAB2_LIB.BASEBOARD_FAB2(SCH_1):PAGE23_I172@CHPSET_LIB.SKX_EXT_B(CHIPS)':
 'DDR0_DQ'<6>: CDS_PINID='DDR0_DQ(6)';
NODE_NAME     J4G1 155
 '@BASEBOARD_FAB2_LIB.BASEBOARD_FAB2(SCH_1):PAGE43_I1@MSTR_SCONN.SCONN288_H44441004(CHIPS)':
 'DQ'<7>: CDS_PINID='DQ(7)';
NODE_NAME     J6T1 10
 '@BASEBOARD_FAB2_LIB.BASEBOARD_FAB2(SCH_1):PAGE44_I13@MSTR_SCONN.SCONN288_H44441003(CHIPS)':
 'DQ'<6>: CDS_PINID='DQ(6)';
NET_NAME
'M_A_DQ<7>'
 '@BASEBOARD_FAB2_LIB.BASEBOARD_FAB2(SCH_1):M_A_DQ'<7>:
 C_SIGNAL='@baseboard_fab2_lib.baseboard_fab2(sch_1):m_a_dq(7)';
NODE_NAME     U5D1 AG84
 '@BASEBOARD_FAB2_LIB.BASEBOARD_FAB2(SCH_1):PAGE23_I172@CHPSET_LIB.SKX_EXT_B(CHIPS)':
 'DDR0_DQ'<7>: CDS_PINID='DDR0_DQ(7)';
NODE_NAME     J4G1 10
 '@BASEBOARD_FAB2_LIB.BASEBOARD_FAB2(SCH_1):PAGE43_I1@MSTR_SCONN.SCONN288_H44441004(CHIPS)':
 'DQ'<6>: CDS_PINID='DQ(6)';
NODE_NAME     J6T1 155
 '@BASEBOARD_FAB2_LIB.BASEBOARD_FAB2(SCH_1):PAGE44_I13@MSTR_SCONN.SCONN288_H44441003(CHIPS)':
 'DQ'<7>: CDS_PINID='DQ(7)';
NET_NAME
'M_A_DQ<8>'
 '@BASEBOARD_FAB2_LIB.BASEBOARD_FAB2(SCH_1):M_A_DQ'<8>:
 C_SIGNAL='@baseboard_fab2_lib.baseboard_fab2(sch_1):m_a_dq(8)';
NODE_NAME     U5D1 W86
 '@BASEBOARD_FAB2_LIB.BASEBOARD_FAB2(SCH_1):PAGE23_I172@CHPSET_LIB.SKX_EXT_B(CHIPS)':
 'DDR0_DQ'<8>: CDS_PINID='DDR0_DQ(8)';
NODE_NAME     J4G1 161
 '@BASEBOARD_FAB2_LIB.BASEBOARD_FAB2(SCH_1):PAGE43_I1@MSTR_SCONN.SCONN288_H44441004(CHIPS)':
 'DQ'<9>: CDS_PINID='DQ(9)';
NODE_NAME     J6T1 16
 '@BASEBOARD_FAB2_LIB.BASEBOARD_FAB2(SCH_1):PAGE44_I13@MSTR_SCONN.SCONN288_H44441003(CHIPS)':
 'DQ'<8>: CDS_PINID='DQ(8)';
NET_NAME
'M_A_DQ<9>'
 '@BASEBOARD_FAB2_LIB.BASEBOARD_FAB2(SCH_1):M_A_DQ'<9>:
 C_SIGNAL='@baseboard_fab2_lib.baseboard_fab2(sch_1):m_a_dq(9)';
NODE_NAME     U5D1 W84
 '@BASEBOARD_FAB2_LIB.BASEBOARD_FAB2(SCH_1):PAGE23_I172@CHPSET_LIB.SKX_EXT_B(CHIPS)':
 'DDR0_DQ'<9>: CDS_PINID='DDR0_DQ(9)';
NODE_NAME     J4G1 16
 '@BASEBOARD_FAB2_LIB.BASEBOARD_FAB2(SCH_1):PAGE43_I1@MSTR_SCONN.SCONN288_H44441004(CHIPS)':
 'DQ'<8>: CDS_PINID='DQ(8)';
NODE_NAME     J6T1 161
 '@BASEBOARD_FAB2_LIB.BASEBOARD_FAB2(SCH_1):PAGE44_I13@MSTR_SCONN.SCONN288_H44441003(CHIPS)':
 'DQ'<9>: CDS_PINID='DQ(9)';
NET_NAME
'M_A_DQS_DN<0>'
 '@BASEBOARD_FAB2_LIB.BASEBOARD_FAB2(SCH_1):M_A_DQS_DN'<0>:
 C_SIGNAL='@baseboard_fab2_lib.baseboard_fab2(sch_1):m_a_dqs_dn(0)';
NODE_NAME     U5D1 AJ84
 '@BASEBOARD_FAB2_LIB.BASEBOARD_FAB2(SCH_1):PAGE23_I172@CHPSET_LIB.SKX_EXT_B(CHIPS)':
 'DDR0_DQS_DN'<0>: CDS_PINID='DDR0_DQS_DN(0)';
NODE_NAME     J4G1 152
 '@BASEBOARD_FAB2_LIB.BASEBOARD_FAB2(SCH_1):PAGE43_I2@MSTR_SCONN.SCONN288_H44441004(CHIPS)':
 'DQS0N': CDS_PINID='DQS0N';
NODE_NAME     J6T1 152
 '@BASEBOARD_FAB2_LIB.BASEBOARD_FAB2(SCH_1):PAGE44_I120@MSTR_SCONN.SCONN288_H44441003(CHIPS)':
 'DQS0N': CDS_PINID='DQS0N';
NET_NAME
'M_A_DQS_DN<10>'
 '@BASEBOARD_FAB2_LIB.BASEBOARD_FAB2(SCH_1):M_A_DQS_DN'<10>:
 C_SIGNAL='@baseboard_fab2_lib.baseboard_fab2(sch_1):m_a_dqs_dn(10)';
NODE_NAME     U5D1 U84
 '@BASEBOARD_FAB2_LIB.BASEBOARD_FAB2(SCH_1):PAGE23_I172@CHPSET_LIB.SKX_EXT_B(CHIPS)':
 'DDR0_DQS_DN'<10>: CDS_PINID='DDR0_DQS_DN(10)';
NODE_NAME     J4G1 19
 '@BASEBOARD_FAB2_LIB.BASEBOARD_FAB2(SCH_1):PAGE43_I2@MSTR_SCONN.SCONN288_H44441004(CHIPS)':
 'DQS10N': CDS_PINID='DQS10N';
NODE_NAME     J6T1 19
 '@BASEBOARD_FAB2_LIB.BASEBOARD_FAB2(SCH_1):PAGE44_I120@MSTR_SCONN.SCONN288_H44441003(CHIPS)':
 'DQS10N': CDS_PINID='DQS10N';
NET_NAME
'M_A_DQS_DN<11>'
 '@BASEBOARD_FAB2_LIB.BASEBOARD_FAB2(SCH_1):M_A_DQS_DN'<11>:
 C_SIGNAL='@baseboard_fab2_lib.baseboard_fab2(sch_1):m_a_dqs_dn(11)';
NODE_NAME     U5D1 U82
 '@BASEBOARD_FAB2_LIB.BASEBOARD_FAB2(SCH_1):PAGE23_I172@CHPSET_LIB.SKX_EXT_B(CHIPS)':
 'DDR0_DQS_DN'<11>: CDS_PINID='DDR0_DQS_DN(11)';
NODE_NAME     J4G1 30
 '@BASEBOARD_FAB2_LIB.BASEBOARD_FAB2(SCH_1):PAGE43_I2@MSTR_SCONN.SCONN288_H44441004(CHIPS)':
 'DQS11N': CDS_PINID='DQS11N';
NODE_NAME     J6T1 30
 '@BASEBOARD_FAB2_LIB.BASEBOARD_FAB2(SCH_1):PAGE44_I120@MSTR_SCONN.SCONN288_H44441003(CHIPS)':
 'DQS11N': CDS_PINID='DQS11N';
NET_NAME
'M_A_DQS_DN<12>'
 '@BASEBOARD_FAB2_LIB.BASEBOARD_FAB2(SCH_1):M_A_DQS_DN'<12>:
 C_SIGNAL='@baseboard_fab2_lib.baseboard_fab2(sch_1):m_a_dqs_dn(12)';
NODE_NAME     U5D1 K75
 '@BASEBOARD_FAB2_LIB.BASEBOARD_FAB2(SCH_1):PAGE23_I172@CHPSET_LIB.SKX_EXT_B(CHIPS)':
 'DDR0_DQS_DN'<12>: CDS_PINID='DDR0_DQS_DN(12)';
NODE_NAME     J4G1 41
 '@BASEBOARD_FAB2_LIB.BASEBOARD_FAB2(SCH_1):PAGE43_I2@MSTR_SCONN.SCONN288_H44441004(CHIPS)':
 'DQS12N': CDS_PINID='DQS12N';
NODE_NAME     J6T1 41
 '@BASEBOARD_FAB2_LIB.BASEBOARD_FAB2(SCH_1):PAGE44_I120@MSTR_SCONN.SCONN288_H44441003(CHIPS)':
 'DQS12N': CDS_PINID='DQS12N';
NET_NAME
'M_A_DQS_DN<13>'
 '@BASEBOARD_FAB2_LIB.BASEBOARD_FAB2(SCH_1):M_A_DQS_DN'<13>:
 C_SIGNAL='@baseboard_fab2_lib.baseboard_fab2(sch_1):m_a_dqs_dn(13)';
NODE_NAME     U5D1 A40
 '@BASEBOARD_FAB2_LIB.BASEBOARD_FAB2(SCH_1):PAGE23_I172@CHPSET_LIB.SKX_EXT_B(CHIPS)':
 'DDR0_DQS_DN'<13>: CDS_PINID='DDR0_DQS_DN(13)';
NODE_NAME     J4G1 100
 '@BASEBOARD_FAB2_LIB.BASEBOARD_FAB2(SCH_1):PAGE43_I2@MSTR_SCONN.SCONN288_H44441004(CHIPS)':
 'DQS13N': CDS_PINID='DQS13N';
NODE_NAME     J6T1 100
 '@BASEBOARD_FAB2_LIB.BASEBOARD_FAB2(SCH_1):PAGE44_I120@MSTR_SCONN.SCONN288_H44441003(CHIPS)':
 'DQS13N': CDS_PINID='DQS13N';
NET_NAME
'M_A_DQS_DN<14>'
 '@BASEBOARD_FAB2_LIB.BASEBOARD_FAB2(SCH_1):M_A_DQS_DN'<14>:
 C_SIGNAL='@baseboard_fab2_lib.baseboard_fab2(sch_1):m_a_dqs_dn(14)';
NODE_NAME     U5D1 J36
 '@BASEBOARD_FAB2_LIB.BASEBOARD_FAB2(SCH_1):PAGE23_I172@CHPSET_LIB.SKX_EXT_B(CHIPS)':
 'DDR0_DQS_DN'<14>: CDS_PINID='DDR0_DQS_DN(14)';
NODE_NAME     J4G1 111
 '@BASEBOARD_FAB2_LIB.BASEBOARD_FAB2(SCH_1):PAGE43_I2@MSTR_SCONN.SCONN288_H44441004(CHIPS)':
 'DQS14N': CDS_PINID='DQS14N';
NODE_NAME     J6T1 111
 '@BASEBOARD_FAB2_LIB.BASEBOARD_FAB2(SCH_1):PAGE44_I120@MSTR_SCONN.SCONN288_H44441003(CHIPS)':
 'DQS14N': CDS_PINID='DQS14N';
NET_NAME
'M_A_DQS_DN<15>'
 '@BASEBOARD_FAB2_LIB.BASEBOARD_FAB2(SCH_1):M_A_DQS_DN'<15>:
 C_SIGNAL='@baseboard_fab2_lib.baseboard_fab2(sch_1):m_a_dqs_dn(15)';
NODE_NAME     U5D1 J30
 '@BASEBOARD_FAB2_LIB.BASEBOARD_FAB2(SCH_1):PAGE23_I172@CHPSET_LIB.SKX_EXT_B(CHIPS)':
 'DDR0_DQS_DN'<15>: CDS_PINID='DDR0_DQS_DN(15)';
NODE_NAME     J4G1 122
 '@BASEBOARD_FAB2_LIB.BASEBOARD_FAB2(SCH_1):PAGE43_I2@MSTR_SCONN.SCONN288_H44441004(CHIPS)':
 'DQS15N': CDS_PINID='DQS15N';
NODE_NAME     J6T1 122
 '@BASEBOARD_FAB2_LIB.BASEBOARD_FAB2(SCH_1):PAGE44_I120@MSTR_SCONN.SCONN288_H44441003(CHIPS)':
 'DQS15N': CDS_PINID='DQS15N';
NET_NAME
'M_A_DQS_DN<16>'
 '@BASEBOARD_FAB2_LIB.BASEBOARD_FAB2(SCH_1):M_A_DQS_DN'<16>:
 C_SIGNAL='@baseboard_fab2_lib.baseboard_fab2(sch_1):m_a_dqs_dn(16)';
NODE_NAME     U5D1 J24
 '@BASEBOARD_FAB2_LIB.BASEBOARD_FAB2(SCH_1):PAGE23_I172@CHPSET_LIB.SKX_EXT_B(CHIPS)':
 'DDR0_DQS_DN'<16>: CDS_PINID='DDR0_DQS_DN(16)';
NODE_NAME     J4G1 133
 '@BASEBOARD_FAB2_LIB.BASEBOARD_FAB2(SCH_1):PAGE43_I2@MSTR_SCONN.SCONN288_H44441004(CHIPS)':
 'DQS16N': CDS_PINID='DQS16N';
NODE_NAME     J6T1 133
 '@BASEBOARD_FAB2_LIB.BASEBOARD_FAB2(SCH_1):PAGE44_I120@MSTR_SCONN.SCONN288_H44441003(CHIPS)':
 'DQS16N': CDS_PINID='DQS16N';
NET_NAME
'M_A_DQS_DN<17>'
 '@BASEBOARD_FAB2_LIB.BASEBOARD_FAB2(SCH_1):M_A_DQS_DN'<17>:
 C_SIGNAL='@baseboard_fab2_lib.baseboard_fab2(sch_1):m_a_dqs_dn(17)';
NODE_NAME     U5D1 AB67
 '@BASEBOARD_FAB2_LIB.BASEBOARD_FAB2(SCH_1):PAGE23_I172@CHPSET_LIB.SKX_EXT_B(CHIPS)':
 'DDR0_DQS_DN'<17>: CDS_PINID='DDR0_DQS_DN(17)';
NODE_NAME     J4G1 52
 '@BASEBOARD_FAB2_LIB.BASEBOARD_FAB2(SCH_1):PAGE43_I2@MSTR_SCONN.SCONN288_H44441004(CHIPS)':
 'DQS17N': CDS_PINID='DQS17N';
NODE_NAME     J6T1 52
 '@BASEBOARD_FAB2_LIB.BASEBOARD_FAB2(SCH_1):PAGE44_I120@MSTR_SCONN.SCONN288_H44441003(CHIPS)':
 'DQS17N': CDS_PINID='DQS17N';
NET_NAME
'M_A_DQS_DN<1>'
 '@BASEBOARD_FAB2_LIB.BASEBOARD_FAB2(SCH_1):M_A_DQS_DN'<1>:
 C_SIGNAL='@baseboard_fab2_lib.baseboard_fab2(sch_1):m_a_dqs_dn(1)';
NODE_NAME     U5D1 R84
 '@BASEBOARD_FAB2_LIB.BASEBOARD_FAB2(SCH_1):PAGE23_I172@CHPSET_LIB.SKX_EXT_B(CHIPS)':
 'DDR0_DQS_DN'<1>: CDS_PINID='DDR0_DQS_DN(1)';
NODE_NAME     J4G1 163
 '@BASEBOARD_FAB2_LIB.BASEBOARD_FAB2(SCH_1):PAGE43_I2@MSTR_SCONN.SCONN288_H44441004(CHIPS)':
 'DQS1N': CDS_PINID='DQS1N';
NODE_NAME     J6T1 163
 '@BASEBOARD_FAB2_LIB.BASEBOARD_FAB2(SCH_1):PAGE44_I120@MSTR_SCONN.SCONN288_H44441003(CHIPS)':
 'DQS1N': CDS_PINID='DQS1N';
NET_NAME
'M_A_DQS_DN<2>'
 '@BASEBOARD_FAB2_LIB.BASEBOARD_FAB2(SCH_1):M_A_DQS_DN'<2>:
 C_SIGNAL='@baseboard_fab2_lib.baseboard_fab2(sch_1):m_a_dqs_dn(2)';
NODE_NAME     U5D1 P79
 '@BASEBOARD_FAB2_LIB.BASEBOARD_FAB2(SCH_1):PAGE23_I172@CHPSET_LIB.SKX_EXT_B(CHIPS)':
 'DDR0_DQS_DN'<2>: CDS_PINID='DDR0_DQS_DN(2)';
NODE_NAME     J4G1 174
 '@BASEBOARD_FAB2_LIB.BASEBOARD_FAB2(SCH_1):PAGE43_I2@MSTR_SCONN.SCONN288_H44441004(CHIPS)':
 'DQS2N': CDS_PINID='DQS2N';
NODE_NAME     J6T1 174
 '@BASEBOARD_FAB2_LIB.BASEBOARD_FAB2(SCH_1):PAGE44_I120@MSTR_SCONN.SCONN288_H44441003(CHIPS)':
 'DQS2N': CDS_PINID='DQS2N';
NET_NAME
'M_A_DQS_DN<3>'
 '@BASEBOARD_FAB2_LIB.BASEBOARD_FAB2(SCH_1):M_A_DQS_DN'<3>:
 C_SIGNAL='@baseboard_fab2_lib.baseboard_fab2(sch_1):m_a_dqs_dn(3)';
NODE_NAME     U5D1 T75
 '@BASEBOARD_FAB2_LIB.BASEBOARD_FAB2(SCH_1):PAGE23_I172@CHPSET_LIB.SKX_EXT_B(CHIPS)':
 'DDR0_DQS_DN'<3>: CDS_PINID='DDR0_DQS_DN(3)';
NODE_NAME     J4G1 185
 '@BASEBOARD_FAB2_LIB.BASEBOARD_FAB2(SCH_1):PAGE43_I2@MSTR_SCONN.SCONN288_H44441004(CHIPS)':
 'DQS3N': CDS_PINID='DQS3N';
NODE_NAME     J6T1 185
 '@BASEBOARD_FAB2_LIB.BASEBOARD_FAB2(SCH_1):PAGE44_I120@MSTR_SCONN.SCONN288_H44441003(CHIPS)':
 'DQS3N': CDS_PINID='DQS3N';
NET_NAME
'M_A_DQS_DN<4>'
 '@BASEBOARD_FAB2_LIB.BASEBOARD_FAB2(SCH_1):M_A_DQS_DN'<4>:
 C_SIGNAL='@baseboard_fab2_lib.baseboard_fab2(sch_1):m_a_dqs_dn(4)';
NODE_NAME     U5D1 G40
 '@BASEBOARD_FAB2_LIB.BASEBOARD_FAB2(SCH_1):PAGE23_I172@CHPSET_LIB.SKX_EXT_B(CHIPS)':
 'DDR0_DQS_DN'<4>: CDS_PINID='DDR0_DQS_DN(4)';
NODE_NAME     J4G1 244
 '@BASEBOARD_FAB2_LIB.BASEBOARD_FAB2(SCH_1):PAGE43_I2@MSTR_SCONN.SCONN288_H44441004(CHIPS)':
 'DQS4N': CDS_PINID='DQS4N';
NODE_NAME     J6T1 244
 '@BASEBOARD_FAB2_LIB.BASEBOARD_FAB2(SCH_1):PAGE44_I120@MSTR_SCONN.SCONN288_H44441003(CHIPS)':
 'DQS4N': CDS_PINID='DQS4N';
NET_NAME
'M_A_DQS_DN<5>'
 '@BASEBOARD_FAB2_LIB.BASEBOARD_FAB2(SCH_1):M_A_DQS_DN'<5>:
 C_SIGNAL='@baseboard_fab2_lib.baseboard_fab2(sch_1):m_a_dqs_dn(5)';
NODE_NAME     U5D1 R36
 '@BASEBOARD_FAB2_LIB.BASEBOARD_FAB2(SCH_1):PAGE23_I172@CHPSET_LIB.SKX_EXT_B(CHIPS)':
 'DDR0_DQS_DN'<5>: CDS_PINID='DDR0_DQS_DN(5)';
NODE_NAME     J4G1 255
 '@BASEBOARD_FAB2_LIB.BASEBOARD_FAB2(SCH_1):PAGE43_I2@MSTR_SCONN.SCONN288_H44441004(CHIPS)':
 'DQS5N': CDS_PINID='DQS5N';
NODE_NAME     J6T1 255
 '@BASEBOARD_FAB2_LIB.BASEBOARD_FAB2(SCH_1):PAGE44_I120@MSTR_SCONN.SCONN288_H44441003(CHIPS)':
 'DQS5N': CDS_PINID='DQS5N';
NET_NAME
'M_A_DQS_DN<6>'
 '@BASEBOARD_FAB2_LIB.BASEBOARD_FAB2(SCH_1):M_A_DQS_DN'<6>:
 C_SIGNAL='@baseboard_fab2_lib.baseboard_fab2(sch_1):m_a_dqs_dn(6)';
NODE_NAME     U5D1 R30
 '@BASEBOARD_FAB2_LIB.BASEBOARD_FAB2(SCH_1):PAGE23_I172@CHPSET_LIB.SKX_EXT_B(CHIPS)':
 'DDR0_DQS_DN'<6>: CDS_PINID='DDR0_DQS_DN(6)';
NODE_NAME     J4G1 266
 '@BASEBOARD_FAB2_LIB.BASEBOARD_FAB2(SCH_1):PAGE43_I2@MSTR_SCONN.SCONN288_H44441004(CHIPS)':
 'DQS6N': CDS_PINID='DQS6N';
NODE_NAME     J6T1 266
 '@BASEBOARD_FAB2_LIB.BASEBOARD_FAB2(SCH_1):PAGE44_I120@MSTR_SCONN.SCONN288_H44441003(CHIPS)':
 'DQS6N': CDS_PINID='DQS6N';
NET_NAME
'M_A_DQS_DN<7>'
 '@BASEBOARD_FAB2_LIB.BASEBOARD_FAB2(SCH_1):M_A_DQS_DN'<7>:
 C_SIGNAL='@baseboard_fab2_lib.baseboard_fab2(sch_1):m_a_dqs_dn(7)';
NODE_NAME     U5D1 N24
 '@BASEBOARD_FAB2_LIB.BASEBOARD_FAB2(SCH_1):PAGE23_I172@CHPSET_LIB.SKX_EXT_B(CHIPS)':
 'DDR0_DQS_DN'<7>: CDS_PINID='DDR0_DQS_DN(7)';
NODE_NAME     J4G1 277
 '@BASEBOARD_FAB2_LIB.BASEBOARD_FAB2(SCH_1):PAGE43_I2@MSTR_SCONN.SCONN288_H44441004(CHIPS)':
 'DQS7N': CDS_PINID='DQS7N';
NODE_NAME     J6T1 277
 '@BASEBOARD_FAB2_LIB.BASEBOARD_FAB2(SCH_1):PAGE44_I120@MSTR_SCONN.SCONN288_H44441003(CHIPS)':
 'DQS7N': CDS_PINID='DQS7N';
NET_NAME
'M_A_DQS_DN<8>'
 '@BASEBOARD_FAB2_LIB.BASEBOARD_FAB2(SCH_1):M_A_DQS_DN'<8>:
 C_SIGNAL='@baseboard_fab2_lib.baseboard_fab2(sch_1):m_a_dqs_dn(8)';
NODE_NAME     U5D1 AH67
 '@BASEBOARD_FAB2_LIB.BASEBOARD_FAB2(SCH_1):PAGE23_I172@CHPSET_LIB.SKX_EXT_B(CHIPS)':
 'DDR0_DQS_DN'<8>: CDS_PINID='DDR0_DQS_DN(8)';
NODE_NAME     J4G1 196
 '@BASEBOARD_FAB2_LIB.BASEBOARD_FAB2(SCH_1):PAGE43_I2@MSTR_SCONN.SCONN288_H44441004(CHIPS)':
 'DQS8N': CDS_PINID='DQS8N';
NODE_NAME     J6T1 196
 '@BASEBOARD_FAB2_LIB.BASEBOARD_FAB2(SCH_1):PAGE44_I120@MSTR_SCONN.SCONN288_H44441003(CHIPS)':
 'DQS8N': CDS_PINID='DQS8N';
NET_NAME
'M_A_DQS_DN<9>'
 '@BASEBOARD_FAB2_LIB.BASEBOARD_FAB2(SCH_1):M_A_DQS_DN'<9>:
 C_SIGNAL='@baseboard_fab2_lib.baseboard_fab2(sch_1):m_a_dqs_dn(9)';
NODE_NAME     U5D1 AL84
 '@BASEBOARD_FAB2_LIB.BASEBOARD_FAB2(SCH_1):PAGE23_I172@CHPSET_LIB.SKX_EXT_B(CHIPS)':
 'DDR0_DQS_DN'<9>: CDS_PINID='DDR0_DQS_DN(9)';
NODE_NAME     J4G1 8
 '@BASEBOARD_FAB2_LIB.BASEBOARD_FAB2(SCH_1):PAGE43_I2@MSTR_SCONN.SCONN288_H44441004(CHIPS)':
 'DQS9N': CDS_PINID='DQS9N';
NODE_NAME     J6T1 8
 '@BASEBOARD_FAB2_LIB.BASEBOARD_FAB2(SCH_1):PAGE44_I120@MSTR_SCONN.SCONN288_H44441003(CHIPS)':
 'DQS9N': CDS_PINID='DQS9N';
NET_NAME
'M_A_DQS_DP<0>'
 '@BASEBOARD_FAB2_LIB.BASEBOARD_FAB2(SCH_1):M_A_DQS_DP'<0>:
 C_SIGNAL='@baseboard_fab2_lib.baseboard_fab2(sch_1):m_a_dqs_dp(0)';
NODE_NAME     U5D1 AH85
 '@BASEBOARD_FAB2_LIB.BASEBOARD_FAB2(SCH_1):PAGE23_I172@CHPSET_LIB.SKX_EXT_B(CHIPS)':
 'DDR0_DQS_DP'<0>: CDS_PINID='DDR0_DQS_DP(0)';
NODE_NAME     J4G1 153
 '@BASEBOARD_FAB2_LIB.BASEBOARD_FAB2(SCH_1):PAGE43_I2@MSTR_SCONN.SCONN288_H44441004(CHIPS)':
 'DQS0P': CDS_PINID='DQS0P';
NODE_NAME     J6T1 153
 '@BASEBOARD_FAB2_LIB.BASEBOARD_FAB2(SCH_1):PAGE44_I120@MSTR_SCONN.SCONN288_H44441003(CHIPS)':
 'DQS0P': CDS_PINID='DQS0P';
NET_NAME
'M_A_DQS_DP<10>'
 '@BASEBOARD_FAB2_LIB.BASEBOARD_FAB2(SCH_1):M_A_DQS_DP'<10>:
 C_SIGNAL='@baseboard_fab2_lib.baseboard_fab2(sch_1):m_a_dqs_dp(10)';
NODE_NAME     U5D1 V85
 '@BASEBOARD_FAB2_LIB.BASEBOARD_FAB2(SCH_1):PAGE23_I172@CHPSET_LIB.SKX_EXT_B(CHIPS)':
 'DDR0_DQS_DP'<10>: CDS_PINID='DDR0_DQS_DP(10)';
NODE_NAME     J4G1 18
 '@BASEBOARD_FAB2_LIB.BASEBOARD_FAB2(SCH_1):PAGE43_I2@MSTR_SCONN.SCONN288_H44441004(CHIPS)':
 'DQS10P': CDS_PINID='DQS10P';
NODE_NAME     J6T1 18
 '@BASEBOARD_FAB2_LIB.BASEBOARD_FAB2(SCH_1):PAGE44_I120@MSTR_SCONN.SCONN288_H44441003(CHIPS)':
 'DQS10P': CDS_PINID='DQS10P';
NET_NAME
'M_A_DQS_DP<11>'
 '@BASEBOARD_FAB2_LIB.BASEBOARD_FAB2(SCH_1):M_A_DQS_DP'<11>:
 C_SIGNAL='@baseboard_fab2_lib.baseboard_fab2(sch_1):m_a_dqs_dp(11)';
NODE_NAME     U5D1 T81
 '@BASEBOARD_FAB2_LIB.BASEBOARD_FAB2(SCH_1):PAGE23_I172@CHPSET_LIB.SKX_EXT_B(CHIPS)':
 'DDR0_DQS_DP'<11>: CDS_PINID='DDR0_DQS_DP(11)';
NODE_NAME     J4G1 29
 '@BASEBOARD_FAB2_LIB.BASEBOARD_FAB2(SCH_1):PAGE43_I2@MSTR_SCONN.SCONN288_H44441004(CHIPS)':
 'DQS11P': CDS_PINID='DQS11P';
NODE_NAME     J6T1 29
 '@BASEBOARD_FAB2_LIB.BASEBOARD_FAB2(SCH_1):PAGE44_I120@MSTR_SCONN.SCONN288_H44441003(CHIPS)':
 'DQS11P': CDS_PINID='DQS11P';
NET_NAME
'M_A_DQS_DP<12>'
 '@BASEBOARD_FAB2_LIB.BASEBOARD_FAB2(SCH_1):M_A_DQS_DP'<12>:
 C_SIGNAL='@baseboard_fab2_lib.baseboard_fab2(sch_1):m_a_dqs_dp(12)';
NODE_NAME     U5D1 M75
 '@BASEBOARD_FAB2_LIB.BASEBOARD_FAB2(SCH_1):PAGE23_I172@CHPSET_LIB.SKX_EXT_B(CHIPS)':
 'DDR0_DQS_DP'<12>: CDS_PINID='DDR0_DQS_DP(12)';
NODE_NAME     J4G1 40
 '@BASEBOARD_FAB2_LIB.BASEBOARD_FAB2(SCH_1):PAGE43_I2@MSTR_SCONN.SCONN288_H44441004(CHIPS)':
 'DQS12P': CDS_PINID='DQS12P';
NODE_NAME     J6T1 40
 '@BASEBOARD_FAB2_LIB.BASEBOARD_FAB2(SCH_1):PAGE44_I120@MSTR_SCONN.SCONN288_H44441003(CHIPS)':
 'DQS12P': CDS_PINID='DQS12P';
NET_NAME
'M_A_DQS_DP<13>'
 '@BASEBOARD_FAB2_LIB.BASEBOARD_FAB2(SCH_1):M_A_DQS_DP'<13>:
 C_SIGNAL='@baseboard_fab2_lib.baseboard_fab2(sch_1):m_a_dqs_dp(13)';
NODE_NAME     U5D1 C40
 '@BASEBOARD_FAB2_LIB.BASEBOARD_FAB2(SCH_1):PAGE23_I172@CHPSET_LIB.SKX_EXT_B(CHIPS)':
 'DDR0_DQS_DP'<13>: CDS_PINID='DDR0_DQS_DP(13)';
NODE_NAME     J4G1 99
 '@BASEBOARD_FAB2_LIB.BASEBOARD_FAB2(SCH_1):PAGE43_I2@MSTR_SCONN.SCONN288_H44441004(CHIPS)':
 'DQS13P': CDS_PINID='DQS13P';
NODE_NAME     J6T1 99
 '@BASEBOARD_FAB2_LIB.BASEBOARD_FAB2(SCH_1):PAGE44_I120@MSTR_SCONN.SCONN288_H44441003(CHIPS)':
 'DQS13P': CDS_PINID='DQS13P';
NET_NAME
'M_A_DQS_DP<14>'
 '@BASEBOARD_FAB2_LIB.BASEBOARD_FAB2(SCH_1):M_A_DQS_DP'<14>:
 C_SIGNAL='@baseboard_fab2_lib.baseboard_fab2(sch_1):m_a_dqs_dp(14)';
NODE_NAME     U5D1 L36
 '@BASEBOARD_FAB2_LIB.BASEBOARD_FAB2(SCH_1):PAGE23_I172@CHPSET_LIB.SKX_EXT_B(CHIPS)':
 'DDR0_DQS_DP'<14>: CDS_PINID='DDR0_DQS_DP(14)';
NODE_NAME     J4G1 110
 '@BASEBOARD_FAB2_LIB.BASEBOARD_FAB2(SCH_1):PAGE43_I2@MSTR_SCONN.SCONN288_H44441004(CHIPS)':
 'DQS14P': CDS_PINID='DQS14P';
NODE_NAME     J6T1 110
 '@BASEBOARD_FAB2_LIB.BASEBOARD_FAB2(SCH_1):PAGE44_I120@MSTR_SCONN.SCONN288_H44441003(CHIPS)':
 'DQS14P': CDS_PINID='DQS14P';
NET_NAME
'M_A_DQS_DP<15>'
 '@BASEBOARD_FAB2_LIB.BASEBOARD_FAB2(SCH_1):M_A_DQS_DP'<15>:
 C_SIGNAL='@baseboard_fab2_lib.baseboard_fab2(sch_1):m_a_dqs_dp(15)';
NODE_NAME     U5D1 L30
 '@BASEBOARD_FAB2_LIB.BASEBOARD_FAB2(SCH_1):PAGE23_I172@CHPSET_LIB.SKX_EXT_B(CHIPS)':
 'DDR0_DQS_DP'<15>: CDS_PINID='DDR0_DQS_DP(15)';
NODE_NAME     J4G1 121
 '@BASEBOARD_FAB2_LIB.BASEBOARD_FAB2(SCH_1):PAGE43_I2@MSTR_SCONN.SCONN288_H44441004(CHIPS)':
 'DQS15P': CDS_PINID='DQS15P';
NODE_NAME     J6T1 121
 '@BASEBOARD_FAB2_LIB.BASEBOARD_FAB2(SCH_1):PAGE44_I120@MSTR_SCONN.SCONN288_H44441003(CHIPS)':
 'DQS15P': CDS_PINID='DQS15P';
NET_NAME
'M_A_DQS_DP<16>'
 '@BASEBOARD_FAB2_LIB.BASEBOARD_FAB2(SCH_1):M_A_DQS_DP'<16>:
 C_SIGNAL='@baseboard_fab2_lib.baseboard_fab2(sch_1):m_a_dqs_dp(16)';
NODE_NAME     U5D1 L24
 '@BASEBOARD_FAB2_LIB.BASEBOARD_FAB2(SCH_1):PAGE23_I172@CHPSET_LIB.SKX_EXT_B(CHIPS)':
 'DDR0_DQS_DP'<16>: CDS_PINID='DDR0_DQS_DP(16)';
NODE_NAME     J4G1 132
 '@BASEBOARD_FAB2_LIB.BASEBOARD_FAB2(SCH_1):PAGE43_I2@MSTR_SCONN.SCONN288_H44441004(CHIPS)':
 'DQS16P': CDS_PINID='DQS16P';
NODE_NAME     J6T1 132
 '@BASEBOARD_FAB2_LIB.BASEBOARD_FAB2(SCH_1):PAGE44_I120@MSTR_SCONN.SCONN288_H44441003(CHIPS)':
 'DQS16P': CDS_PINID='DQS16P';
NET_NAME
'M_A_DQS_DP<17>'
 '@BASEBOARD_FAB2_LIB.BASEBOARD_FAB2(SCH_1):M_A_DQS_DP'<17>:
 C_SIGNAL='@baseboard_fab2_lib.baseboard_fab2(sch_1):m_a_dqs_dp(17)';
NODE_NAME     U5D1 AD67
 '@BASEBOARD_FAB2_LIB.BASEBOARD_FAB2(SCH_1):PAGE23_I172@CHPSET_LIB.SKX_EXT_B(CHIPS)':
 'DDR0_DQS_DP'<17>: CDS_PINID='DDR0_DQS_DP(17)';
NODE_NAME     J4G1 51
 '@BASEBOARD_FAB2_LIB.BASEBOARD_FAB2(SCH_1):PAGE43_I2@MSTR_SCONN.SCONN288_H44441004(CHIPS)':
 'DQS17P': CDS_PINID='DQS17P';
NODE_NAME     J6T1 51
 '@BASEBOARD_FAB2_LIB.BASEBOARD_FAB2(SCH_1):PAGE44_I120@MSTR_SCONN.SCONN288_H44441003(CHIPS)':
 'DQS17P': CDS_PINID='DQS17P';
NET_NAME
'M_A_DQS_DP<1>'
 '@BASEBOARD_FAB2_LIB.BASEBOARD_FAB2(SCH_1):M_A_DQS_DP'<1>:
 C_SIGNAL='@baseboard_fab2_lib.baseboard_fab2(sch_1):m_a_dqs_dp(1)';
NODE_NAME     U5D1 P85
 '@BASEBOARD_FAB2_LIB.BASEBOARD_FAB2(SCH_1):PAGE23_I172@CHPSET_LIB.SKX_EXT_B(CHIPS)':
 'DDR0_DQS_DP'<1>: CDS_PINID='DDR0_DQS_DP(1)';
NODE_NAME     J4G1 164
 '@BASEBOARD_FAB2_LIB.BASEBOARD_FAB2(SCH_1):PAGE43_I2@MSTR_SCONN.SCONN288_H44441004(CHIPS)':
 'DQS1P': CDS_PINID='DQS1P';
NODE_NAME     J6T1 164
 '@BASEBOARD_FAB2_LIB.BASEBOARD_FAB2(SCH_1):PAGE44_I120@MSTR_SCONN.SCONN288_H44441003(CHIPS)':
 'DQS1P': CDS_PINID='DQS1P';
NET_NAME
'M_A_DQS_DP<2>'
 '@BASEBOARD_FAB2_LIB.BASEBOARD_FAB2(SCH_1):M_A_DQS_DP'<2>:
 C_SIGNAL='@baseboard_fab2_lib.baseboard_fab2(sch_1):m_a_dqs_dp(2)';
NODE_NAME     U5D1 R80
 '@BASEBOARD_FAB2_LIB.BASEBOARD_FAB2(SCH_1):PAGE23_I172@CHPSET_LIB.SKX_EXT_B(CHIPS)':
 'DDR0_DQS_DP'<2>: CDS_PINID='DDR0_DQS_DP(2)';
NODE_NAME     J4G1 175
 '@BASEBOARD_FAB2_LIB.BASEBOARD_FAB2(SCH_1):PAGE43_I2@MSTR_SCONN.SCONN288_H44441004(CHIPS)':
 'DQS2P': CDS_PINID='DQS2P';
NODE_NAME     J6T1 175
 '@BASEBOARD_FAB2_LIB.BASEBOARD_FAB2(SCH_1):PAGE44_I120@MSTR_SCONN.SCONN288_H44441003(CHIPS)':
 'DQS2P': CDS_PINID='DQS2P';
NET_NAME
'M_A_DQS_DP<3>'
 '@BASEBOARD_FAB2_LIB.BASEBOARD_FAB2(SCH_1):M_A_DQS_DP'<3>:
 C_SIGNAL='@baseboard_fab2_lib.baseboard_fab2(sch_1):m_a_dqs_dp(3)';
NODE_NAME     U5D1 P75
 '@BASEBOARD_FAB2_LIB.BASEBOARD_FAB2(SCH_1):PAGE23_I172@CHPSET_LIB.SKX_EXT_B(CHIPS)':
 'DDR0_DQS_DP'<3>: CDS_PINID='DDR0_DQS_DP(3)';
NODE_NAME     J4G1 186
 '@BASEBOARD_FAB2_LIB.BASEBOARD_FAB2(SCH_1):PAGE43_I2@MSTR_SCONN.SCONN288_H44441004(CHIPS)':
 'DQS3P': CDS_PINID='DQS3P';
NODE_NAME     J6T1 186
 '@BASEBOARD_FAB2_LIB.BASEBOARD_FAB2(SCH_1):PAGE44_I120@MSTR_SCONN.SCONN288_H44441003(CHIPS)':
 'DQS3P': CDS_PINID='DQS3P';
NET_NAME
'M_A_DQS_DP<4>'
 '@BASEBOARD_FAB2_LIB.BASEBOARD_FAB2(SCH_1):M_A_DQS_DP'<4>:
 C_SIGNAL='@baseboard_fab2_lib.baseboard_fab2(sch_1):m_a_dqs_dp(4)';
NODE_NAME     U5D1 E40
 '@BASEBOARD_FAB2_LIB.BASEBOARD_FAB2(SCH_1):PAGE23_I172@CHPSET_LIB.SKX_EXT_B(CHIPS)':
 'DDR0_DQS_DP'<4>: CDS_PINID='DDR0_DQS_DP(4)';
NODE_NAME     J4G1 245
 '@BASEBOARD_FAB2_LIB.BASEBOARD_FAB2(SCH_1):PAGE43_I2@MSTR_SCONN.SCONN288_H44441004(CHIPS)':
 'DQS4P': CDS_PINID='DQS4P';
NODE_NAME     J6T1 245
 '@BASEBOARD_FAB2_LIB.BASEBOARD_FAB2(SCH_1):PAGE44_I120@MSTR_SCONN.SCONN288_H44441003(CHIPS)':
 'DQS4P': CDS_PINID='DQS4P';
NET_NAME
'M_A_DQS_DP<5>'
 '@BASEBOARD_FAB2_LIB.BASEBOARD_FAB2(SCH_1):M_A_DQS_DP'<5>:
 C_SIGNAL='@baseboard_fab2_lib.baseboard_fab2(sch_1):m_a_dqs_dp(5)';
NODE_NAME     U5D1 N36
 '@BASEBOARD_FAB2_LIB.BASEBOARD_FAB2(SCH_1):PAGE23_I172@CHPSET_LIB.SKX_EXT_B(CHIPS)':
 'DDR0_DQS_DP'<5>: CDS_PINID='DDR0_DQS_DP(5)';
NODE_NAME     J4G1 256
 '@BASEBOARD_FAB2_LIB.BASEBOARD_FAB2(SCH_1):PAGE43_I2@MSTR_SCONN.SCONN288_H44441004(CHIPS)':
 'DQS5P': CDS_PINID='DQS5P';
NODE_NAME     J6T1 256
 '@BASEBOARD_FAB2_LIB.BASEBOARD_FAB2(SCH_1):PAGE44_I120@MSTR_SCONN.SCONN288_H44441003(CHIPS)':
 'DQS5P': CDS_PINID='DQS5P';
NET_NAME
'M_A_DQS_DP<6>'
 '@BASEBOARD_FAB2_LIB.BASEBOARD_FAB2(SCH_1):M_A_DQS_DP'<6>:
 C_SIGNAL='@baseboard_fab2_lib.baseboard_fab2(sch_1):m_a_dqs_dp(6)';
NODE_NAME     U5D1 N30
 '@BASEBOARD_FAB2_LIB.BASEBOARD_FAB2(SCH_1):PAGE23_I172@CHPSET_LIB.SKX_EXT_B(CHIPS)':
 'DDR0_DQS_DP'<6>: CDS_PINID='DDR0_DQS_DP(6)';
NODE_NAME     J4G1 267
 '@BASEBOARD_FAB2_LIB.BASEBOARD_FAB2(SCH_1):PAGE43_I2@MSTR_SCONN.SCONN288_H44441004(CHIPS)':
 'DQS6P': CDS_PINID='DQS6P';
NODE_NAME     J6T1 267
 '@BASEBOARD_FAB2_LIB.BASEBOARD_FAB2(SCH_1):PAGE44_I120@MSTR_SCONN.SCONN288_H44441003(CHIPS)':
 'DQS6P': CDS_PINID='DQS6P';
NET_NAME
'M_A_DQS_DP<7>'
 '@BASEBOARD_FAB2_LIB.BASEBOARD_FAB2(SCH_1):M_A_DQS_DP'<7>:
 C_SIGNAL='@baseboard_fab2_lib.baseboard_fab2(sch_1):m_a_dqs_dp(7)';
NODE_NAME     U5D1 R24
 '@BASEBOARD_FAB2_LIB.BASEBOARD_FAB2(SCH_1):PAGE23_I172@CHPSET_LIB.SKX_EXT_B(CHIPS)':
 'DDR0_DQS_DP'<7>: CDS_PINID='DDR0_DQS_DP(7)';
NODE_NAME     J4G1 278
 '@BASEBOARD_FAB2_LIB.BASEBOARD_FAB2(SCH_1):PAGE43_I2@MSTR_SCONN.SCONN288_H44441004(CHIPS)':
 'DQS7P': CDS_PINID='DQS7P';
NODE_NAME     J6T1 278
 '@BASEBOARD_FAB2_LIB.BASEBOARD_FAB2(SCH_1):PAGE44_I120@MSTR_SCONN.SCONN288_H44441003(CHIPS)':
 'DQS7P': CDS_PINID='DQS7P';
NET_NAME
'M_A_DQS_DP<8>'
 '@BASEBOARD_FAB2_LIB.BASEBOARD_FAB2(SCH_1):M_A_DQS_DP'<8>:
 C_SIGNAL='@baseboard_fab2_lib.baseboard_fab2(sch_1):m_a_dqs_dp(8)';
NODE_NAME     U5D1 AF67
 '@BASEBOARD_FAB2_LIB.BASEBOARD_FAB2(SCH_1):PAGE23_I172@CHPSET_LIB.SKX_EXT_B(CHIPS)':
 'DDR0_DQS_DP'<8>: CDS_PINID='DDR0_DQS_DP(8)';
NODE_NAME     J4G1 197
 '@BASEBOARD_FAB2_LIB.BASEBOARD_FAB2(SCH_1):PAGE43_I2@MSTR_SCONN.SCONN288_H44441004(CHIPS)':
 'DQS8P': CDS_PINID='DQS8P';
NODE_NAME     J6T1 197
 '@BASEBOARD_FAB2_LIB.BASEBOARD_FAB2(SCH_1):PAGE44_I120@MSTR_SCONN.SCONN288_H44441003(CHIPS)':
 'DQS8P': CDS_PINID='DQS8P';
NET_NAME
'M_A_DQS_DP<9>'
 '@BASEBOARD_FAB2_LIB.BASEBOARD_FAB2(SCH_1):M_A_DQS_DP'<9>:
 C_SIGNAL='@baseboard_fab2_lib.baseboard_fab2(sch_1):m_a_dqs_dp(9)';
NODE_NAME     U5D1 AM85
 '@BASEBOARD_FAB2_LIB.BASEBOARD_FAB2(SCH_1):PAGE23_I172@CHPSET_LIB.SKX_EXT_B(CHIPS)':
 'DDR0_DQS_DP'<9>: CDS_PINID='DDR0_DQS_DP(9)';
NODE_NAME     J4G1 7
 '@BASEBOARD_FAB2_LIB.BASEBOARD_FAB2(SCH_1):PAGE43_I2@MSTR_SCONN.SCONN288_H44441004(CHIPS)':
 'DQS9P': CDS_PINID='DQS9P';
NODE_NAME     J6T1 7
 '@BASEBOARD_FAB2_LIB.BASEBOARD_FAB2(SCH_1):PAGE44_I120@MSTR_SCONN.SCONN288_H44441003(CHIPS)':
 'DQS9P': CDS_PINID='DQS9P';
NET_NAME
'M_A_ECC<0>'
 '@BASEBOARD_FAB2_LIB.BASEBOARD_FAB2(SCH_1):M_A_ECC'<0>:
 C_SIGNAL='@baseboard_fab2_lib.baseboard_fab2(sch_1):m_a_ecc(0)';
NODE_NAME     U5D1 AC68
 '@BASEBOARD_FAB2_LIB.BASEBOARD_FAB2(SCH_1):PAGE23_I172@CHPSET_LIB.SKX_EXT_B(CHIPS)':
 'DDR0_ECC'<0>: CDS_PINID='DDR0_ECC(0)';
NODE_NAME     J4G1 194
 '@BASEBOARD_FAB2_LIB.BASEBOARD_FAB2(SCH_1):PAGE43_I1@MSTR_SCONN.SCONN288_H44441004(CHIPS)':
 'CB'<1>: CDS_PINID='CB(1)';
NODE_NAME     J6T1 49
 '@BASEBOARD_FAB2_LIB.BASEBOARD_FAB2(SCH_1):PAGE44_I13@MSTR_SCONN.SCONN288_H44441003(CHIPS)':
 'CB'<0>: CDS_PINID='CB(0)';
NET_NAME
'M_A_ECC<1>'
 '@BASEBOARD_FAB2_LIB.BASEBOARD_FAB2(SCH_1):M_A_ECC'<1>:
 C_SIGNAL='@baseboard_fab2_lib.baseboard_fab2(sch_1):m_a_ecc(1)';
NODE_NAME     U5D1 AG68
 '@BASEBOARD_FAB2_LIB.BASEBOARD_FAB2(SCH_1):PAGE23_I172@CHPSET_LIB.SKX_EXT_B(CHIPS)':
 'DDR0_ECC'<1>: CDS_PINID='DDR0_ECC(1)';
NODE_NAME     J4G1 49
 '@BASEBOARD_FAB2_LIB.BASEBOARD_FAB2(SCH_1):PAGE43_I1@MSTR_SCONN.SCONN288_H44441004(CHIPS)':
 'CB'<0>: CDS_PINID='CB(0)';
NODE_NAME     J6T1 194
 '@BASEBOARD_FAB2_LIB.BASEBOARD_FAB2(SCH_1):PAGE44_I13@MSTR_SCONN.SCONN288_H44441003(CHIPS)':
 'CB'<1>: CDS_PINID='CB(1)';
NET_NAME
'M_A_ECC<2>'
 '@BASEBOARD_FAB2_LIB.BASEBOARD_FAB2(SCH_1):M_A_ECC'<2>:
 C_SIGNAL='@baseboard_fab2_lib.baseboard_fab2(sch_1):m_a_ecc(2)';
NODE_NAME     U5D1 AD65
 '@BASEBOARD_FAB2_LIB.BASEBOARD_FAB2(SCH_1):PAGE23_I172@CHPSET_LIB.SKX_EXT_B(CHIPS)':
 'DDR0_ECC'<2>: CDS_PINID='DDR0_ECC(2)';
NODE_NAME     J4G1 201
 '@BASEBOARD_FAB2_LIB.BASEBOARD_FAB2(SCH_1):PAGE43_I1@MSTR_SCONN.SCONN288_H44441004(CHIPS)':
 'CB'<3>: CDS_PINID='CB(3)';
NODE_NAME     J6T1 56
 '@BASEBOARD_FAB2_LIB.BASEBOARD_FAB2(SCH_1):PAGE44_I13@MSTR_SCONN.SCONN288_H44441003(CHIPS)':
 'CB'<2>: CDS_PINID='CB(2)';
NET_NAME
'M_A_ECC<3>'
 '@BASEBOARD_FAB2_LIB.BASEBOARD_FAB2(SCH_1):M_A_ECC'<3>:
 C_SIGNAL='@baseboard_fab2_lib.baseboard_fab2(sch_1):m_a_ecc(3)';
NODE_NAME     U5D1 AF65
 '@BASEBOARD_FAB2_LIB.BASEBOARD_FAB2(SCH_1):PAGE23_I172@CHPSET_LIB.SKX_EXT_B(CHIPS)':
 'DDR0_ECC'<3>: CDS_PINID='DDR0_ECC(3)';
NODE_NAME     J4G1 56
 '@BASEBOARD_FAB2_LIB.BASEBOARD_FAB2(SCH_1):PAGE43_I1@MSTR_SCONN.SCONN288_H44441004(CHIPS)':
 'CB'<2>: CDS_PINID='CB(2)';
NODE_NAME     J6T1 201
 '@BASEBOARD_FAB2_LIB.BASEBOARD_FAB2(SCH_1):PAGE44_I13@MSTR_SCONN.SCONN288_H44441003(CHIPS)':
 'CB'<3>: CDS_PINID='CB(3)';
NET_NAME
'M_A_ECC<4>'
 '@BASEBOARD_FAB2_LIB.BASEBOARD_FAB2(SCH_1):M_A_ECC'<4>:
 C_SIGNAL='@baseboard_fab2_lib.baseboard_fab2(sch_1):m_a_ecc(4)';
NODE_NAME     U5D1 AD69
 '@BASEBOARD_FAB2_LIB.BASEBOARD_FAB2(SCH_1):PAGE23_I172@CHPSET_LIB.SKX_EXT_B(CHIPS)':
 'DDR0_ECC'<4>: CDS_PINID='DDR0_ECC(4)';
NODE_NAME     J4G1 192
 '@BASEBOARD_FAB2_LIB.BASEBOARD_FAB2(SCH_1):PAGE43_I1@MSTR_SCONN.SCONN288_H44441004(CHIPS)':
 'CB'<5>: CDS_PINID='CB(5)';
NODE_NAME     J6T1 47
 '@BASEBOARD_FAB2_LIB.BASEBOARD_FAB2(SCH_1):PAGE44_I13@MSTR_SCONN.SCONN288_H44441003(CHIPS)':
 'CB'<4>: CDS_PINID='CB(4)';
NET_NAME
'M_A_ECC<5>'
 '@BASEBOARD_FAB2_LIB.BASEBOARD_FAB2(SCH_1):M_A_ECC'<5>:
 C_SIGNAL='@baseboard_fab2_lib.baseboard_fab2(sch_1):m_a_ecc(5)';
NODE_NAME     U5D1 AF69
 '@BASEBOARD_FAB2_LIB.BASEBOARD_FAB2(SCH_1):PAGE23_I172@CHPSET_LIB.SKX_EXT_B(CHIPS)':
 'DDR0_ECC'<5>: CDS_PINID='DDR0_ECC(5)';
NODE_NAME     J4G1 47
 '@BASEBOARD_FAB2_LIB.BASEBOARD_FAB2(SCH_1):PAGE43_I1@MSTR_SCONN.SCONN288_H44441004(CHIPS)':
 'CB'<4>: CDS_PINID='CB(4)';
NODE_NAME     J6T1 192
 '@BASEBOARD_FAB2_LIB.BASEBOARD_FAB2(SCH_1):PAGE44_I13@MSTR_SCONN.SCONN288_H44441003(CHIPS)':
 'CB'<5>: CDS_PINID='CB(5)';
NET_NAME
'M_A_ECC<6>'
 '@BASEBOARD_FAB2_LIB.BASEBOARD_FAB2(SCH_1):M_A_ECC'<6>:
 C_SIGNAL='@baseboard_fab2_lib.baseboard_fab2(sch_1):m_a_ecc(6)';
NODE_NAME     U5D1 AC66
 '@BASEBOARD_FAB2_LIB.BASEBOARD_FAB2(SCH_1):PAGE23_I172@CHPSET_LIB.SKX_EXT_B(CHIPS)':
 'DDR0_ECC'<6>: CDS_PINID='DDR0_ECC(6)';
NODE_NAME     J4G1 199
 '@BASEBOARD_FAB2_LIB.BASEBOARD_FAB2(SCH_1):PAGE43_I1@MSTR_SCONN.SCONN288_H44441004(CHIPS)':
 'CB'<7>: CDS_PINID='CB(7)';
NODE_NAME     J6T1 54
 '@BASEBOARD_FAB2_LIB.BASEBOARD_FAB2(SCH_1):PAGE44_I13@MSTR_SCONN.SCONN288_H44441003(CHIPS)':
 'CB'<6>: CDS_PINID='CB(6)';
NET_NAME
'M_A_ECC<7>'
 '@BASEBOARD_FAB2_LIB.BASEBOARD_FAB2(SCH_1):M_A_ECC'<7>:
 C_SIGNAL='@baseboard_fab2_lib.baseboard_fab2(sch_1):m_a_ecc(7)';
NODE_NAME     U5D1 AG66
 '@BASEBOARD_FAB2_LIB.BASEBOARD_FAB2(SCH_1):PAGE23_I172@CHPSET_LIB.SKX_EXT_B(CHIPS)':
 'DDR0_ECC'<7>: CDS_PINID='DDR0_ECC(7)';
NODE_NAME     J4G1 54
 '@BASEBOARD_FAB2_LIB.BASEBOARD_FAB2(SCH_1):PAGE43_I1@MSTR_SCONN.SCONN288_H44441004(CHIPS)':
 'CB'<6>: CDS_PINID='CB(6)';
NODE_NAME     J6T1 199
 '@BASEBOARD_FAB2_LIB.BASEBOARD_FAB2(SCH_1):PAGE44_I13@MSTR_SCONN.SCONN288_H44441003(CHIPS)':
 'CB'<7>: CDS_PINID='CB(7)';
NET_NAME
'M_A_MA<0>'
 '@BASEBOARD_FAB2_LIB.BASEBOARD_FAB2(SCH_1):M_A_MA'<0>:
 C_SIGNAL='@baseboard_fab2_lib.baseboard_fab2(sch_1):m_a_ma(0)';
NODE_NAME     U5D1 F53
 '@BASEBOARD_FAB2_LIB.BASEBOARD_FAB2(SCH_1):PAGE23_I172@CHPSET_LIB.SKX_EXT_B(CHIPS)':
 'DDR0_MA'<0>: CDS_PINID='DDR0_MA(0)';
NODE_NAME     J4G1 79
 '@BASEBOARD_FAB2_LIB.BASEBOARD_FAB2(SCH_1):PAGE43_I1@MSTR_SCONN.SCONN288_H44441004(CHIPS)':
 'A0': CDS_PINID='A0';
NODE_NAME     J6T1 79
 '@BASEBOARD_FAB2_LIB.BASEBOARD_FAB2(SCH_1):PAGE44_I13@MSTR_SCONN.SCONN288_H44441003(CHIPS)':
 'A0': CDS_PINID='A0';
NET_NAME
'M_A_MA<10>'
 '@BASEBOARD_FAB2_LIB.BASEBOARD_FAB2(SCH_1):M_A_MA'<10>:
 C_SIGNAL='@baseboard_fab2_lib.baseboard_fab2(sch_1):m_a_ma(10)';
NODE_NAME     U5D1 J54
 '@BASEBOARD_FAB2_LIB.BASEBOARD_FAB2(SCH_1):PAGE23_I172@CHPSET_LIB.SKX_EXT_B(CHIPS)':
 'DDR0_MA'<10>: CDS_PINID='DDR0_MA(10)';
NODE_NAME     J4G1 225
 '@BASEBOARD_FAB2_LIB.BASEBOARD_FAB2(SCH_1):PAGE43_I1@MSTR_SCONN.SCONN288_H44441004(CHIPS)':
 'A10': CDS_PINID='A10';
NODE_NAME     J6T1 225
 '@BASEBOARD_FAB2_LIB.BASEBOARD_FAB2(SCH_1):PAGE44_I13@MSTR_SCONN.SCONN288_H44441003(CHIPS)':
 'A10': CDS_PINID='A10';
NET_NAME
'M_A_MA<11>'
 '@BASEBOARD_FAB2_LIB.BASEBOARD_FAB2(SCH_1):M_A_MA'<11>:
 C_SIGNAL='@baseboard_fab2_lib.baseboard_fab2(sch_1):m_a_ma(11)';
NODE_NAME     U5D1 G62
 '@BASEBOARD_FAB2_LIB.BASEBOARD_FAB2(SCH_1):PAGE23_I172@CHPSET_LIB.SKX_EXT_B(CHIPS)':
 'DDR0_MA'<11>: CDS_PINID='DDR0_MA(11)';
NODE_NAME     J4G1 210
 '@BASEBOARD_FAB2_LIB.BASEBOARD_FAB2(SCH_1):PAGE43_I1@MSTR_SCONN.SCONN288_H44441004(CHIPS)':
 'A11': CDS_PINID='A11';
NODE_NAME     J6T1 210
 '@BASEBOARD_FAB2_LIB.BASEBOARD_FAB2(SCH_1):PAGE44_I13@MSTR_SCONN.SCONN288_H44441003(CHIPS)':
 'A11': CDS_PINID='A11';
NET_NAME
'M_A_MA<12>'
 '@BASEBOARD_FAB2_LIB.BASEBOARD_FAB2(SCH_1):M_A_MA'<12>:
 C_SIGNAL='@baseboard_fab2_lib.baseboard_fab2(sch_1):m_a_ma(12)';
NODE_NAME     U5D1 J64
 '@BASEBOARD_FAB2_LIB.BASEBOARD_FAB2(SCH_1):PAGE23_I172@CHPSET_LIB.SKX_EXT_B(CHIPS)':
 'DDR0_MA'<12>: CDS_PINID='DDR0_MA(12)';
NODE_NAME     J4G1 65
 '@BASEBOARD_FAB2_LIB.BASEBOARD_FAB2(SCH_1):PAGE43_I1@MSTR_SCONN.SCONN288_H44441004(CHIPS)':
 'A12': CDS_PINID='A12';
NODE_NAME     J6T1 65
 '@BASEBOARD_FAB2_LIB.BASEBOARD_FAB2(SCH_1):PAGE44_I13@MSTR_SCONN.SCONN288_H44441003(CHIPS)':
 'A12': CDS_PINID='A12';
NET_NAME
'M_A_MA<13>'
 '@BASEBOARD_FAB2_LIB.BASEBOARD_FAB2(SCH_1):M_A_MA'<13>:
 C_SIGNAL='@baseboard_fab2_lib.baseboard_fab2(sch_1):m_a_ma(13)';
NODE_NAME     U5D1 J48
 '@BASEBOARD_FAB2_LIB.BASEBOARD_FAB2(SCH_1):PAGE23_I172@CHPSET_LIB.SKX_EXT_B(CHIPS)':
 'DDR0_MA'<13>: CDS_PINID='DDR0_MA(13)';
NODE_NAME     J4G1 232
 '@BASEBOARD_FAB2_LIB.BASEBOARD_FAB2(SCH_1):PAGE43_I1@MSTR_SCONN.SCONN288_H44441004(CHIPS)':
 'A13': CDS_PINID='A13';
NODE_NAME     J6T1 232
 '@BASEBOARD_FAB2_LIB.BASEBOARD_FAB2(SCH_1):PAGE44_I13@MSTR_SCONN.SCONN288_H44441003(CHIPS)':
 'A13': CDS_PINID='A13';
NET_NAME
'M_A_MA<14>'
 '@BASEBOARD_FAB2_LIB.BASEBOARD_FAB2(SCH_1):M_A_MA'<14>:
 C_SIGNAL='@baseboard_fab2_lib.baseboard_fab2(sch_1):m_a_ma(14)';
NODE_NAME     U5D1 F51
 '@BASEBOARD_FAB2_LIB.BASEBOARD_FAB2(SCH_1):PAGE23_I172@CHPSET_LIB.SKX_EXT_B(CHIPS)':
 'DDR0_MA'<14>: CDS_PINID='DDR0_MA(14)';
NODE_NAME     J4G1 228
 '@BASEBOARD_FAB2_LIB.BASEBOARD_FAB2(SCH_1):PAGE43_I1@MSTR_SCONN.SCONN288_H44441004(CHIPS)':
 'A14_WE_N': CDS_PINID='A14_WE_N';
NODE_NAME     J6T1 228
 '@BASEBOARD_FAB2_LIB.BASEBOARD_FAB2(SCH_1):PAGE44_I13@MSTR_SCONN.SCONN288_H44441003(CHIPS)':
 'A14_WE_N': CDS_PINID='A14_WE_N';
NET_NAME
'M_A_MA<15>'
 '@BASEBOARD_FAB2_LIB.BASEBOARD_FAB2(SCH_1):M_A_MA'<15>:
 C_SIGNAL='@baseboard_fab2_lib.baseboard_fab2(sch_1):m_a_ma(15)';
NODE_NAME     U5D1 K49
 '@BASEBOARD_FAB2_LIB.BASEBOARD_FAB2(SCH_1):PAGE23_I172@CHPSET_LIB.SKX_EXT_B(CHIPS)':
 'DDR0_MA'<15>: CDS_PINID='DDR0_MA(15)';
NODE_NAME     J4G1 86
 '@BASEBOARD_FAB2_LIB.BASEBOARD_FAB2(SCH_1):PAGE43_I1@MSTR_SCONN.SCONN288_H44441004(CHIPS)':
 'A15_CAS_N': CDS_PINID='A15_CAS_N';
NODE_NAME     J6T1 86
 '@BASEBOARD_FAB2_LIB.BASEBOARD_FAB2(SCH_1):PAGE44_I13@MSTR_SCONN.SCONN288_H44441003(CHIPS)':
 'A15_CAS_N': CDS_PINID='A15_CAS_N';
NET_NAME
'M_A_MA<16>'
 '@BASEBOARD_FAB2_LIB.BASEBOARD_FAB2(SCH_1):M_A_MA'<16>:
 C_SIGNAL='@baseboard_fab2_lib.baseboard_fab2(sch_1):m_a_ma(16)';
NODE_NAME     U5D1 D51
 '@BASEBOARD_FAB2_LIB.BASEBOARD_FAB2(SCH_1):PAGE23_I172@CHPSET_LIB.SKX_EXT_B(CHIPS)':
 'DDR0_MA'<16>: CDS_PINID='DDR0_MA(16)';
NODE_NAME     J4G1 82
 '@BASEBOARD_FAB2_LIB.BASEBOARD_FAB2(SCH_1):PAGE43_I1@MSTR_SCONN.SCONN288_H44441004(CHIPS)':
 'A16_RAS_N': CDS_PINID='A16_RAS_N';
NODE_NAME     J6T1 82
 '@BASEBOARD_FAB2_LIB.BASEBOARD_FAB2(SCH_1):PAGE44_I13@MSTR_SCONN.SCONN288_H44441003(CHIPS)':
 'A16_RAS_N': CDS_PINID='A16_RAS_N';
NET_NAME
'M_A_MA<17>'
 '@BASEBOARD_FAB2_LIB.BASEBOARD_FAB2(SCH_1):M_A_MA'<17>:
 C_SIGNAL='@baseboard_fab2_lib.baseboard_fab2(sch_1):m_a_ma(17)';
NODE_NAME     U5D1 K47
 '@BASEBOARD_FAB2_LIB.BASEBOARD_FAB2(SCH_1):PAGE23_I172@CHPSET_LIB.SKX_EXT_B(CHIPS)':
 'DDR0_MA'<17>: CDS_PINID='DDR0_MA(17)';
NODE_NAME     J4G1 234
 '@BASEBOARD_FAB2_LIB.BASEBOARD_FAB2(SCH_1):PAGE43_I1@MSTR_SCONN.SCONN288_H44441004(CHIPS)':
 'A17': CDS_PINID='A17';
NODE_NAME     J6T1 234
 '@BASEBOARD_FAB2_LIB.BASEBOARD_FAB2(SCH_1):PAGE44_I13@MSTR_SCONN.SCONN288_H44441003(CHIPS)':
 'A17': CDS_PINID='A17';
NET_NAME
'M_A_MA<1>'
 '@BASEBOARD_FAB2_LIB.BASEBOARD_FAB2(SCH_1):M_A_MA'<1>:
 C_SIGNAL='@baseboard_fab2_lib.baseboard_fab2(sch_1):m_a_ma(1)';
NODE_NAME     U5D1 F57
 '@BASEBOARD_FAB2_LIB.BASEBOARD_FAB2(SCH_1):PAGE23_I172@CHPSET_LIB.SKX_EXT_B(CHIPS)':
 'DDR0_MA'<1>: CDS_PINID='DDR0_MA(1)';
NODE_NAME     J4G1 72
 '@BASEBOARD_FAB2_LIB.BASEBOARD_FAB2(SCH_1):PAGE43_I1@MSTR_SCONN.SCONN288_H44441004(CHIPS)':
 'A1': CDS_PINID='A1';
NODE_NAME     J6T1 72
 '@BASEBOARD_FAB2_LIB.BASEBOARD_FAB2(SCH_1):PAGE44_I13@MSTR_SCONN.SCONN288_H44441003(CHIPS)':
 'A1': CDS_PINID='A1';
NET_NAME
'M_A_MA<2>'
 '@BASEBOARD_FAB2_LIB.BASEBOARD_FAB2(SCH_1):M_A_MA'<2>:
 C_SIGNAL='@baseboard_fab2_lib.baseboard_fab2(sch_1):m_a_ma(2)';
NODE_NAME     U5D1 D57
 '@BASEBOARD_FAB2_LIB.BASEBOARD_FAB2(SCH_1):PAGE23_I172@CHPSET_LIB.SKX_EXT_B(CHIPS)':
 'DDR0_MA'<2>: CDS_PINID='DDR0_MA(2)';
NODE_NAME     J4G1 216
 '@BASEBOARD_FAB2_LIB.BASEBOARD_FAB2(SCH_1):PAGE43_I1@MSTR_SCONN.SCONN288_H44441004(CHIPS)':
 'A2': CDS_PINID='A2';
NODE_NAME     J6T1 216
 '@BASEBOARD_FAB2_LIB.BASEBOARD_FAB2(SCH_1):PAGE44_I13@MSTR_SCONN.SCONN288_H44441003(CHIPS)':
 'A2': CDS_PINID='A2';
NET_NAME
'M_A_MA<3>'
 '@BASEBOARD_FAB2_LIB.BASEBOARD_FAB2(SCH_1):M_A_MA'<3>:
 C_SIGNAL='@baseboard_fab2_lib.baseboard_fab2(sch_1):m_a_ma(3)';
NODE_NAME     U5D1 C58
 '@BASEBOARD_FAB2_LIB.BASEBOARD_FAB2(SCH_1):PAGE23_I172@CHPSET_LIB.SKX_EXT_B(CHIPS)':
 'DDR0_MA'<3>: CDS_PINID='DDR0_MA(3)';
NODE_NAME     J4G1 71
 '@BASEBOARD_FAB2_LIB.BASEBOARD_FAB2(SCH_1):PAGE43_I1@MSTR_SCONN.SCONN288_H44441004(CHIPS)':
 'A3': CDS_PINID='A3';
NODE_NAME     J6T1 71
 '@BASEBOARD_FAB2_LIB.BASEBOARD_FAB2(SCH_1):PAGE44_I13@MSTR_SCONN.SCONN288_H44441003(CHIPS)':
 'A3': CDS_PINID='A3';
NET_NAME
'M_A_MA<4>'
 '@BASEBOARD_FAB2_LIB.BASEBOARD_FAB2(SCH_1):M_A_MA'<4>:
 C_SIGNAL='@baseboard_fab2_lib.baseboard_fab2(sch_1):m_a_ma(4)';
NODE_NAME     U5D1 G58
 '@BASEBOARD_FAB2_LIB.BASEBOARD_FAB2(SCH_1):PAGE23_I172@CHPSET_LIB.SKX_EXT_B(CHIPS)':
 'DDR0_MA'<4>: CDS_PINID='DDR0_MA(4)';
NODE_NAME     J4G1 214
 '@BASEBOARD_FAB2_LIB.BASEBOARD_FAB2(SCH_1):PAGE43_I1@MSTR_SCONN.SCONN288_H44441004(CHIPS)':
 'A4': CDS_PINID='A4';
NODE_NAME     J6T1 214
 '@BASEBOARD_FAB2_LIB.BASEBOARD_FAB2(SCH_1):PAGE44_I13@MSTR_SCONN.SCONN288_H44441003(CHIPS)':
 'A4': CDS_PINID='A4';
NET_NAME
'M_A_MA<5>'
 '@BASEBOARD_FAB2_LIB.BASEBOARD_FAB2(SCH_1):M_A_MA'<5>:
 C_SIGNAL='@baseboard_fab2_lib.baseboard_fab2(sch_1):m_a_ma(5)';
NODE_NAME     U5D1 F59
 '@BASEBOARD_FAB2_LIB.BASEBOARD_FAB2(SCH_1):PAGE23_I172@CHPSET_LIB.SKX_EXT_B(CHIPS)':
 'DDR0_MA'<5>: CDS_PINID='DDR0_MA(5)';
NODE_NAME     J4G1 213
 '@BASEBOARD_FAB2_LIB.BASEBOARD_FAB2(SCH_1):PAGE43_I1@MSTR_SCONN.SCONN288_H44441004(CHIPS)':
 'A5': CDS_PINID='A5';
NODE_NAME     J6T1 213
 '@BASEBOARD_FAB2_LIB.BASEBOARD_FAB2(SCH_1):PAGE44_I13@MSTR_SCONN.SCONN288_H44441003(CHIPS)':
 'A5': CDS_PINID='A5';
NET_NAME
'M_A_MA<6>'
 '@BASEBOARD_FAB2_LIB.BASEBOARD_FAB2(SCH_1):M_A_MA'<6>:
 C_SIGNAL='@baseboard_fab2_lib.baseboard_fab2(sch_1):m_a_ma(6)';
NODE_NAME     U5D1 D59
 '@BASEBOARD_FAB2_LIB.BASEBOARD_FAB2(SCH_1):PAGE23_I172@CHPSET_LIB.SKX_EXT_B(CHIPS)':
 'DDR0_MA'<6>: CDS_PINID='DDR0_MA(6)';
NODE_NAME     J4G1 69
 '@BASEBOARD_FAB2_LIB.BASEBOARD_FAB2(SCH_1):PAGE43_I1@MSTR_SCONN.SCONN288_H44441004(CHIPS)':
 'A6': CDS_PINID='A6';
NODE_NAME     J6T1 69
 '@BASEBOARD_FAB2_LIB.BASEBOARD_FAB2(SCH_1):PAGE44_I13@MSTR_SCONN.SCONN288_H44441003(CHIPS)':
 'A6': CDS_PINID='A6';
NET_NAME
'M_A_MA<7>'
 '@BASEBOARD_FAB2_LIB.BASEBOARD_FAB2(SCH_1):M_A_MA'<7>:
 C_SIGNAL='@baseboard_fab2_lib.baseboard_fab2(sch_1):m_a_ma(7)';
NODE_NAME     U5D1 G60
 '@BASEBOARD_FAB2_LIB.BASEBOARD_FAB2(SCH_1):PAGE23_I172@CHPSET_LIB.SKX_EXT_B(CHIPS)':
 'DDR0_MA'<7>: CDS_PINID='DDR0_MA(7)';
NODE_NAME     J4G1 211
 '@BASEBOARD_FAB2_LIB.BASEBOARD_FAB2(SCH_1):PAGE43_I1@MSTR_SCONN.SCONN288_H44441004(CHIPS)':
 'A7': CDS_PINID='A7';
NODE_NAME     J6T1 211
 '@BASEBOARD_FAB2_LIB.BASEBOARD_FAB2(SCH_1):PAGE44_I13@MSTR_SCONN.SCONN288_H44441003(CHIPS)':
 'A7': CDS_PINID='A7';
NET_NAME
'M_A_MA<8>'
 '@BASEBOARD_FAB2_LIB.BASEBOARD_FAB2(SCH_1):M_A_MA'<8>:
 C_SIGNAL='@baseboard_fab2_lib.baseboard_fab2(sch_1):m_a_ma(8)';
NODE_NAME     U5D1 C60
 '@BASEBOARD_FAB2_LIB.BASEBOARD_FAB2(SCH_1):PAGE23_I172@CHPSET_LIB.SKX_EXT_B(CHIPS)':
 'DDR0_MA'<8>: CDS_PINID='DDR0_MA(8)';
NODE_NAME     J4G1 68
 '@BASEBOARD_FAB2_LIB.BASEBOARD_FAB2(SCH_1):PAGE43_I1@MSTR_SCONN.SCONN288_H44441004(CHIPS)':
 'A8': CDS_PINID='A8';
NODE_NAME     J6T1 68
 '@BASEBOARD_FAB2_LIB.BASEBOARD_FAB2(SCH_1):PAGE44_I13@MSTR_SCONN.SCONN288_H44441003(CHIPS)':
 'A8': CDS_PINID='A8';
NET_NAME
'M_A_MA<9>'
 '@BASEBOARD_FAB2_LIB.BASEBOARD_FAB2(SCH_1):M_A_MA'<9>:
 C_SIGNAL='@baseboard_fab2_lib.baseboard_fab2(sch_1):m_a_ma(9)';
NODE_NAME     U5D1 F61
 '@BASEBOARD_FAB2_LIB.BASEBOARD_FAB2(SCH_1):PAGE23_I172@CHPSET_LIB.SKX_EXT_B(CHIPS)':
 'DDR0_MA'<9>: CDS_PINID='DDR0_MA(9)';
NODE_NAME     J4G1 66
 '@BASEBOARD_FAB2_LIB.BASEBOARD_FAB2(SCH_1):PAGE43_I1@MSTR_SCONN.SCONN288_H44441004(CHIPS)':
 'A9': CDS_PINID='A9';
NODE_NAME     J6T1 66
 '@BASEBOARD_FAB2_LIB.BASEBOARD_FAB2(SCH_1):PAGE44_I13@MSTR_SCONN.SCONN288_H44441003(CHIPS)':
 'A9': CDS_PINID='A9';
NET_NAME
'M_A_ODT<0>'
 '@BASEBOARD_FAB2_LIB.BASEBOARD_FAB2(SCH_1):M_A_ODT'<0>:
 C_SIGNAL='@baseboard_fab2_lib.baseboard_fab2(sch_1):m_a_odt(0)';
NODE_NAME     U5D1 C50
 '@BASEBOARD_FAB2_LIB.BASEBOARD_FAB2(SCH_1):PAGE23_I172@CHPSET_LIB.SKX_EXT_B(CHIPS)':
 'DDR0_ODT'<0>: CDS_PINID='DDR0_ODT(0)';
NODE_NAME     J4G1 87
 '@BASEBOARD_FAB2_LIB.BASEBOARD_FAB2(SCH_1):PAGE43_I1@MSTR_SCONN.SCONN288_H44441004(CHIPS)':
 'ODT'<0>: CDS_PINID='ODT(0)';
NET_NAME
'M_A_ODT<1>'
 '@BASEBOARD_FAB2_LIB.BASEBOARD_FAB2(SCH_1):M_A_ODT'<1>:
 C_SIGNAL='@baseboard_fab2_lib.baseboard_fab2(sch_1):m_a_odt(1)';
NODE_NAME     U5D1 C48
 '@BASEBOARD_FAB2_LIB.BASEBOARD_FAB2(SCH_1):PAGE23_I172@CHPSET_LIB.SKX_EXT_B(CHIPS)':
 'DDR0_ODT'<1>: CDS_PINID='DDR0_ODT(1)';
NODE_NAME     J4G1 91
 '@BASEBOARD_FAB2_LIB.BASEBOARD_FAB2(SCH_1):PAGE43_I1@MSTR_SCONN.SCONN288_H44441004(CHIPS)':
 'ODT'<1>: CDS_PINID='ODT(1)';
NET_NAME
'M_A_ODT<2>'
 '@BASEBOARD_FAB2_LIB.BASEBOARD_FAB2(SCH_1):M_A_ODT'<2>:
 C_SIGNAL='@baseboard_fab2_lib.baseboard_fab2(sch_1):m_a_odt(2)';
NODE_NAME     U5D1 G50
 '@BASEBOARD_FAB2_LIB.BASEBOARD_FAB2(SCH_1):PAGE23_I172@CHPSET_LIB.SKX_EXT_B(CHIPS)':
 'DDR0_ODT'<2>: CDS_PINID='DDR0_ODT(2)';
NODE_NAME     J6T1 87
 '@BASEBOARD_FAB2_LIB.BASEBOARD_FAB2(SCH_1):PAGE44_I13@MSTR_SCONN.SCONN288_H44441003(CHIPS)':
 'ODT'<0>: CDS_PINID='ODT(0)';
NET_NAME
'M_A_ODT<3>'
 '@BASEBOARD_FAB2_LIB.BASEBOARD_FAB2(SCH_1):M_A_ODT'<3>:
 C_SIGNAL='@baseboard_fab2_lib.baseboard_fab2(sch_1):m_a_odt(3)';
NODE_NAME     U5D1 G48
 '@BASEBOARD_FAB2_LIB.BASEBOARD_FAB2(SCH_1):PAGE23_I172@CHPSET_LIB.SKX_EXT_B(CHIPS)':
 'DDR0_ODT'<3>: CDS_PINID='DDR0_ODT(3)';
NODE_NAME     J6T1 91
 '@BASEBOARD_FAB2_LIB.BASEBOARD_FAB2(SCH_1):PAGE44_I13@MSTR_SCONN.SCONN288_H44441003(CHIPS)':
 'ODT'<1>: CDS_PINID='ODT(1)';
NET_NAME
'M_A_PAR'
 '@BASEBOARD_FAB2_LIB.BASEBOARD_FAB2(SCH_1):M_A_PAR':
 C_SIGNAL='@baseboard_fab2_lib.baseboard_fab2(sch_1):m_a_par';
NODE_NAME     U5D1 D53
 '@BASEBOARD_FAB2_LIB.BASEBOARD_FAB2(SCH_1):PAGE23_I172@CHPSET_LIB.SKX_EXT_B(CHIPS)':
 'DDR0_PAR': CDS_PINID='DDR0_PAR';
NODE_NAME     J4G1 222
 '@BASEBOARD_FAB2_LIB.BASEBOARD_FAB2(SCH_1):PAGE43_I1@MSTR_SCONN.SCONN288_H44441004(CHIPS)':
 'PAR': CDS_PINID='PAR';
NODE_NAME     J6T1 222
 '@BASEBOARD_FAB2_LIB.BASEBOARD_FAB2(SCH_1):PAGE44_I13@MSTR_SCONN.SCONN288_H44441003(CHIPS)':
 'PAR': CDS_PINID='PAR';
NET_NAME
'M_A_VREF'
 '@BASEBOARD_FAB2_LIB.BASEBOARD_FAB2(SCH_1):M_A_VREF':
 C_SIGNAL='@baseboard_fab2_lib.baseboard_fab2(sch_1):m_a_vref';
NODE_NAME     J4G1 146
 '@BASEBOARD_FAB2_LIB.BASEBOARD_FAB2(SCH_1):PAGE43_I1@MSTR_SCONN.SCONN288_H44441004(CHIPS)':
 'VREFCA': CDS_PINID='VREFCA';
NODE_NAME     C4F10 1
 '@BASEBOARD_FAB2_LIB.BASEBOARD_FAB2(SCH_1):PAGE43_I272@DEV_DISCRETE.CAP_A(CHIPS)':
 'A': CDS_PINID='A';
NODE_NAME     C6T1 1
 '@BASEBOARD_FAB2_LIB.BASEBOARD_FAB2(SCH_1):PAGE44_I2@DEV_DISCRETE.CAP_A(CHIPS)':
 'A': CDS_PINID='A';
NODE_NAME     J6T1 146
 '@BASEBOARD_FAB2_LIB.BASEBOARD_FAB2(SCH_1):PAGE44_I13@MSTR_SCONN.SCONN288_H44441003(CHIPS)':
 'VREFCA': CDS_PINID='VREFCA';
NODE_NAME     R4F5 1
 '@BASEBOARD_FAB2_LIB.BASEBOARD_FAB2(SCH_1):PAGE98_I4@MSTR_DISCRETE.RES(CHIPS)':
 'A': CDS_PINID='A';
NODE_NAME     R4F3 2
 '@BASEBOARD_FAB2_LIB.BASEBOARD_FAB2(SCH_1):PAGE98_I5@MSTR_DISCRETE.RES(CHIPS)':
 'B': CDS_PINID='B';
NODE_NAME     R4F4 2
 '@BASEBOARD_FAB2_LIB.BASEBOARD_FAB2(SCH_1):PAGE98_I36@MSTR_DISCRETE.RES(CHIPS)':
 'B': CDS_PINID='B';
NET_NAME
'M_B_ACT_N'
 '@BASEBOARD_FAB2_LIB.BASEBOARD_FAB2(SCH_1):M_B_ACT_N':
 C_SIGNAL='@baseboard_fab2_lib.baseboard_fab2(sch_1):m_b_act_n';
NODE_NAME     U5D1 T63
 '@BASEBOARD_FAB2_LIB.BASEBOARD_FAB2(SCH_1):PAGE24_I172@CHPSET_LIB.SKX_EXT_B(CHIPS)':
 'DDR1_ACT_N': CDS_PINID='DDR1_ACT_N';
NODE_NAME     J4G2 62
 '@BASEBOARD_FAB2_LIB.BASEBOARD_FAB2(SCH_1):PAGE45_I111@MSTR_SCONN.SCONN288_H44441004(CHIPS)':
 'ACT_N': CDS_PINID='ACT_N';
NODE_NAME     J6U1 62
 '@BASEBOARD_FAB2_LIB.BASEBOARD_FAB2(SCH_1):PAGE46_I14@MSTR_SCONN.SCONN288_H44441003(CHIPS)':
 'ACT_N': CDS_PINID='ACT_N';
NET_NAME
'M_B_ALERT_N'
 '@BASEBOARD_FAB2_LIB.BASEBOARD_FAB2(SCH_1):M_B_ALERT_N':
 C_SIGNAL='@baseboard_fab2_lib.baseboard_fab2(sch_1):m_b_alert_n';
NODE_NAME     U5D1 W62
 '@BASEBOARD_FAB2_LIB.BASEBOARD_FAB2(SCH_1):PAGE24_I172@CHPSET_LIB.SKX_EXT_B(CHIPS)':
 'DDR1_ALERT_N': CDS_PINID='DDR1_ALERT_N';
NODE_NAME     J4G2 208
 '@BASEBOARD_FAB2_LIB.BASEBOARD_FAB2(SCH_1):PAGE45_I111@MSTR_SCONN.SCONN288_H44441004(CHIPS)':
 'ALERT_N': CDS_PINID='ALERT_N';
NODE_NAME     J6U1 208
 '@BASEBOARD_FAB2_LIB.BASEBOARD_FAB2(SCH_1):PAGE46_I14@MSTR_SCONN.SCONN288_H44441003(CHIPS)':
 'ALERT_N': CDS_PINID='ALERT_N';
NET_NAME
'M_B_BA<0>'
 '@BASEBOARD_FAB2_LIB.BASEBOARD_FAB2(SCH_1):M_B_BA'<0>:
 C_SIGNAL='@baseboard_fab2_lib.baseboard_fab2(sch_1):m_b_ba(0)';
NODE_NAME     U5D1 T53
 '@BASEBOARD_FAB2_LIB.BASEBOARD_FAB2(SCH_1):PAGE24_I172@CHPSET_LIB.SKX_EXT_B(CHIPS)':
 'DDR1_BA'<0>: CDS_PINID='DDR1_BA(0)';
NODE_NAME     J4G2 81
 '@BASEBOARD_FAB2_LIB.BASEBOARD_FAB2(SCH_1):PAGE45_I111@MSTR_SCONN.SCONN288_H44441004(CHIPS)':
 'BA'<0>: CDS_PINID='BA(0)';
NODE_NAME     J6U1 81
 '@BASEBOARD_FAB2_LIB.BASEBOARD_FAB2(SCH_1):PAGE46_I14@MSTR_SCONN.SCONN288_H44441003(CHIPS)':
 'BA'<0>: CDS_PINID='BA(0)';
NET_NAME
'M_B_BA<1>'
 '@BASEBOARD_FAB2_LIB.BASEBOARD_FAB2(SCH_1):M_B_BA'<1>:
 C_SIGNAL='@baseboard_fab2_lib.baseboard_fab2(sch_1):m_b_ba(1)';
NODE_NAME     U5D1 K55
 '@BASEBOARD_FAB2_LIB.BASEBOARD_FAB2(SCH_1):PAGE24_I172@CHPSET_LIB.SKX_EXT_B(CHIPS)':
 'DDR1_BA'<1>: CDS_PINID='DDR1_BA(1)';
NODE_NAME     J4G2 224
 '@BASEBOARD_FAB2_LIB.BASEBOARD_FAB2(SCH_1):PAGE45_I111@MSTR_SCONN.SCONN288_H44441004(CHIPS)':
 'BA'<1>: CDS_PINID='BA(1)';
NODE_NAME     J6U1 224
 '@BASEBOARD_FAB2_LIB.BASEBOARD_FAB2(SCH_1):PAGE46_I14@MSTR_SCONN.SCONN288_H44441003(CHIPS)':
 'BA'<1>: CDS_PINID='BA(1)';
NET_NAME
'M_B_BG<0>'
 '@BASEBOARD_FAB2_LIB.BASEBOARD_FAB2(SCH_1):M_B_BG'<0>:
 C_SIGNAL='@baseboard_fab2_lib.baseboard_fab2(sch_1):m_b_bg(0)';
NODE_NAME     U5D1 M61
 '@BASEBOARD_FAB2_LIB.BASEBOARD_FAB2(SCH_1):PAGE24_I172@CHPSET_LIB.SKX_EXT_B(CHIPS)':
 'DDR1_BG'<0>: CDS_PINID='DDR1_BG(0)';
NODE_NAME     J4G2 63
 '@BASEBOARD_FAB2_LIB.BASEBOARD_FAB2(SCH_1):PAGE45_I111@MSTR_SCONN.SCONN288_H44441004(CHIPS)':
 'BG'<0>: CDS_PINID='BG(0)';
NODE_NAME     J6U1 63
 '@BASEBOARD_FAB2_LIB.BASEBOARD_FAB2(SCH_1):PAGE46_I14@MSTR_SCONN.SCONN288_H44441003(CHIPS)':
 'BG'<0>: CDS_PINID='BG(0)';
NET_NAME
'M_B_BG<1>'
 '@BASEBOARD_FAB2_LIB.BASEBOARD_FAB2(SCH_1):M_B_BG'<1>:
 C_SIGNAL='@baseboard_fab2_lib.baseboard_fab2(sch_1):m_b_bg(1)';
NODE_NAME     U5D1 N60
 '@BASEBOARD_FAB2_LIB.BASEBOARD_FAB2(SCH_1):PAGE24_I172@CHPSET_LIB.SKX_EXT_B(CHIPS)':
 'DDR1_BG'<1>: CDS_PINID='DDR1_BG(1)';
NODE_NAME     J4G2 207
 '@BASEBOARD_FAB2_LIB.BASEBOARD_FAB2(SCH_1):PAGE45_I111@MSTR_SCONN.SCONN288_H44441004(CHIPS)':
 'BG'<1>: CDS_PINID='BG(1)';
NODE_NAME     J6U1 207
 '@BASEBOARD_FAB2_LIB.BASEBOARD_FAB2(SCH_1):PAGE46_I14@MSTR_SCONN.SCONN288_H44441003(CHIPS)':
 'BG'<1>: CDS_PINID='BG(1)';
NET_NAME
'M_B_C<2>'
 '@BASEBOARD_FAB2_LIB.BASEBOARD_FAB2(SCH_1):M_B_C'<2>:
 C_SIGNAL='@baseboard_fab2_lib.baseboard_fab2(sch_1):m_b_c(2)';
NODE_NAME     U5D1 M47
 '@BASEBOARD_FAB2_LIB.BASEBOARD_FAB2(SCH_1):PAGE24_I172@CHPSET_LIB.SKX_EXT_B(CHIPS)':
 'DDR1_CID'<2>: CDS_PINID='DDR1_CID(2)';
NODE_NAME     J4G2 235
 '@BASEBOARD_FAB2_LIB.BASEBOARD_FAB2(SCH_1):PAGE45_I111@MSTR_SCONN.SCONN288_H44441004(CHIPS)':
 'C'<2>: CDS_PINID='C(2)';
NODE_NAME     J6U1 235
 '@BASEBOARD_FAB2_LIB.BASEBOARD_FAB2(SCH_1):PAGE46_I14@MSTR_SCONN.SCONN288_H44441003(CHIPS)':
 'C'<2>: CDS_PINID='C(2)';
NET_NAME
'M_B_CKE<0>'
 '@BASEBOARD_FAB2_LIB.BASEBOARD_FAB2(SCH_1):M_B_CKE'<0>:
 C_SIGNAL='@baseboard_fab2_lib.baseboard_fab2(sch_1):m_b_cke(0)';
NODE_NAME     U5D1 N62
 '@BASEBOARD_FAB2_LIB.BASEBOARD_FAB2(SCH_1):PAGE24_I172@CHPSET_LIB.SKX_EXT_B(CHIPS)':
 'DDR1_CKE'<0>: CDS_PINID='DDR1_CKE(0)';
NODE_NAME     J4G2 60
 '@BASEBOARD_FAB2_LIB.BASEBOARD_FAB2(SCH_1):PAGE45_I111@MSTR_SCONN.SCONN288_H44441004(CHIPS)':
 'CKE'<0>: CDS_PINID='CKE(0)';
NET_NAME
'M_B_CKE<1>'
 '@BASEBOARD_FAB2_LIB.BASEBOARD_FAB2(SCH_1):M_B_CKE'<1>:
 C_SIGNAL='@baseboard_fab2_lib.baseboard_fab2(sch_1):m_b_cke(1)';
NODE_NAME     U5D1 R64
 '@BASEBOARD_FAB2_LIB.BASEBOARD_FAB2(SCH_1):PAGE24_I172@CHPSET_LIB.SKX_EXT_B(CHIPS)':
 'DDR1_CKE'<1>: CDS_PINID='DDR1_CKE(1)';
NODE_NAME     J4G2 203
 '@BASEBOARD_FAB2_LIB.BASEBOARD_FAB2(SCH_1):PAGE45_I111@MSTR_SCONN.SCONN288_H44441004(CHIPS)':
 'CKE'<1>: CDS_PINID='CKE(1)';
NET_NAME
'M_B_CKE<2>'
 '@BASEBOARD_FAB2_LIB.BASEBOARD_FAB2(SCH_1):M_B_CKE'<2>:
 C_SIGNAL='@baseboard_fab2_lib.baseboard_fab2(sch_1):m_b_cke(2)';
NODE_NAME     U5D1 K63
 '@BASEBOARD_FAB2_LIB.BASEBOARD_FAB2(SCH_1):PAGE24_I172@CHPSET_LIB.SKX_EXT_B(CHIPS)':
 'DDR1_CKE'<2>: CDS_PINID='DDR1_CKE(2)';
NODE_NAME     J6U1 60
 '@BASEBOARD_FAB2_LIB.BASEBOARD_FAB2(SCH_1):PAGE46_I14@MSTR_SCONN.SCONN288_H44441003(CHIPS)':
 'CKE'<0>: CDS_PINID='CKE(0)';
NET_NAME
'M_B_CKE<3>'
 '@BASEBOARD_FAB2_LIB.BASEBOARD_FAB2(SCH_1):M_B_CKE'<3>:
 C_SIGNAL='@baseboard_fab2_lib.baseboard_fab2(sch_1):m_b_cke(3)';
NODE_NAME     U5D1 L64
 '@BASEBOARD_FAB2_LIB.BASEBOARD_FAB2(SCH_1):PAGE24_I172@CHPSET_LIB.SKX_EXT_B(CHIPS)':
 'DDR1_CKE'<3>: CDS_PINID='DDR1_CKE(3)';
NODE_NAME     J6U1 203
 '@BASEBOARD_FAB2_LIB.BASEBOARD_FAB2(SCH_1):PAGE46_I14@MSTR_SCONN.SCONN288_H44441003(CHIPS)':
 'CKE'<1>: CDS_PINID='CKE(1)';
NET_NAME
'M_B_CLK_DN<0>'
 '@BASEBOARD_FAB2_LIB.BASEBOARD_FAB2(SCH_1):M_B_CLK_DN'<0>:
 C_SIGNAL='@baseboard_fab2_lib.baseboard_fab2(sch_1):m_b_clk_dn(0)';
NODE_NAME     U5D1 M53
 '@BASEBOARD_FAB2_LIB.BASEBOARD_FAB2(SCH_1):PAGE24_I172@CHPSET_LIB.SKX_EXT_B(CHIPS)':
 'DDR1_CLK_DN'<0>: CDS_PINID='DDR1_CLK_DN(0)';
NODE_NAME     J4G2 75
 '@BASEBOARD_FAB2_LIB.BASEBOARD_FAB2(SCH_1):PAGE45_I111@MSTR_SCONN.SCONN288_H44441004(CHIPS)':
 'CK0N': CDS_PINID='CK0N';
NET_NAME
'M_B_CLK_DN<1>'
 '@BASEBOARD_FAB2_LIB.BASEBOARD_FAB2(SCH_1):M_B_CLK_DN'<1>:
 C_SIGNAL='@baseboard_fab2_lib.baseboard_fab2(sch_1):m_b_clk_dn(1)';
NODE_NAME     U5D1 R54
 '@BASEBOARD_FAB2_LIB.BASEBOARD_FAB2(SCH_1):PAGE24_I172@CHPSET_LIB.SKX_EXT_B(CHIPS)':
 'DDR1_CLK_DN'<1>: CDS_PINID='DDR1_CLK_DN(1)';
NODE_NAME     J4G2 219
 '@BASEBOARD_FAB2_LIB.BASEBOARD_FAB2(SCH_1):PAGE45_I111@MSTR_SCONN.SCONN288_H44441004(CHIPS)':
 'CK1N': CDS_PINID='CK1N';
NET_NAME
'M_B_CLK_DN<2>'
 '@BASEBOARD_FAB2_LIB.BASEBOARD_FAB2(SCH_1):M_B_CLK_DN'<2>:
 C_SIGNAL='@baseboard_fab2_lib.baseboard_fab2(sch_1):m_b_clk_dn(2)';
NODE_NAME     U5D1 N56
 '@BASEBOARD_FAB2_LIB.BASEBOARD_FAB2(SCH_1):PAGE24_I172@CHPSET_LIB.SKX_EXT_B(CHIPS)':
 'DDR1_CLK_DN'<2>: CDS_PINID='DDR1_CLK_DN(2)';
NODE_NAME     J6U1 75
 '@BASEBOARD_FAB2_LIB.BASEBOARD_FAB2(SCH_1):PAGE46_I14@MSTR_SCONN.SCONN288_H44441003(CHIPS)':
 'CK0N': CDS_PINID='CK0N';
NET_NAME
'M_B_CLK_DN<3>'
 '@BASEBOARD_FAB2_LIB.BASEBOARD_FAB2(SCH_1):M_B_CLK_DN'<3>:
 C_SIGNAL='@baseboard_fab2_lib.baseboard_fab2(sch_1):m_b_clk_dn(3)';
NODE_NAME     U5D1 R56
 '@BASEBOARD_FAB2_LIB.BASEBOARD_FAB2(SCH_1):PAGE24_I172@CHPSET_LIB.SKX_EXT_B(CHIPS)':
 'DDR1_CLK_DN'<3>: CDS_PINID='DDR1_CLK_DN(3)';
NODE_NAME     J6U1 219
 '@BASEBOARD_FAB2_LIB.BASEBOARD_FAB2(SCH_1):PAGE46_I14@MSTR_SCONN.SCONN288_H44441003(CHIPS)':
 'CK1N': CDS_PINID='CK1N';
NET_NAME
'M_B_CLK_DP<0>'
 '@BASEBOARD_FAB2_LIB.BASEBOARD_FAB2(SCH_1):M_B_CLK_DP'<0>:
 C_SIGNAL='@baseboard_fab2_lib.baseboard_fab2(sch_1):m_b_clk_dp(0)';
NODE_NAME     U5D1 N54
 '@BASEBOARD_FAB2_LIB.BASEBOARD_FAB2(SCH_1):PAGE24_I172@CHPSET_LIB.SKX_EXT_B(CHIPS)':
 'DDR1_CLK_DP'<0>: CDS_PINID='DDR1_CLK_DP(0)';
NODE_NAME     J4G2 74
 '@BASEBOARD_FAB2_LIB.BASEBOARD_FAB2(SCH_1):PAGE45_I111@MSTR_SCONN.SCONN288_H44441004(CHIPS)':
 'CK0P': CDS_PINID='CK0P';
NET_NAME
'M_B_CLK_DP<1>'
 '@BASEBOARD_FAB2_LIB.BASEBOARD_FAB2(SCH_1):M_B_CLK_DP'<1>:
 C_SIGNAL='@baseboard_fab2_lib.baseboard_fab2(sch_1):m_b_clk_dp(1)';
NODE_NAME     U5D1 T55
 '@BASEBOARD_FAB2_LIB.BASEBOARD_FAB2(SCH_1):PAGE24_I172@CHPSET_LIB.SKX_EXT_B(CHIPS)':
 'DDR1_CLK_DP'<1>: CDS_PINID='DDR1_CLK_DP(1)';
NODE_NAME     J4G2 218
 '@BASEBOARD_FAB2_LIB.BASEBOARD_FAB2(SCH_1):PAGE45_I111@MSTR_SCONN.SCONN288_H44441004(CHIPS)':
 'CK1P': CDS_PINID='CK1P';
NET_NAME
'M_B_CLK_DP<2>'
 '@BASEBOARD_FAB2_LIB.BASEBOARD_FAB2(SCH_1):M_B_CLK_DP'<2>:
 C_SIGNAL='@baseboard_fab2_lib.baseboard_fab2(sch_1):m_b_clk_dp(2)';
NODE_NAME     U5D1 M57
 '@BASEBOARD_FAB2_LIB.BASEBOARD_FAB2(SCH_1):PAGE24_I172@CHPSET_LIB.SKX_EXT_B(CHIPS)':
 'DDR1_CLK_DP'<2>: CDS_PINID='DDR1_CLK_DP(2)';
NODE_NAME     J6U1 74
 '@BASEBOARD_FAB2_LIB.BASEBOARD_FAB2(SCH_1):PAGE46_I14@MSTR_SCONN.SCONN288_H44441003(CHIPS)':
 'CK0P': CDS_PINID='CK0P';
NET_NAME
'M_B_CLK_DP<3>'
 '@BASEBOARD_FAB2_LIB.BASEBOARD_FAB2(SCH_1):M_B_CLK_DP'<3>:
 C_SIGNAL='@baseboard_fab2_lib.baseboard_fab2(sch_1):m_b_clk_dp(3)';
NODE_NAME     U5D1 T57
 '@BASEBOARD_FAB2_LIB.BASEBOARD_FAB2(SCH_1):PAGE24_I172@CHPSET_LIB.SKX_EXT_B(CHIPS)':
 'DDR1_CLK_DP'<3>: CDS_PINID='DDR1_CLK_DP(3)';
NODE_NAME     J6U1 218
 '@BASEBOARD_FAB2_LIB.BASEBOARD_FAB2(SCH_1):PAGE46_I14@MSTR_SCONN.SCONN288_H44441003(CHIPS)':
 'CK1P': CDS_PINID='CK1P';
NET_NAME
'M_B_CPU_VREF'
 '@BASEBOARD_FAB2_LIB.BASEBOARD_FAB2(SCH_1):M_B_CPU_VREF':
 C_SIGNAL='@baseboard_fab2_lib.baseboard_fab2(sch_1):m_b_cpu_vref';
NODE_NAME     U5D1 AK63
 '@BASEBOARD_FAB2_LIB.BASEBOARD_FAB2(SCH_1):PAGE21_I259@CHPSET_LIB.SKX_EXT_B(CHIPS)':
 'DDR1_CAVREF': CDS_PINID='DDR1_CAVREF';
NODE_NAME     R4G1 1
 '@BASEBOARD_FAB2_LIB.BASEBOARD_FAB2(SCH_1):PAGE98_I42@MSTR_DISCRETE.RES(CHIPS)':
 'A': CDS_PINID='A';
NODE_NAME     C4G1 1
 '@BASEBOARD_FAB2_LIB.BASEBOARD_FAB2(SCH_1):PAGE98_I43@DEV_DISCRETE.CAP_A(CHIPS)':
 'A': CDS_PINID='A';
NET_NAME
'M_B_CS_N<0>'
 '@BASEBOARD_FAB2_LIB.BASEBOARD_FAB2(SCH_1):M_B_CS_N'<0>:
 C_SIGNAL='@baseboard_fab2_lib.baseboard_fab2(sch_1):m_b_cs_n(0)';
NODE_NAME     U5D1 K51
 '@BASEBOARD_FAB2_LIB.BASEBOARD_FAB2(SCH_1):PAGE24_I172@CHPSET_LIB.SKX_EXT_B(CHIPS)':
 'DDR1_CS_N'<0>: CDS_PINID='DDR1_CS_N(0)';
NODE_NAME     J4G2 84
 '@BASEBOARD_FAB2_LIB.BASEBOARD_FAB2(SCH_1):PAGE45_I111@MSTR_SCONN.SCONN288_H44441004(CHIPS)':
 'S0_N': CDS_PINID='S0_N';
NET_NAME
'M_B_CS_N<1>'
 '@BASEBOARD_FAB2_LIB.BASEBOARD_FAB2(SCH_1):M_B_CS_N'<1>:
 C_SIGNAL='@baseboard_fab2_lib.baseboard_fab2(sch_1):m_b_cs_n(1)';
NODE_NAME     U5D1 R50
 '@BASEBOARD_FAB2_LIB.BASEBOARD_FAB2(SCH_1):PAGE24_I172@CHPSET_LIB.SKX_EXT_B(CHIPS)':
 'DDR1_CS_N'<1>: CDS_PINID='DDR1_CS_N(1)';
NODE_NAME     J4G2 89
 '@BASEBOARD_FAB2_LIB.BASEBOARD_FAB2(SCH_1):PAGE45_I111@MSTR_SCONN.SCONN288_H44441004(CHIPS)':
 'S1_N': CDS_PINID='S1_N';
NET_NAME
'M_B_CS_N<2>'
 '@BASEBOARD_FAB2_LIB.BASEBOARD_FAB2(SCH_1):M_B_CS_N'<2>:
 C_SIGNAL='@baseboard_fab2_lib.baseboard_fab2(sch_1):m_b_cs_n(2)';
NODE_NAME     U5D1 N46
 '@BASEBOARD_FAB2_LIB.BASEBOARD_FAB2(SCH_1):PAGE24_I172@CHPSET_LIB.SKX_EXT_B(CHIPS)':
 'DDR1_CS_N'<2>: CDS_PINID='DDR1_CS_N(2)';
NODE_NAME     J4G2 93
 '@BASEBOARD_FAB2_LIB.BASEBOARD_FAB2(SCH_1):PAGE45_I111@MSTR_SCONN.SCONN288_H44441004(CHIPS)':
 'S2_N_C'<0>: CDS_PINID='S2_N_C(0)';
NET_NAME
'M_B_CS_N<3>'
 '@BASEBOARD_FAB2_LIB.BASEBOARD_FAB2(SCH_1):M_B_CS_N'<3>:
 C_SIGNAL='@baseboard_fab2_lib.baseboard_fab2(sch_1):m_b_cs_n(3)';
NODE_NAME     U5D1 V47
 '@BASEBOARD_FAB2_LIB.BASEBOARD_FAB2(SCH_1):PAGE24_I172@CHPSET_LIB.SKX_EXT_B(CHIPS)':
 'DDR1_CS_N'<3>: CDS_PINID='DDR1_CS_N(3)';
NODE_NAME     J4G2 237
 '@BASEBOARD_FAB2_LIB.BASEBOARD_FAB2(SCH_1):PAGE45_I111@MSTR_SCONN.SCONN288_H44441004(CHIPS)':
 'S3_N_C'<1>: CDS_PINID='S3_N_C(1)';
NET_NAME
'M_B_CS_N<4>'
 '@BASEBOARD_FAB2_LIB.BASEBOARD_FAB2(SCH_1):M_B_CS_N'<4>:
 C_SIGNAL='@baseboard_fab2_lib.baseboard_fab2(sch_1):m_b_cs_n(4)';
NODE_NAME     U5D1 J50
 '@BASEBOARD_FAB2_LIB.BASEBOARD_FAB2(SCH_1):PAGE24_I172@CHPSET_LIB.SKX_EXT_B(CHIPS)':
 'DDR1_CS_N'<4>: CDS_PINID='DDR1_CS_N(4)';
NODE_NAME     J6U1 84
 '@BASEBOARD_FAB2_LIB.BASEBOARD_FAB2(SCH_1):PAGE46_I14@MSTR_SCONN.SCONN288_H44441003(CHIPS)':
 'S0_N': CDS_PINID='S0_N';
NET_NAME
'M_B_CS_N<5>'
 '@BASEBOARD_FAB2_LIB.BASEBOARD_FAB2(SCH_1):M_B_CS_N'<5>:
 C_SIGNAL='@baseboard_fab2_lib.baseboard_fab2(sch_1):m_b_cs_n(5)';
NODE_NAME     U5D1 T49
 '@BASEBOARD_FAB2_LIB.BASEBOARD_FAB2(SCH_1):PAGE24_I172@CHPSET_LIB.SKX_EXT_B(CHIPS)':
 'DDR1_CS_N'<5>: CDS_PINID='DDR1_CS_N(5)';
NODE_NAME     J6U1 89
 '@BASEBOARD_FAB2_LIB.BASEBOARD_FAB2(SCH_1):PAGE46_I14@MSTR_SCONN.SCONN288_H44441003(CHIPS)':
 'S1_N': CDS_PINID='S1_N';
NET_NAME
'M_B_CS_N<6>'
 '@BASEBOARD_FAB2_LIB.BASEBOARD_FAB2(SCH_1):M_B_CS_N'<6>:
 C_SIGNAL='@baseboard_fab2_lib.baseboard_fab2(sch_1):m_b_cs_n(6)';
NODE_NAME     U5D1 M45
 '@BASEBOARD_FAB2_LIB.BASEBOARD_FAB2(SCH_1):PAGE24_I172@CHPSET_LIB.SKX_EXT_B(CHIPS)':
 'DDR1_CS_N'<6>: CDS_PINID='DDR1_CS_N(6)';
NODE_NAME     J6U1 93
 '@BASEBOARD_FAB2_LIB.BASEBOARD_FAB2(SCH_1):PAGE46_I14@MSTR_SCONN.SCONN288_H44441003(CHIPS)':
 'S2_N_C'<0>: CDS_PINID='S2_N_C(0)';
NET_NAME
'M_B_CS_N<7>'
 '@BASEBOARD_FAB2_LIB.BASEBOARD_FAB2(SCH_1):M_B_CS_N'<7>:
 C_SIGNAL='@baseboard_fab2_lib.baseboard_fab2(sch_1):m_b_cs_n(7)';
NODE_NAME     U5D1 R46
 '@BASEBOARD_FAB2_LIB.BASEBOARD_FAB2(SCH_1):PAGE24_I172@CHPSET_LIB.SKX_EXT_B(CHIPS)':
 'DDR1_CS_N'<7>: CDS_PINID='DDR1_CS_N(7)';
NODE_NAME     J6U1 237
 '@BASEBOARD_FAB2_LIB.BASEBOARD_FAB2(SCH_1):PAGE46_I14@MSTR_SCONN.SCONN288_H44441003(CHIPS)':
 'S3_N_C'<1>: CDS_PINID='S3_N_C(1)';
NET_NAME
'M_B_DQ<0>'
 '@BASEBOARD_FAB2_LIB.BASEBOARD_FAB2(SCH_1):M_B_DQ'<0>:
 C_SIGNAL='@baseboard_fab2_lib.baseboard_fab2(sch_1):m_b_dq(0)';
NODE_NAME     U5D1 AV81
 '@BASEBOARD_FAB2_LIB.BASEBOARD_FAB2(SCH_1):PAGE24_I172@CHPSET_LIB.SKX_EXT_B(CHIPS)':
 'DDR1_DQ'<0>: CDS_PINID='DDR1_DQ(0)';
NODE_NAME     J4G2 150
 '@BASEBOARD_FAB2_LIB.BASEBOARD_FAB2(SCH_1):PAGE45_I111@MSTR_SCONN.SCONN288_H44441004(CHIPS)':
 'DQ'<1>: CDS_PINID='DQ(1)';
NODE_NAME     J6U1 5
 '@BASEBOARD_FAB2_LIB.BASEBOARD_FAB2(SCH_1):PAGE46_I14@MSTR_SCONN.SCONN288_H44441003(CHIPS)':
 'DQ'<0>: CDS_PINID='DQ(0)';
NET_NAME
'M_B_DQ<10>'
 '@BASEBOARD_FAB2_LIB.BASEBOARD_FAB2(SCH_1):M_B_DQ'<10>:
 C_SIGNAL='@baseboard_fab2_lib.baseboard_fab2(sch_1):m_b_dq(10)';
NODE_NAME     U5D1 AC82
 '@BASEBOARD_FAB2_LIB.BASEBOARD_FAB2(SCH_1):PAGE24_I172@CHPSET_LIB.SKX_EXT_B(CHIPS)':
 'DDR1_DQ'<10>: CDS_PINID='DDR1_DQ(10)';
NODE_NAME     J4G2 168
 '@BASEBOARD_FAB2_LIB.BASEBOARD_FAB2(SCH_1):PAGE45_I111@MSTR_SCONN.SCONN288_H44441004(CHIPS)':
 'DQ'<11>: CDS_PINID='DQ(11)';
NODE_NAME     J6U1 23
 '@BASEBOARD_FAB2_LIB.BASEBOARD_FAB2(SCH_1):PAGE46_I14@MSTR_SCONN.SCONN288_H44441003(CHIPS)':
 'DQ'<10>: CDS_PINID='DQ(10)';
NET_NAME
'M_B_DQ<11>'
 '@BASEBOARD_FAB2_LIB.BASEBOARD_FAB2(SCH_1):M_B_DQ'<11>:
 C_SIGNAL='@baseboard_fab2_lib.baseboard_fab2(sch_1):m_b_dq(11)';
NODE_NAME     U5D1 AB81
 '@BASEBOARD_FAB2_LIB.BASEBOARD_FAB2(SCH_1):PAGE24_I172@CHPSET_LIB.SKX_EXT_B(CHIPS)':
 'DDR1_DQ'<11>: CDS_PINID='DDR1_DQ(11)';
NODE_NAME     J4G2 23
 '@BASEBOARD_FAB2_LIB.BASEBOARD_FAB2(SCH_1):PAGE45_I111@MSTR_SCONN.SCONN288_H44441004(CHIPS)':
 'DQ'<10>: CDS_PINID='DQ(10)';
NODE_NAME     J6U1 168
 '@BASEBOARD_FAB2_LIB.BASEBOARD_FAB2(SCH_1):PAGE46_I14@MSTR_SCONN.SCONN288_H44441003(CHIPS)':
 'DQ'<11>: CDS_PINID='DQ(11)';
NET_NAME
'M_B_DQ<12>'
 '@BASEBOARD_FAB2_LIB.BASEBOARD_FAB2(SCH_1):M_B_DQ'<12>:
 C_SIGNAL='@baseboard_fab2_lib.baseboard_fab2(sch_1):m_b_dq(12)';
NODE_NAME     U5D1 AJ80
 '@BASEBOARD_FAB2_LIB.BASEBOARD_FAB2(SCH_1):PAGE24_I172@CHPSET_LIB.SKX_EXT_B(CHIPS)':
 'DDR1_DQ'<12>: CDS_PINID='DDR1_DQ(12)';
NODE_NAME     J4G2 159
 '@BASEBOARD_FAB2_LIB.BASEBOARD_FAB2(SCH_1):PAGE45_I111@MSTR_SCONN.SCONN288_H44441004(CHIPS)':
 'DQ'<13>: CDS_PINID='DQ(13)';
NODE_NAME     J6U1 14
 '@BASEBOARD_FAB2_LIB.BASEBOARD_FAB2(SCH_1):PAGE46_I14@MSTR_SCONN.SCONN288_H44441003(CHIPS)':
 'DQ'<12>: CDS_PINID='DQ(12)';
NET_NAME
'M_B_DQ<13>'
 '@BASEBOARD_FAB2_LIB.BASEBOARD_FAB2(SCH_1):M_B_DQ'<13>:
 C_SIGNAL='@baseboard_fab2_lib.baseboard_fab2(sch_1):m_b_dq(13)';
NODE_NAME     U5D1 AH79
 '@BASEBOARD_FAB2_LIB.BASEBOARD_FAB2(SCH_1):PAGE24_I172@CHPSET_LIB.SKX_EXT_B(CHIPS)':
 'DDR1_DQ'<13>: CDS_PINID='DDR1_DQ(13)';
NODE_NAME     J4G2 14
 '@BASEBOARD_FAB2_LIB.BASEBOARD_FAB2(SCH_1):PAGE45_I111@MSTR_SCONN.SCONN288_H44441004(CHIPS)':
 'DQ'<12>: CDS_PINID='DQ(12)';
NODE_NAME     J6U1 159
 '@BASEBOARD_FAB2_LIB.BASEBOARD_FAB2(SCH_1):PAGE46_I14@MSTR_SCONN.SCONN288_H44441003(CHIPS)':
 'DQ'<13>: CDS_PINID='DQ(13)';
NET_NAME
'M_B_DQ<14>'
 '@BASEBOARD_FAB2_LIB.BASEBOARD_FAB2(SCH_1):M_B_DQ'<14>:
 C_SIGNAL='@baseboard_fab2_lib.baseboard_fab2(sch_1):m_b_dq(14)';
NODE_NAME     U5D1 AE82
 '@BASEBOARD_FAB2_LIB.BASEBOARD_FAB2(SCH_1):PAGE24_I172@CHPSET_LIB.SKX_EXT_B(CHIPS)':
 'DDR1_DQ'<14>: CDS_PINID='DDR1_DQ(14)';
NODE_NAME     J4G2 166
 '@BASEBOARD_FAB2_LIB.BASEBOARD_FAB2(SCH_1):PAGE45_I111@MSTR_SCONN.SCONN288_H44441004(CHIPS)':
 'DQ'<15>: CDS_PINID='DQ(15)';
NODE_NAME     J6U1 21
 '@BASEBOARD_FAB2_LIB.BASEBOARD_FAB2(SCH_1):PAGE46_I14@MSTR_SCONN.SCONN288_H44441003(CHIPS)':
 'DQ'<14>: CDS_PINID='DQ(14)';
NET_NAME
'M_B_DQ<15>'
 '@BASEBOARD_FAB2_LIB.BASEBOARD_FAB2(SCH_1):M_B_DQ'<15>:
 C_SIGNAL='@baseboard_fab2_lib.baseboard_fab2(sch_1):m_b_dq(15)';
NODE_NAME     U5D1 AC80
 '@BASEBOARD_FAB2_LIB.BASEBOARD_FAB2(SCH_1):PAGE24_I172@CHPSET_LIB.SKX_EXT_B(CHIPS)':
 'DDR1_DQ'<15>: CDS_PINID='DDR1_DQ(15)';
NODE_NAME     J4G2 21
 '@BASEBOARD_FAB2_LIB.BASEBOARD_FAB2(SCH_1):PAGE45_I111@MSTR_SCONN.SCONN288_H44441004(CHIPS)':
 'DQ'<14>: CDS_PINID='DQ(14)';
NODE_NAME     J6U1 166
 '@BASEBOARD_FAB2_LIB.BASEBOARD_FAB2(SCH_1):PAGE46_I14@MSTR_SCONN.SCONN288_H44441003(CHIPS)':
 'DQ'<15>: CDS_PINID='DQ(15)';
NET_NAME
'M_B_DQ<16>'
 '@BASEBOARD_FAB2_LIB.BASEBOARD_FAB2(SCH_1):M_B_DQ'<16>:
 C_SIGNAL='@baseboard_fab2_lib.baseboard_fab2(sch_1):m_b_dq(16)';
NODE_NAME     U5D1 E80
 '@BASEBOARD_FAB2_LIB.BASEBOARD_FAB2(SCH_1):PAGE24_I172@CHPSET_LIB.SKX_EXT_B(CHIPS)':
 'DDR1_DQ'<16>: CDS_PINID='DDR1_DQ(16)';
NODE_NAME     J4G2 172
 '@BASEBOARD_FAB2_LIB.BASEBOARD_FAB2(SCH_1):PAGE45_I111@MSTR_SCONN.SCONN288_H44441004(CHIPS)':
 'DQ'<17>: CDS_PINID='DQ(17)';
NODE_NAME     J6U1 27
 '@BASEBOARD_FAB2_LIB.BASEBOARD_FAB2(SCH_1):PAGE46_I14@MSTR_SCONN.SCONN288_H44441003(CHIPS)':
 'DQ'<16>: CDS_PINID='DQ(16)';
NET_NAME
'M_B_DQ<17>'
 '@BASEBOARD_FAB2_LIB.BASEBOARD_FAB2(SCH_1):M_B_DQ'<17>:
 C_SIGNAL='@baseboard_fab2_lib.baseboard_fab2(sch_1):m_b_dq(17)';
NODE_NAME     U5D1 J80
 '@BASEBOARD_FAB2_LIB.BASEBOARD_FAB2(SCH_1):PAGE24_I172@CHPSET_LIB.SKX_EXT_B(CHIPS)':
 'DDR1_DQ'<17>: CDS_PINID='DDR1_DQ(17)';
NODE_NAME     J4G2 27
 '@BASEBOARD_FAB2_LIB.BASEBOARD_FAB2(SCH_1):PAGE45_I111@MSTR_SCONN.SCONN288_H44441004(CHIPS)':
 'DQ'<16>: CDS_PINID='DQ(16)';
NODE_NAME     J6U1 172
 '@BASEBOARD_FAB2_LIB.BASEBOARD_FAB2(SCH_1):PAGE46_I14@MSTR_SCONN.SCONN288_H44441003(CHIPS)':
 'DQ'<17>: CDS_PINID='DQ(17)';
NET_NAME
'M_B_DQ<18>'
 '@BASEBOARD_FAB2_LIB.BASEBOARD_FAB2(SCH_1):M_B_DQ'<18>:
 C_SIGNAL='@baseboard_fab2_lib.baseboard_fab2(sch_1):m_b_dq(18)';
NODE_NAME     U5D1 F77
 '@BASEBOARD_FAB2_LIB.BASEBOARD_FAB2(SCH_1):PAGE24_I172@CHPSET_LIB.SKX_EXT_B(CHIPS)':
 'DDR1_DQ'<18>: CDS_PINID='DDR1_DQ(18)';
NODE_NAME     J4G2 179
 '@BASEBOARD_FAB2_LIB.BASEBOARD_FAB2(SCH_1):PAGE45_I111@MSTR_SCONN.SCONN288_H44441004(CHIPS)':
 'DQ'<19>: CDS_PINID='DQ(19)';
NODE_NAME     J6U1 34
 '@BASEBOARD_FAB2_LIB.BASEBOARD_FAB2(SCH_1):PAGE46_I14@MSTR_SCONN.SCONN288_H44441003(CHIPS)':
 'DQ'<18>: CDS_PINID='DQ(18)';
NET_NAME
'M_B_DQ<19>'
 '@BASEBOARD_FAB2_LIB.BASEBOARD_FAB2(SCH_1):M_B_DQ'<19>:
 C_SIGNAL='@baseboard_fab2_lib.baseboard_fab2(sch_1):m_b_dq(19)';
NODE_NAME     U5D1 H77
 '@BASEBOARD_FAB2_LIB.BASEBOARD_FAB2(SCH_1):PAGE24_I172@CHPSET_LIB.SKX_EXT_B(CHIPS)':
 'DDR1_DQ'<19>: CDS_PINID='DDR1_DQ(19)';
NODE_NAME     J4G2 34
 '@BASEBOARD_FAB2_LIB.BASEBOARD_FAB2(SCH_1):PAGE45_I111@MSTR_SCONN.SCONN288_H44441004(CHIPS)':
 'DQ'<18>: CDS_PINID='DQ(18)';
NODE_NAME     J6U1 179
 '@BASEBOARD_FAB2_LIB.BASEBOARD_FAB2(SCH_1):PAGE46_I14@MSTR_SCONN.SCONN288_H44441003(CHIPS)':
 'DQ'<19>: CDS_PINID='DQ(19)';
NET_NAME
'M_B_DQ<1>'
 '@BASEBOARD_FAB2_LIB.BASEBOARD_FAB2(SCH_1):M_B_DQ'<1>:
 C_SIGNAL='@baseboard_fab2_lib.baseboard_fab2(sch_1):m_b_dq(1)';
NODE_NAME     U5D1 AT79
 '@BASEBOARD_FAB2_LIB.BASEBOARD_FAB2(SCH_1):PAGE24_I172@CHPSET_LIB.SKX_EXT_B(CHIPS)':
 'DDR1_DQ'<1>: CDS_PINID='DDR1_DQ(1)';
NODE_NAME     J4G2 5
 '@BASEBOARD_FAB2_LIB.BASEBOARD_FAB2(SCH_1):PAGE45_I111@MSTR_SCONN.SCONN288_H44441004(CHIPS)':
 'DQ'<0>: CDS_PINID='DQ(0)';
NODE_NAME     J6U1 150
 '@BASEBOARD_FAB2_LIB.BASEBOARD_FAB2(SCH_1):PAGE46_I14@MSTR_SCONN.SCONN288_H44441003(CHIPS)':
 'DQ'<1>: CDS_PINID='DQ(1)';
NET_NAME
'M_B_DQ<20>'
 '@BASEBOARD_FAB2_LIB.BASEBOARD_FAB2(SCH_1):M_B_DQ'<20>:
 C_SIGNAL='@baseboard_fab2_lib.baseboard_fab2(sch_1):m_b_dq(20)';
NODE_NAME     U5D1 F81
 '@BASEBOARD_FAB2_LIB.BASEBOARD_FAB2(SCH_1):PAGE24_I172@CHPSET_LIB.SKX_EXT_B(CHIPS)':
 'DDR1_DQ'<20>: CDS_PINID='DDR1_DQ(20)';
NODE_NAME     J4G2 170
 '@BASEBOARD_FAB2_LIB.BASEBOARD_FAB2(SCH_1):PAGE45_I111@MSTR_SCONN.SCONN288_H44441004(CHIPS)':
 'DQ'<21>: CDS_PINID='DQ(21)';
NODE_NAME     J6U1 25
 '@BASEBOARD_FAB2_LIB.BASEBOARD_FAB2(SCH_1):PAGE46_I14@MSTR_SCONN.SCONN288_H44441003(CHIPS)':
 'DQ'<20>: CDS_PINID='DQ(20)';
NET_NAME
'M_B_DQ<21>'
 '@BASEBOARD_FAB2_LIB.BASEBOARD_FAB2(SCH_1):M_B_DQ'<21>:
 C_SIGNAL='@baseboard_fab2_lib.baseboard_fab2(sch_1):m_b_dq(21)';
NODE_NAME     U5D1 H81
 '@BASEBOARD_FAB2_LIB.BASEBOARD_FAB2(SCH_1):PAGE24_I172@CHPSET_LIB.SKX_EXT_B(CHIPS)':
 'DDR1_DQ'<21>: CDS_PINID='DDR1_DQ(21)';
NODE_NAME     J4G2 25
 '@BASEBOARD_FAB2_LIB.BASEBOARD_FAB2(SCH_1):PAGE45_I111@MSTR_SCONN.SCONN288_H44441004(CHIPS)':
 'DQ'<20>: CDS_PINID='DQ(20)';
NODE_NAME     J6U1 170
 '@BASEBOARD_FAB2_LIB.BASEBOARD_FAB2(SCH_1):PAGE46_I14@MSTR_SCONN.SCONN288_H44441003(CHIPS)':
 'DQ'<21>: CDS_PINID='DQ(21)';
NET_NAME
'M_B_DQ<22>'
 '@BASEBOARD_FAB2_LIB.BASEBOARD_FAB2(SCH_1):M_B_DQ'<22>:
 C_SIGNAL='@baseboard_fab2_lib.baseboard_fab2(sch_1):m_b_dq(22)';
NODE_NAME     U5D1 E78
 '@BASEBOARD_FAB2_LIB.BASEBOARD_FAB2(SCH_1):PAGE24_I172@CHPSET_LIB.SKX_EXT_B(CHIPS)':
 'DDR1_DQ'<22>: CDS_PINID='DDR1_DQ(22)';
NODE_NAME     J4G2 177
 '@BASEBOARD_FAB2_LIB.BASEBOARD_FAB2(SCH_1):PAGE45_I111@MSTR_SCONN.SCONN288_H44441004(CHIPS)':
 'DQ'<23>: CDS_PINID='DQ(23)';
NODE_NAME     J6U1 32
 '@BASEBOARD_FAB2_LIB.BASEBOARD_FAB2(SCH_1):PAGE46_I14@MSTR_SCONN.SCONN288_H44441003(CHIPS)':
 'DQ'<22>: CDS_PINID='DQ(22)';
NET_NAME
'M_B_DQ<23>'
 '@BASEBOARD_FAB2_LIB.BASEBOARD_FAB2(SCH_1):M_B_DQ'<23>:
 C_SIGNAL='@baseboard_fab2_lib.baseboard_fab2(sch_1):m_b_dq(23)';
NODE_NAME     U5D1 J78
 '@BASEBOARD_FAB2_LIB.BASEBOARD_FAB2(SCH_1):PAGE24_I172@CHPSET_LIB.SKX_EXT_B(CHIPS)':
 'DDR1_DQ'<23>: CDS_PINID='DDR1_DQ(23)';
NODE_NAME     J4G2 32
 '@BASEBOARD_FAB2_LIB.BASEBOARD_FAB2(SCH_1):PAGE45_I111@MSTR_SCONN.SCONN288_H44441004(CHIPS)':
 'DQ'<22>: CDS_PINID='DQ(22)';
NODE_NAME     J6U1 177
 '@BASEBOARD_FAB2_LIB.BASEBOARD_FAB2(SCH_1):PAGE46_I14@MSTR_SCONN.SCONN288_H44441003(CHIPS)':
 'DQ'<23>: CDS_PINID='DQ(23)';
NET_NAME
'M_B_DQ<24>'
 '@BASEBOARD_FAB2_LIB.BASEBOARD_FAB2(SCH_1):M_B_DQ'<24>:
 C_SIGNAL='@baseboard_fab2_lib.baseboard_fab2(sch_1):m_b_dq(24)';
NODE_NAME     U5D1 D75
 '@BASEBOARD_FAB2_LIB.BASEBOARD_FAB2(SCH_1):PAGE24_I172@CHPSET_LIB.SKX_EXT_B(CHIPS)':
 'DDR1_DQ'<24>: CDS_PINID='DDR1_DQ(24)';
NODE_NAME     J4G2 183
 '@BASEBOARD_FAB2_LIB.BASEBOARD_FAB2(SCH_1):PAGE45_I111@MSTR_SCONN.SCONN288_H44441004(CHIPS)':
 'DQ'<25>: CDS_PINID='DQ(25)';
NODE_NAME     J6U1 38
 '@BASEBOARD_FAB2_LIB.BASEBOARD_FAB2(SCH_1):PAGE46_I14@MSTR_SCONN.SCONN288_H44441003(CHIPS)':
 'DQ'<24>: CDS_PINID='DQ(24)';
NET_NAME
'M_B_DQ<25>'
 '@BASEBOARD_FAB2_LIB.BASEBOARD_FAB2(SCH_1):M_B_DQ'<25>:
 C_SIGNAL='@baseboard_fab2_lib.baseboard_fab2(sch_1):m_b_dq(25)';
NODE_NAME     U5D1 C74
 '@BASEBOARD_FAB2_LIB.BASEBOARD_FAB2(SCH_1):PAGE24_I172@CHPSET_LIB.SKX_EXT_B(CHIPS)':
 'DDR1_DQ'<25>: CDS_PINID='DDR1_DQ(25)';
NODE_NAME     J4G2 38
 '@BASEBOARD_FAB2_LIB.BASEBOARD_FAB2(SCH_1):PAGE45_I111@MSTR_SCONN.SCONN288_H44441004(CHIPS)':
 'DQ'<24>: CDS_PINID='DQ(24)';
NODE_NAME     J6U1 183
 '@BASEBOARD_FAB2_LIB.BASEBOARD_FAB2(SCH_1):PAGE46_I14@MSTR_SCONN.SCONN288_H44441003(CHIPS)':
 'DQ'<25>: CDS_PINID='DQ(25)';
NET_NAME
'M_B_DQ<26>'
 '@BASEBOARD_FAB2_LIB.BASEBOARD_FAB2(SCH_1):M_B_DQ'<26>:
 C_SIGNAL='@baseboard_fab2_lib.baseboard_fab2(sch_1):m_b_dq(26)';
NODE_NAME     U5D1 D71
 '@BASEBOARD_FAB2_LIB.BASEBOARD_FAB2(SCH_1):PAGE24_I172@CHPSET_LIB.SKX_EXT_B(CHIPS)':
 'DDR1_DQ'<26>: CDS_PINID='DDR1_DQ(26)';
NODE_NAME     J4G2 190
 '@BASEBOARD_FAB2_LIB.BASEBOARD_FAB2(SCH_1):PAGE45_I111@MSTR_SCONN.SCONN288_H44441004(CHIPS)':
 'DQ'<27>: CDS_PINID='DQ(27)';
NODE_NAME     J6U1 45
 '@BASEBOARD_FAB2_LIB.BASEBOARD_FAB2(SCH_1):PAGE46_I14@MSTR_SCONN.SCONN288_H44441003(CHIPS)':
 'DQ'<26>: CDS_PINID='DQ(26)';
NET_NAME
'M_B_DQ<27>'
 '@BASEBOARD_FAB2_LIB.BASEBOARD_FAB2(SCH_1):M_B_DQ'<27>:
 C_SIGNAL='@baseboard_fab2_lib.baseboard_fab2(sch_1):m_b_dq(27)';
NODE_NAME     U5D1 F71
 '@BASEBOARD_FAB2_LIB.BASEBOARD_FAB2(SCH_1):PAGE24_I172@CHPSET_LIB.SKX_EXT_B(CHIPS)':
 'DDR1_DQ'<27>: CDS_PINID='DDR1_DQ(27)';
NODE_NAME     J4G2 45
 '@BASEBOARD_FAB2_LIB.BASEBOARD_FAB2(SCH_1):PAGE45_I111@MSTR_SCONN.SCONN288_H44441004(CHIPS)':
 'DQ'<26>: CDS_PINID='DQ(26)';
NODE_NAME     J6U1 190
 '@BASEBOARD_FAB2_LIB.BASEBOARD_FAB2(SCH_1):PAGE46_I14@MSTR_SCONN.SCONN288_H44441003(CHIPS)':
 'DQ'<27>: CDS_PINID='DQ(27)';
NET_NAME
'M_B_DQ<28>'
 '@BASEBOARD_FAB2_LIB.BASEBOARD_FAB2(SCH_1):M_B_DQ'<28>:
 C_SIGNAL='@baseboard_fab2_lib.baseboard_fab2(sch_1):m_b_dq(28)';
NODE_NAME     U5D1 F75
 '@BASEBOARD_FAB2_LIB.BASEBOARD_FAB2(SCH_1):PAGE24_I172@CHPSET_LIB.SKX_EXT_B(CHIPS)':
 'DDR1_DQ'<28>: CDS_PINID='DDR1_DQ(28)';
NODE_NAME     J4G2 181
 '@BASEBOARD_FAB2_LIB.BASEBOARD_FAB2(SCH_1):PAGE45_I111@MSTR_SCONN.SCONN288_H44441004(CHIPS)':
 'DQ'<29>: CDS_PINID='DQ(29)';
NODE_NAME     J6U1 36
 '@BASEBOARD_FAB2_LIB.BASEBOARD_FAB2(SCH_1):PAGE46_I14@MSTR_SCONN.SCONN288_H44441003(CHIPS)':
 'DQ'<28>: CDS_PINID='DQ(28)';
NET_NAME
'M_B_DQ<29>'
 '@BASEBOARD_FAB2_LIB.BASEBOARD_FAB2(SCH_1):M_B_DQ'<29>:
 C_SIGNAL='@baseboard_fab2_lib.baseboard_fab2(sch_1):m_b_dq(29)';
NODE_NAME     U5D1 G74
 '@BASEBOARD_FAB2_LIB.BASEBOARD_FAB2(SCH_1):PAGE24_I172@CHPSET_LIB.SKX_EXT_B(CHIPS)':
 'DDR1_DQ'<29>: CDS_PINID='DDR1_DQ(29)';
NODE_NAME     J4G2 36
 '@BASEBOARD_FAB2_LIB.BASEBOARD_FAB2(SCH_1):PAGE45_I111@MSTR_SCONN.SCONN288_H44441004(CHIPS)':
 'DQ'<28>: CDS_PINID='DQ(28)';
NODE_NAME     J6U1 181
 '@BASEBOARD_FAB2_LIB.BASEBOARD_FAB2(SCH_1):PAGE46_I14@MSTR_SCONN.SCONN288_H44441003(CHIPS)':
 'DQ'<29>: CDS_PINID='DQ(29)';
NET_NAME
'M_B_DQ<2>'
 '@BASEBOARD_FAB2_LIB.BASEBOARD_FAB2(SCH_1):M_B_DQ'<2>:
 C_SIGNAL='@baseboard_fab2_lib.baseboard_fab2(sch_1):m_b_dq(2)';
NODE_NAME     U5D1 AN82
 '@BASEBOARD_FAB2_LIB.BASEBOARD_FAB2(SCH_1):PAGE24_I172@CHPSET_LIB.SKX_EXT_B(CHIPS)':
 'DDR1_DQ'<2>: CDS_PINID='DDR1_DQ(2)';
NODE_NAME     J4G2 157
 '@BASEBOARD_FAB2_LIB.BASEBOARD_FAB2(SCH_1):PAGE45_I111@MSTR_SCONN.SCONN288_H44441004(CHIPS)':
 'DQ'<3>: CDS_PINID='DQ(3)';
NODE_NAME     J6U1 12
 '@BASEBOARD_FAB2_LIB.BASEBOARD_FAB2(SCH_1):PAGE46_I14@MSTR_SCONN.SCONN288_H44441003(CHIPS)':
 'DQ'<2>: CDS_PINID='DQ(2)';
NET_NAME
'M_B_DQ<30>'
 '@BASEBOARD_FAB2_LIB.BASEBOARD_FAB2(SCH_1):M_B_DQ'<30>:
 C_SIGNAL='@baseboard_fab2_lib.baseboard_fab2(sch_1):m_b_dq(30)';
NODE_NAME     U5D1 C72
 '@BASEBOARD_FAB2_LIB.BASEBOARD_FAB2(SCH_1):PAGE24_I172@CHPSET_LIB.SKX_EXT_B(CHIPS)':
 'DDR1_DQ'<30>: CDS_PINID='DDR1_DQ(30)';
NODE_NAME     J4G2 188
 '@BASEBOARD_FAB2_LIB.BASEBOARD_FAB2(SCH_1):PAGE45_I111@MSTR_SCONN.SCONN288_H44441004(CHIPS)':
 'DQ'<31>: CDS_PINID='DQ(31)';
NODE_NAME     J6U1 43
 '@BASEBOARD_FAB2_LIB.BASEBOARD_FAB2(SCH_1):PAGE46_I14@MSTR_SCONN.SCONN288_H44441003(CHIPS)':
 'DQ'<30>: CDS_PINID='DQ(30)';
NET_NAME
'M_B_DQ<31>'
 '@BASEBOARD_FAB2_LIB.BASEBOARD_FAB2(SCH_1):M_B_DQ'<31>:
 C_SIGNAL='@baseboard_fab2_lib.baseboard_fab2(sch_1):m_b_dq(31)';
NODE_NAME     U5D1 G72
 '@BASEBOARD_FAB2_LIB.BASEBOARD_FAB2(SCH_1):PAGE24_I172@CHPSET_LIB.SKX_EXT_B(CHIPS)':
 'DDR1_DQ'<31>: CDS_PINID='DDR1_DQ(31)';
NODE_NAME     J4G2 43
 '@BASEBOARD_FAB2_LIB.BASEBOARD_FAB2(SCH_1):PAGE45_I111@MSTR_SCONN.SCONN288_H44441004(CHIPS)':
 'DQ'<30>: CDS_PINID='DQ(30)';
NODE_NAME     J6U1 188
 '@BASEBOARD_FAB2_LIB.BASEBOARD_FAB2(SCH_1):PAGE46_I14@MSTR_SCONN.SCONN288_H44441003(CHIPS)':
 'DQ'<31>: CDS_PINID='DQ(31)';
NET_NAME
'M_B_DQ<32>'
 '@BASEBOARD_FAB2_LIB.BASEBOARD_FAB2(SCH_1):M_B_DQ'<32>:
 C_SIGNAL='@baseboard_fab2_lib.baseboard_fab2(sch_1):m_b_dq(32)';
NODE_NAME     U5D1 K43
 '@BASEBOARD_FAB2_LIB.BASEBOARD_FAB2(SCH_1):PAGE24_I172@CHPSET_LIB.SKX_EXT_B(CHIPS)':
 'DDR1_DQ'<32>: CDS_PINID='DDR1_DQ(32)';
NODE_NAME     J4G2 242
 '@BASEBOARD_FAB2_LIB.BASEBOARD_FAB2(SCH_1):PAGE45_I111@MSTR_SCONN.SCONN288_H44441004(CHIPS)':
 'DQ'<33>: CDS_PINID='DQ(33)';
NODE_NAME     J6U1 97
 '@BASEBOARD_FAB2_LIB.BASEBOARD_FAB2(SCH_1):PAGE46_I14@MSTR_SCONN.SCONN288_H44441003(CHIPS)':
 'DQ'<32>: CDS_PINID='DQ(32)';
NET_NAME
'M_B_DQ<33>'
 '@BASEBOARD_FAB2_LIB.BASEBOARD_FAB2(SCH_1):M_B_DQ'<33>:
 C_SIGNAL='@baseboard_fab2_lib.baseboard_fab2(sch_1):m_b_dq(33)';
NODE_NAME     U5D1 H43
 '@BASEBOARD_FAB2_LIB.BASEBOARD_FAB2(SCH_1):PAGE24_I172@CHPSET_LIB.SKX_EXT_B(CHIPS)':
 'DDR1_DQ'<33>: CDS_PINID='DDR1_DQ(33)';
NODE_NAME     J4G2 97
 '@BASEBOARD_FAB2_LIB.BASEBOARD_FAB2(SCH_1):PAGE45_I111@MSTR_SCONN.SCONN288_H44441004(CHIPS)':
 'DQ'<32>: CDS_PINID='DQ(32)';
NODE_NAME     J6U1 242
 '@BASEBOARD_FAB2_LIB.BASEBOARD_FAB2(SCH_1):PAGE46_I14@MSTR_SCONN.SCONN288_H44441003(CHIPS)':
 'DQ'<33>: CDS_PINID='DQ(33)';
NET_NAME
'M_B_DQ<34>'
 '@BASEBOARD_FAB2_LIB.BASEBOARD_FAB2(SCH_1):M_B_DQ'<34>:
 C_SIGNAL='@baseboard_fab2_lib.baseboard_fab2(sch_1):m_b_dq(34)';
NODE_NAME     U5D1 L40
 '@BASEBOARD_FAB2_LIB.BASEBOARD_FAB2(SCH_1):PAGE24_I172@CHPSET_LIB.SKX_EXT_B(CHIPS)':
 'DDR1_DQ'<34>: CDS_PINID='DDR1_DQ(34)';
NODE_NAME     J4G2 249
 '@BASEBOARD_FAB2_LIB.BASEBOARD_FAB2(SCH_1):PAGE45_I111@MSTR_SCONN.SCONN288_H44441004(CHIPS)':
 'DQ'<35>: CDS_PINID='DQ(35)';
NODE_NAME     J6U1 104
 '@BASEBOARD_FAB2_LIB.BASEBOARD_FAB2(SCH_1):PAGE46_I14@MSTR_SCONN.SCONN288_H44441003(CHIPS)':
 'DQ'<34>: CDS_PINID='DQ(34)';
NET_NAME
'M_B_DQ<35>'
 '@BASEBOARD_FAB2_LIB.BASEBOARD_FAB2(SCH_1):M_B_DQ'<35>:
 C_SIGNAL='@baseboard_fab2_lib.baseboard_fab2(sch_1):m_b_dq(35)';
NODE_NAME     U5D1 N40
 '@BASEBOARD_FAB2_LIB.BASEBOARD_FAB2(SCH_1):PAGE24_I172@CHPSET_LIB.SKX_EXT_B(CHIPS)':
 'DDR1_DQ'<35>: CDS_PINID='DDR1_DQ(35)';
NODE_NAME     J4G2 104
 '@BASEBOARD_FAB2_LIB.BASEBOARD_FAB2(SCH_1):PAGE45_I111@MSTR_SCONN.SCONN288_H44441004(CHIPS)':
 'DQ'<34>: CDS_PINID='DQ(34)';
NODE_NAME     J6U1 249
 '@BASEBOARD_FAB2_LIB.BASEBOARD_FAB2(SCH_1):PAGE46_I14@MSTR_SCONN.SCONN288_H44441003(CHIPS)':
 'DQ'<35>: CDS_PINID='DQ(35)';
NET_NAME
'M_B_DQ<36>'
 '@BASEBOARD_FAB2_LIB.BASEBOARD_FAB2(SCH_1):M_B_DQ'<36>:
 C_SIGNAL='@baseboard_fab2_lib.baseboard_fab2(sch_1):m_b_dq(36)';
NODE_NAME     U5D1 P43
 '@BASEBOARD_FAB2_LIB.BASEBOARD_FAB2(SCH_1):PAGE24_I172@CHPSET_LIB.SKX_EXT_B(CHIPS)':
 'DDR1_DQ'<36>: CDS_PINID='DDR1_DQ(36)';
NODE_NAME     J4G2 240
 '@BASEBOARD_FAB2_LIB.BASEBOARD_FAB2(SCH_1):PAGE45_I111@MSTR_SCONN.SCONN288_H44441004(CHIPS)':
 'DQ'<37>: CDS_PINID='DQ(37)';
NODE_NAME     J6U1 95
 '@BASEBOARD_FAB2_LIB.BASEBOARD_FAB2(SCH_1):PAGE46_I14@MSTR_SCONN.SCONN288_H44441003(CHIPS)':
 'DQ'<36>: CDS_PINID='DQ(36)';
NET_NAME
'M_B_DQ<37>'
 '@BASEBOARD_FAB2_LIB.BASEBOARD_FAB2(SCH_1):M_B_DQ'<37>:
 C_SIGNAL='@baseboard_fab2_lib.baseboard_fab2(sch_1):m_b_dq(37)';
NODE_NAME     U5D1 T43
 '@BASEBOARD_FAB2_LIB.BASEBOARD_FAB2(SCH_1):PAGE24_I172@CHPSET_LIB.SKX_EXT_B(CHIPS)':
 'DDR1_DQ'<37>: CDS_PINID='DDR1_DQ(37)';
NODE_NAME     J4G2 95
 '@BASEBOARD_FAB2_LIB.BASEBOARD_FAB2(SCH_1):PAGE45_I111@MSTR_SCONN.SCONN288_H44441004(CHIPS)':
 'DQ'<36>: CDS_PINID='DQ(36)';
NODE_NAME     J6U1 240
 '@BASEBOARD_FAB2_LIB.BASEBOARD_FAB2(SCH_1):PAGE46_I14@MSTR_SCONN.SCONN288_H44441003(CHIPS)':
 'DQ'<37>: CDS_PINID='DQ(37)';
NET_NAME
'M_B_DQ<38>'
 '@BASEBOARD_FAB2_LIB.BASEBOARD_FAB2(SCH_1):M_B_DQ'<38>:
 C_SIGNAL='@baseboard_fab2_lib.baseboard_fab2(sch_1):m_b_dq(38)';
NODE_NAME     U5D1 K41
 '@BASEBOARD_FAB2_LIB.BASEBOARD_FAB2(SCH_1):PAGE24_I172@CHPSET_LIB.SKX_EXT_B(CHIPS)':
 'DDR1_DQ'<38>: CDS_PINID='DDR1_DQ(38)';
NODE_NAME     J4G2 247
 '@BASEBOARD_FAB2_LIB.BASEBOARD_FAB2(SCH_1):PAGE45_I111@MSTR_SCONN.SCONN288_H44441004(CHIPS)':
 'DQ'<39>: CDS_PINID='DQ(39)';
NODE_NAME     J6U1 102
 '@BASEBOARD_FAB2_LIB.BASEBOARD_FAB2(SCH_1):PAGE46_I14@MSTR_SCONN.SCONN288_H44441003(CHIPS)':
 'DQ'<38>: CDS_PINID='DQ(38)';
NET_NAME
'M_B_DQ<39>'
 '@BASEBOARD_FAB2_LIB.BASEBOARD_FAB2(SCH_1):M_B_DQ'<39>:
 C_SIGNAL='@baseboard_fab2_lib.baseboard_fab2(sch_1):m_b_dq(39)';
NODE_NAME     U5D1 P41
 '@BASEBOARD_FAB2_LIB.BASEBOARD_FAB2(SCH_1):PAGE24_I172@CHPSET_LIB.SKX_EXT_B(CHIPS)':
 'DDR1_DQ'<39>: CDS_PINID='DDR1_DQ(39)';
NODE_NAME     J4G2 102
 '@BASEBOARD_FAB2_LIB.BASEBOARD_FAB2(SCH_1):PAGE45_I111@MSTR_SCONN.SCONN288_H44441004(CHIPS)':
 'DQ'<38>: CDS_PINID='DQ(38)';
NODE_NAME     J6U1 247
 '@BASEBOARD_FAB2_LIB.BASEBOARD_FAB2(SCH_1):PAGE46_I14@MSTR_SCONN.SCONN288_H44441003(CHIPS)':
 'DQ'<39>: CDS_PINID='DQ(39)';
NET_NAME
'M_B_DQ<3>'
 '@BASEBOARD_FAB2_LIB.BASEBOARD_FAB2(SCH_1):M_B_DQ'<3>:
 C_SIGNAL='@baseboard_fab2_lib.baseboard_fab2(sch_1):m_b_dq(3)';
NODE_NAME     U5D1 AM81
 '@BASEBOARD_FAB2_LIB.BASEBOARD_FAB2(SCH_1):PAGE24_I172@CHPSET_LIB.SKX_EXT_B(CHIPS)':
 'DDR1_DQ'<3>: CDS_PINID='DDR1_DQ(3)';
NODE_NAME     J4G2 12
 '@BASEBOARD_FAB2_LIB.BASEBOARD_FAB2(SCH_1):PAGE45_I111@MSTR_SCONN.SCONN288_H44441004(CHIPS)':
 'DQ'<2>: CDS_PINID='DQ(2)';
NODE_NAME     J6U1 157
 '@BASEBOARD_FAB2_LIB.BASEBOARD_FAB2(SCH_1):PAGE46_I14@MSTR_SCONN.SCONN288_H44441003(CHIPS)':
 'DQ'<3>: CDS_PINID='DQ(3)';
NET_NAME
'M_B_DQ<40>'
 '@BASEBOARD_FAB2_LIB.BASEBOARD_FAB2(SCH_1):M_B_DQ'<40>:
 C_SIGNAL='@baseboard_fab2_lib.baseboard_fab2(sch_1):m_b_dq(40)';
NODE_NAME     U5D1 C36
 '@BASEBOARD_FAB2_LIB.BASEBOARD_FAB2(SCH_1):PAGE24_I172@CHPSET_LIB.SKX_EXT_B(CHIPS)':
 'DDR1_DQ'<40>: CDS_PINID='DDR1_DQ(40)';
NODE_NAME     J4G2 253
 '@BASEBOARD_FAB2_LIB.BASEBOARD_FAB2(SCH_1):PAGE45_I111@MSTR_SCONN.SCONN288_H44441004(CHIPS)':
 'DQ'<41>: CDS_PINID='DQ(41)';
NODE_NAME     J6U1 108
 '@BASEBOARD_FAB2_LIB.BASEBOARD_FAB2(SCH_1):PAGE46_I14@MSTR_SCONN.SCONN288_H44441003(CHIPS)':
 'DQ'<40>: CDS_PINID='DQ(40)';
NET_NAME
'M_B_DQ<41>'
 '@BASEBOARD_FAB2_LIB.BASEBOARD_FAB2(SCH_1):M_B_DQ'<41>:
 C_SIGNAL='@baseboard_fab2_lib.baseboard_fab2(sch_1):m_b_dq(41)';
NODE_NAME     U5D1 B35
 '@BASEBOARD_FAB2_LIB.BASEBOARD_FAB2(SCH_1):PAGE24_I172@CHPSET_LIB.SKX_EXT_B(CHIPS)':
 'DDR1_DQ'<41>: CDS_PINID='DDR1_DQ(41)';
NODE_NAME     J4G2 108
 '@BASEBOARD_FAB2_LIB.BASEBOARD_FAB2(SCH_1):PAGE45_I111@MSTR_SCONN.SCONN288_H44441004(CHIPS)':
 'DQ'<40>: CDS_PINID='DQ(40)';
NODE_NAME     J6U1 253
 '@BASEBOARD_FAB2_LIB.BASEBOARD_FAB2(SCH_1):PAGE46_I14@MSTR_SCONN.SCONN288_H44441003(CHIPS)':
 'DQ'<41>: CDS_PINID='DQ(41)';
NET_NAME
'M_B_DQ<42>'
 '@BASEBOARD_FAB2_LIB.BASEBOARD_FAB2(SCH_1):M_B_DQ'<42>:
 C_SIGNAL='@baseboard_fab2_lib.baseboard_fab2(sch_1):m_b_dq(42)';
NODE_NAME     U5D1 C32
 '@BASEBOARD_FAB2_LIB.BASEBOARD_FAB2(SCH_1):PAGE24_I172@CHPSET_LIB.SKX_EXT_B(CHIPS)':
 'DDR1_DQ'<42>: CDS_PINID='DDR1_DQ(42)';
NODE_NAME     J4G2 260
 '@BASEBOARD_FAB2_LIB.BASEBOARD_FAB2(SCH_1):PAGE45_I111@MSTR_SCONN.SCONN288_H44441004(CHIPS)':
 'DQ'<43>: CDS_PINID='DQ(43)';
NODE_NAME     J6U1 115
 '@BASEBOARD_FAB2_LIB.BASEBOARD_FAB2(SCH_1):PAGE46_I14@MSTR_SCONN.SCONN288_H44441003(CHIPS)':
 'DQ'<42>: CDS_PINID='DQ(42)';
NET_NAME
'M_B_DQ<43>'
 '@BASEBOARD_FAB2_LIB.BASEBOARD_FAB2(SCH_1):M_B_DQ'<43>:
 C_SIGNAL='@baseboard_fab2_lib.baseboard_fab2(sch_1):m_b_dq(43)';
NODE_NAME     U5D1 E32
 '@BASEBOARD_FAB2_LIB.BASEBOARD_FAB2(SCH_1):PAGE24_I172@CHPSET_LIB.SKX_EXT_B(CHIPS)':
 'DDR1_DQ'<43>: CDS_PINID='DDR1_DQ(43)';
NODE_NAME     J4G2 115
 '@BASEBOARD_FAB2_LIB.BASEBOARD_FAB2(SCH_1):PAGE45_I111@MSTR_SCONN.SCONN288_H44441004(CHIPS)':
 'DQ'<42>: CDS_PINID='DQ(42)';
NODE_NAME     J6U1 260
 '@BASEBOARD_FAB2_LIB.BASEBOARD_FAB2(SCH_1):PAGE46_I14@MSTR_SCONN.SCONN288_H44441003(CHIPS)':
 'DQ'<43>: CDS_PINID='DQ(43)';
NET_NAME
'M_B_DQ<44>'
 '@BASEBOARD_FAB2_LIB.BASEBOARD_FAB2(SCH_1):M_B_DQ'<44>:
 C_SIGNAL='@baseboard_fab2_lib.baseboard_fab2(sch_1):m_b_dq(44)';
NODE_NAME     U5D1 E36
 '@BASEBOARD_FAB2_LIB.BASEBOARD_FAB2(SCH_1):PAGE24_I172@CHPSET_LIB.SKX_EXT_B(CHIPS)':
 'DDR1_DQ'<44>: CDS_PINID='DDR1_DQ(44)';
NODE_NAME     J4G2 251
 '@BASEBOARD_FAB2_LIB.BASEBOARD_FAB2(SCH_1):PAGE45_I111@MSTR_SCONN.SCONN288_H44441004(CHIPS)':
 'DQ'<45>: CDS_PINID='DQ(45)';
NODE_NAME     J6U1 106
 '@BASEBOARD_FAB2_LIB.BASEBOARD_FAB2(SCH_1):PAGE46_I14@MSTR_SCONN.SCONN288_H44441003(CHIPS)':
 'DQ'<44>: CDS_PINID='DQ(44)';
NET_NAME
'M_B_DQ<45>'
 '@BASEBOARD_FAB2_LIB.BASEBOARD_FAB2(SCH_1):M_B_DQ'<45>:
 C_SIGNAL='@baseboard_fab2_lib.baseboard_fab2(sch_1):m_b_dq(45)';
NODE_NAME     U5D1 F35
 '@BASEBOARD_FAB2_LIB.BASEBOARD_FAB2(SCH_1):PAGE24_I172@CHPSET_LIB.SKX_EXT_B(CHIPS)':
 'DDR1_DQ'<45>: CDS_PINID='DDR1_DQ(45)';
NODE_NAME     J4G2 106
 '@BASEBOARD_FAB2_LIB.BASEBOARD_FAB2(SCH_1):PAGE45_I111@MSTR_SCONN.SCONN288_H44441004(CHIPS)':
 'DQ'<44>: CDS_PINID='DQ(44)';
NODE_NAME     J6U1 251
 '@BASEBOARD_FAB2_LIB.BASEBOARD_FAB2(SCH_1):PAGE46_I14@MSTR_SCONN.SCONN288_H44441003(CHIPS)':
 'DQ'<45>: CDS_PINID='DQ(45)';
NET_NAME
'M_B_DQ<46>'
 '@BASEBOARD_FAB2_LIB.BASEBOARD_FAB2(SCH_1):M_B_DQ'<46>:
 C_SIGNAL='@baseboard_fab2_lib.baseboard_fab2(sch_1):m_b_dq(46)';
NODE_NAME     U5D1 B33
 '@BASEBOARD_FAB2_LIB.BASEBOARD_FAB2(SCH_1):PAGE24_I172@CHPSET_LIB.SKX_EXT_B(CHIPS)':
 'DDR1_DQ'<46>: CDS_PINID='DDR1_DQ(46)';
NODE_NAME     J4G2 258
 '@BASEBOARD_FAB2_LIB.BASEBOARD_FAB2(SCH_1):PAGE45_I111@MSTR_SCONN.SCONN288_H44441004(CHIPS)':
 'DQ'<47>: CDS_PINID='DQ(47)';
NODE_NAME     J6U1 113
 '@BASEBOARD_FAB2_LIB.BASEBOARD_FAB2(SCH_1):PAGE46_I14@MSTR_SCONN.SCONN288_H44441003(CHIPS)':
 'DQ'<46>: CDS_PINID='DQ(46)';
NET_NAME
'M_B_DQ<47>'
 '@BASEBOARD_FAB2_LIB.BASEBOARD_FAB2(SCH_1):M_B_DQ'<47>:
 C_SIGNAL='@baseboard_fab2_lib.baseboard_fab2(sch_1):m_b_dq(47)';
NODE_NAME     U5D1 F33
 '@BASEBOARD_FAB2_LIB.BASEBOARD_FAB2(SCH_1):PAGE24_I172@CHPSET_LIB.SKX_EXT_B(CHIPS)':
 'DDR1_DQ'<47>: CDS_PINID='DDR1_DQ(47)';
NODE_NAME     J4G2 113
 '@BASEBOARD_FAB2_LIB.BASEBOARD_FAB2(SCH_1):PAGE45_I111@MSTR_SCONN.SCONN288_H44441004(CHIPS)':
 'DQ'<46>: CDS_PINID='DQ(46)';
NODE_NAME     J6U1 258
 '@BASEBOARD_FAB2_LIB.BASEBOARD_FAB2(SCH_1):PAGE46_I14@MSTR_SCONN.SCONN288_H44441003(CHIPS)':
 'DQ'<47>: CDS_PINID='DQ(47)';
NET_NAME
'M_B_DQ<48>'
 '@BASEBOARD_FAB2_LIB.BASEBOARD_FAB2(SCH_1):M_B_DQ'<48>:
 C_SIGNAL='@baseboard_fab2_lib.baseboard_fab2(sch_1):m_b_dq(48)';
NODE_NAME     U5D1 C30
 '@BASEBOARD_FAB2_LIB.BASEBOARD_FAB2(SCH_1):PAGE24_I172@CHPSET_LIB.SKX_EXT_B(CHIPS)':
 'DDR1_DQ'<48>: CDS_PINID='DDR1_DQ(48)';
NODE_NAME     J4G2 264
 '@BASEBOARD_FAB2_LIB.BASEBOARD_FAB2(SCH_1):PAGE45_I111@MSTR_SCONN.SCONN288_H44441004(CHIPS)':
 'DQ'<49>: CDS_PINID='DQ(49)';
NODE_NAME     J6U1 119
 '@BASEBOARD_FAB2_LIB.BASEBOARD_FAB2(SCH_1):PAGE46_I14@MSTR_SCONN.SCONN288_H44441003(CHIPS)':
 'DQ'<48>: CDS_PINID='DQ(48)';
NET_NAME
'M_B_DQ<49>'
 '@BASEBOARD_FAB2_LIB.BASEBOARD_FAB2(SCH_1):M_B_DQ'<49>:
 C_SIGNAL='@baseboard_fab2_lib.baseboard_fab2(sch_1):m_b_dq(49)';
NODE_NAME     U5D1 B29
 '@BASEBOARD_FAB2_LIB.BASEBOARD_FAB2(SCH_1):PAGE24_I172@CHPSET_LIB.SKX_EXT_B(CHIPS)':
 'DDR1_DQ'<49>: CDS_PINID='DDR1_DQ(49)';
NODE_NAME     J4G2 119
 '@BASEBOARD_FAB2_LIB.BASEBOARD_FAB2(SCH_1):PAGE45_I111@MSTR_SCONN.SCONN288_H44441004(CHIPS)':
 'DQ'<48>: CDS_PINID='DQ(48)';
NODE_NAME     J6U1 264
 '@BASEBOARD_FAB2_LIB.BASEBOARD_FAB2(SCH_1):PAGE46_I14@MSTR_SCONN.SCONN288_H44441003(CHIPS)':
 'DQ'<49>: CDS_PINID='DQ(49)';
NET_NAME
'M_B_DQ<4>'
 '@BASEBOARD_FAB2_LIB.BASEBOARD_FAB2(SCH_1):M_B_DQ'<4>:
 C_SIGNAL='@baseboard_fab2_lib.baseboard_fab2(sch_1):m_b_dq(4)';
NODE_NAME     U5D1 AW80
 '@BASEBOARD_FAB2_LIB.BASEBOARD_FAB2(SCH_1):PAGE24_I172@CHPSET_LIB.SKX_EXT_B(CHIPS)':
 'DDR1_DQ'<4>: CDS_PINID='DDR1_DQ(4)';
NODE_NAME     J4G2 148
 '@BASEBOARD_FAB2_LIB.BASEBOARD_FAB2(SCH_1):PAGE45_I111@MSTR_SCONN.SCONN288_H44441004(CHIPS)':
 'DQ'<5>: CDS_PINID='DQ(5)';
NODE_NAME     J6U1 3
 '@BASEBOARD_FAB2_LIB.BASEBOARD_FAB2(SCH_1):PAGE46_I14@MSTR_SCONN.SCONN288_H44441003(CHIPS)':
 'DQ'<4>: CDS_PINID='DQ(4)';
NET_NAME
'M_B_DQ<50>'
 '@BASEBOARD_FAB2_LIB.BASEBOARD_FAB2(SCH_1):M_B_DQ'<50>:
 C_SIGNAL='@baseboard_fab2_lib.baseboard_fab2(sch_1):m_b_dq(50)';
NODE_NAME     U5D1 C26
 '@BASEBOARD_FAB2_LIB.BASEBOARD_FAB2(SCH_1):PAGE24_I172@CHPSET_LIB.SKX_EXT_B(CHIPS)':
 'DDR1_DQ'<50>: CDS_PINID='DDR1_DQ(50)';
NODE_NAME     J4G2 271
 '@BASEBOARD_FAB2_LIB.BASEBOARD_FAB2(SCH_1):PAGE45_I111@MSTR_SCONN.SCONN288_H44441004(CHIPS)':
 'DQ'<51>: CDS_PINID='DQ(51)';
NODE_NAME     J6U1 126
 '@BASEBOARD_FAB2_LIB.BASEBOARD_FAB2(SCH_1):PAGE46_I14@MSTR_SCONN.SCONN288_H44441003(CHIPS)':
 'DQ'<50>: CDS_PINID='DQ(50)';
NET_NAME
'M_B_DQ<51>'
 '@BASEBOARD_FAB2_LIB.BASEBOARD_FAB2(SCH_1):M_B_DQ'<51>:
 C_SIGNAL='@baseboard_fab2_lib.baseboard_fab2(sch_1):m_b_dq(51)';
NODE_NAME     U5D1 E26
 '@BASEBOARD_FAB2_LIB.BASEBOARD_FAB2(SCH_1):PAGE24_I172@CHPSET_LIB.SKX_EXT_B(CHIPS)':
 'DDR1_DQ'<51>: CDS_PINID='DDR1_DQ(51)';
NODE_NAME     J4G2 126
 '@BASEBOARD_FAB2_LIB.BASEBOARD_FAB2(SCH_1):PAGE45_I111@MSTR_SCONN.SCONN288_H44441004(CHIPS)':
 'DQ'<50>: CDS_PINID='DQ(50)';
NODE_NAME     J6U1 271
 '@BASEBOARD_FAB2_LIB.BASEBOARD_FAB2(SCH_1):PAGE46_I14@MSTR_SCONN.SCONN288_H44441003(CHIPS)':
 'DQ'<51>: CDS_PINID='DQ(51)';
NET_NAME
'M_B_DQ<52>'
 '@BASEBOARD_FAB2_LIB.BASEBOARD_FAB2(SCH_1):M_B_DQ'<52>:
 C_SIGNAL='@baseboard_fab2_lib.baseboard_fab2(sch_1):m_b_dq(52)';
NODE_NAME     U5D1 E30
 '@BASEBOARD_FAB2_LIB.BASEBOARD_FAB2(SCH_1):PAGE24_I172@CHPSET_LIB.SKX_EXT_B(CHIPS)':
 'DDR1_DQ'<52>: CDS_PINID='DDR1_DQ(52)';
NODE_NAME     J4G2 262
 '@BASEBOARD_FAB2_LIB.BASEBOARD_FAB2(SCH_1):PAGE45_I111@MSTR_SCONN.SCONN288_H44441004(CHIPS)':
 'DQ'<53>: CDS_PINID='DQ(53)';
NODE_NAME     J6U1 117
 '@BASEBOARD_FAB2_LIB.BASEBOARD_FAB2(SCH_1):PAGE46_I14@MSTR_SCONN.SCONN288_H44441003(CHIPS)':
 'DQ'<52>: CDS_PINID='DQ(52)';
NET_NAME
'M_B_DQ<53>'
 '@BASEBOARD_FAB2_LIB.BASEBOARD_FAB2(SCH_1):M_B_DQ'<53>:
 C_SIGNAL='@baseboard_fab2_lib.baseboard_fab2(sch_1):m_b_dq(53)';
NODE_NAME     U5D1 F29
 '@BASEBOARD_FAB2_LIB.BASEBOARD_FAB2(SCH_1):PAGE24_I172@CHPSET_LIB.SKX_EXT_B(CHIPS)':
 'DDR1_DQ'<53>: CDS_PINID='DDR1_DQ(53)';
NODE_NAME     J4G2 117
 '@BASEBOARD_FAB2_LIB.BASEBOARD_FAB2(SCH_1):PAGE45_I111@MSTR_SCONN.SCONN288_H44441004(CHIPS)':
 'DQ'<52>: CDS_PINID='DQ(52)';
NODE_NAME     J6U1 262
 '@BASEBOARD_FAB2_LIB.BASEBOARD_FAB2(SCH_1):PAGE46_I14@MSTR_SCONN.SCONN288_H44441003(CHIPS)':
 'DQ'<53>: CDS_PINID='DQ(53)';
NET_NAME
'M_B_DQ<54>'
 '@BASEBOARD_FAB2_LIB.BASEBOARD_FAB2(SCH_1):M_B_DQ'<54>:
 C_SIGNAL='@baseboard_fab2_lib.baseboard_fab2(sch_1):m_b_dq(54)';
NODE_NAME     U5D1 B27
 '@BASEBOARD_FAB2_LIB.BASEBOARD_FAB2(SCH_1):PAGE24_I172@CHPSET_LIB.SKX_EXT_B(CHIPS)':
 'DDR1_DQ'<54>: CDS_PINID='DDR1_DQ(54)';
NODE_NAME     J4G2 269
 '@BASEBOARD_FAB2_LIB.BASEBOARD_FAB2(SCH_1):PAGE45_I111@MSTR_SCONN.SCONN288_H44441004(CHIPS)':
 'DQ'<55>: CDS_PINID='DQ(55)';
NODE_NAME     J6U1 124
 '@BASEBOARD_FAB2_LIB.BASEBOARD_FAB2(SCH_1):PAGE46_I14@MSTR_SCONN.SCONN288_H44441003(CHIPS)':
 'DQ'<54>: CDS_PINID='DQ(54)';
NET_NAME
'M_B_DQ<55>'
 '@BASEBOARD_FAB2_LIB.BASEBOARD_FAB2(SCH_1):M_B_DQ'<55>:
 C_SIGNAL='@baseboard_fab2_lib.baseboard_fab2(sch_1):m_b_dq(55)';
NODE_NAME     U5D1 F27
 '@BASEBOARD_FAB2_LIB.BASEBOARD_FAB2(SCH_1):PAGE24_I172@CHPSET_LIB.SKX_EXT_B(CHIPS)':
 'DDR1_DQ'<55>: CDS_PINID='DDR1_DQ(55)';
NODE_NAME     J4G2 124
 '@BASEBOARD_FAB2_LIB.BASEBOARD_FAB2(SCH_1):PAGE45_I111@MSTR_SCONN.SCONN288_H44441004(CHIPS)':
 'DQ'<54>: CDS_PINID='DQ(54)';
NODE_NAME     J6U1 269
 '@BASEBOARD_FAB2_LIB.BASEBOARD_FAB2(SCH_1):PAGE46_I14@MSTR_SCONN.SCONN288_H44441003(CHIPS)':
 'DQ'<55>: CDS_PINID='DQ(55)';
NET_NAME
'M_B_DQ<56>'
 '@BASEBOARD_FAB2_LIB.BASEBOARD_FAB2(SCH_1):M_B_DQ'<56>:
 C_SIGNAL='@baseboard_fab2_lib.baseboard_fab2(sch_1):m_b_dq(56)';
NODE_NAME     U5D1 U28
 '@BASEBOARD_FAB2_LIB.BASEBOARD_FAB2(SCH_1):PAGE24_I172@CHPSET_LIB.SKX_EXT_B(CHIPS)':
 'DDR1_DQ'<56>: CDS_PINID='DDR1_DQ(56)';
NODE_NAME     J4G2 275
 '@BASEBOARD_FAB2_LIB.BASEBOARD_FAB2(SCH_1):PAGE45_I111@MSTR_SCONN.SCONN288_H44441004(CHIPS)':
 'DQ'<57>: CDS_PINID='DQ(57)';
NODE_NAME     J6U1 130
 '@BASEBOARD_FAB2_LIB.BASEBOARD_FAB2(SCH_1):PAGE46_I14@MSTR_SCONN.SCONN288_H44441003(CHIPS)':
 'DQ'<56>: CDS_PINID='DQ(56)';
NET_NAME
'M_B_DQ<57>'
 '@BASEBOARD_FAB2_LIB.BASEBOARD_FAB2(SCH_1):M_B_DQ'<57>:
 C_SIGNAL='@baseboard_fab2_lib.baseboard_fab2(sch_1):m_b_dq(57)';
NODE_NAME     U5D1 AA28
 '@BASEBOARD_FAB2_LIB.BASEBOARD_FAB2(SCH_1):PAGE24_I172@CHPSET_LIB.SKX_EXT_B(CHIPS)':
 'DDR1_DQ'<57>: CDS_PINID='DDR1_DQ(57)';
NODE_NAME     J4G2 130
 '@BASEBOARD_FAB2_LIB.BASEBOARD_FAB2(SCH_1):PAGE45_I111@MSTR_SCONN.SCONN288_H44441004(CHIPS)':
 'DQ'<56>: CDS_PINID='DQ(56)';
NODE_NAME     J6U1 275
 '@BASEBOARD_FAB2_LIB.BASEBOARD_FAB2(SCH_1):PAGE46_I14@MSTR_SCONN.SCONN288_H44441003(CHIPS)':
 'DQ'<57>: CDS_PINID='DQ(57)';
NET_NAME
'M_B_DQ<58>'
 '@BASEBOARD_FAB2_LIB.BASEBOARD_FAB2(SCH_1):M_B_DQ'<58>:
 C_SIGNAL='@baseboard_fab2_lib.baseboard_fab2(sch_1):m_b_dq(58)';
NODE_NAME     U5D1 V25
 '@BASEBOARD_FAB2_LIB.BASEBOARD_FAB2(SCH_1):PAGE24_I172@CHPSET_LIB.SKX_EXT_B(CHIPS)':
 'DDR1_DQ'<58>: CDS_PINID='DDR1_DQ(58)';
NODE_NAME     J4G2 282
 '@BASEBOARD_FAB2_LIB.BASEBOARD_FAB2(SCH_1):PAGE45_I111@MSTR_SCONN.SCONN288_H44441004(CHIPS)':
 'DQ'<59>: CDS_PINID='DQ(59)';
NODE_NAME     J6U1 137
 '@BASEBOARD_FAB2_LIB.BASEBOARD_FAB2(SCH_1):PAGE46_I14@MSTR_SCONN.SCONN288_H44441003(CHIPS)':
 'DQ'<58>: CDS_PINID='DQ(58)';
NET_NAME
'M_B_DQ<59>'
 '@BASEBOARD_FAB2_LIB.BASEBOARD_FAB2(SCH_1):M_B_DQ'<59>:
 C_SIGNAL='@baseboard_fab2_lib.baseboard_fab2(sch_1):m_b_dq(59)';
NODE_NAME     U5D1 Y25
 '@BASEBOARD_FAB2_LIB.BASEBOARD_FAB2(SCH_1):PAGE24_I172@CHPSET_LIB.SKX_EXT_B(CHIPS)':
 'DDR1_DQ'<59>: CDS_PINID='DDR1_DQ(59)';
NODE_NAME     J4G2 137
 '@BASEBOARD_FAB2_LIB.BASEBOARD_FAB2(SCH_1):PAGE45_I111@MSTR_SCONN.SCONN288_H44441004(CHIPS)':
 'DQ'<58>: CDS_PINID='DQ(58)';
NODE_NAME     J6U1 282
 '@BASEBOARD_FAB2_LIB.BASEBOARD_FAB2(SCH_1):PAGE46_I14@MSTR_SCONN.SCONN288_H44441003(CHIPS)':
 'DQ'<59>: CDS_PINID='DQ(59)';
NET_NAME
'M_B_DQ<5>'
 '@BASEBOARD_FAB2_LIB.BASEBOARD_FAB2(SCH_1):M_B_DQ'<5>:
 C_SIGNAL='@baseboard_fab2_lib.baseboard_fab2(sch_1):m_b_dq(5)';
NODE_NAME     U5D1 AV79
 '@BASEBOARD_FAB2_LIB.BASEBOARD_FAB2(SCH_1):PAGE24_I172@CHPSET_LIB.SKX_EXT_B(CHIPS)':
 'DDR1_DQ'<5>: CDS_PINID='DDR1_DQ(5)';
NODE_NAME     J4G2 3
 '@BASEBOARD_FAB2_LIB.BASEBOARD_FAB2(SCH_1):PAGE45_I111@MSTR_SCONN.SCONN288_H44441004(CHIPS)':
 'DQ'<4>: CDS_PINID='DQ(4)';
NODE_NAME     J6U1 148
 '@BASEBOARD_FAB2_LIB.BASEBOARD_FAB2(SCH_1):PAGE46_I14@MSTR_SCONN.SCONN288_H44441003(CHIPS)':
 'DQ'<5>: CDS_PINID='DQ(5)';
NET_NAME
'M_B_DQ<60>'
 '@BASEBOARD_FAB2_LIB.BASEBOARD_FAB2(SCH_1):M_B_DQ'<60>:
 C_SIGNAL='@baseboard_fab2_lib.baseboard_fab2(sch_1):m_b_dq(60)';
NODE_NAME     U5D1 V29
 '@BASEBOARD_FAB2_LIB.BASEBOARD_FAB2(SCH_1):PAGE24_I172@CHPSET_LIB.SKX_EXT_B(CHIPS)':
 'DDR1_DQ'<60>: CDS_PINID='DDR1_DQ(60)';
NODE_NAME     J4G2 273
 '@BASEBOARD_FAB2_LIB.BASEBOARD_FAB2(SCH_1):PAGE45_I111@MSTR_SCONN.SCONN288_H44441004(CHIPS)':
 'DQ'<61>: CDS_PINID='DQ(61)';
NODE_NAME     J6U1 128
 '@BASEBOARD_FAB2_LIB.BASEBOARD_FAB2(SCH_1):PAGE46_I14@MSTR_SCONN.SCONN288_H44441003(CHIPS)':
 'DQ'<60>: CDS_PINID='DQ(60)';
NET_NAME
'M_B_DQ<61>'
 '@BASEBOARD_FAB2_LIB.BASEBOARD_FAB2(SCH_1):M_B_DQ'<61>:
 C_SIGNAL='@baseboard_fab2_lib.baseboard_fab2(sch_1):m_b_dq(61)';
NODE_NAME     U5D1 Y29
 '@BASEBOARD_FAB2_LIB.BASEBOARD_FAB2(SCH_1):PAGE24_I172@CHPSET_LIB.SKX_EXT_B(CHIPS)':
 'DDR1_DQ'<61>: CDS_PINID='DDR1_DQ(61)';
NODE_NAME     J4G2 128
 '@BASEBOARD_FAB2_LIB.BASEBOARD_FAB2(SCH_1):PAGE45_I111@MSTR_SCONN.SCONN288_H44441004(CHIPS)':
 'DQ'<60>: CDS_PINID='DQ(60)';
NODE_NAME     J6U1 273
 '@BASEBOARD_FAB2_LIB.BASEBOARD_FAB2(SCH_1):PAGE46_I14@MSTR_SCONN.SCONN288_H44441003(CHIPS)':
 'DQ'<61>: CDS_PINID='DQ(61)';
NET_NAME
'M_B_DQ<62>'
 '@BASEBOARD_FAB2_LIB.BASEBOARD_FAB2(SCH_1):M_B_DQ'<62>:
 C_SIGNAL='@baseboard_fab2_lib.baseboard_fab2(sch_1):m_b_dq(62)';
NODE_NAME     U5D1 U26
 '@BASEBOARD_FAB2_LIB.BASEBOARD_FAB2(SCH_1):PAGE24_I172@CHPSET_LIB.SKX_EXT_B(CHIPS)':
 'DDR1_DQ'<62>: CDS_PINID='DDR1_DQ(62)';
NODE_NAME     J4G2 280
 '@BASEBOARD_FAB2_LIB.BASEBOARD_FAB2(SCH_1):PAGE45_I111@MSTR_SCONN.SCONN288_H44441004(CHIPS)':
 'DQ'<63>: CDS_PINID='DQ(63)';
NODE_NAME     J6U1 135
 '@BASEBOARD_FAB2_LIB.BASEBOARD_FAB2(SCH_1):PAGE46_I14@MSTR_SCONN.SCONN288_H44441003(CHIPS)':
 'DQ'<62>: CDS_PINID='DQ(62)';
NET_NAME
'M_B_DQ<63>'
 '@BASEBOARD_FAB2_LIB.BASEBOARD_FAB2(SCH_1):M_B_DQ'<63>:
 C_SIGNAL='@baseboard_fab2_lib.baseboard_fab2(sch_1):m_b_dq(63)';
NODE_NAME     U5D1 AA26
 '@BASEBOARD_FAB2_LIB.BASEBOARD_FAB2(SCH_1):PAGE24_I172@CHPSET_LIB.SKX_EXT_B(CHIPS)':
 'DDR1_DQ'<63>: CDS_PINID='DDR1_DQ(63)';
NODE_NAME     J4G2 135
 '@BASEBOARD_FAB2_LIB.BASEBOARD_FAB2(SCH_1):PAGE45_I111@MSTR_SCONN.SCONN288_H44441004(CHIPS)':
 'DQ'<62>: CDS_PINID='DQ(62)';
NODE_NAME     J6U1 280
 '@BASEBOARD_FAB2_LIB.BASEBOARD_FAB2(SCH_1):PAGE46_I14@MSTR_SCONN.SCONN288_H44441003(CHIPS)':
 'DQ'<63>: CDS_PINID='DQ(63)';
NET_NAME
'M_B_DQ<6>'
 '@BASEBOARD_FAB2_LIB.BASEBOARD_FAB2(SCH_1):M_B_DQ'<6>:
 C_SIGNAL='@baseboard_fab2_lib.baseboard_fab2(sch_1):m_b_dq(6)';
NODE_NAME     U5D1 AR82
 '@BASEBOARD_FAB2_LIB.BASEBOARD_FAB2(SCH_1):PAGE24_I172@CHPSET_LIB.SKX_EXT_B(CHIPS)':
 'DDR1_DQ'<6>: CDS_PINID='DDR1_DQ(6)';
NODE_NAME     J4G2 155
 '@BASEBOARD_FAB2_LIB.BASEBOARD_FAB2(SCH_1):PAGE45_I111@MSTR_SCONN.SCONN288_H44441004(CHIPS)':
 'DQ'<7>: CDS_PINID='DQ(7)';
NODE_NAME     J6U1 10
 '@BASEBOARD_FAB2_LIB.BASEBOARD_FAB2(SCH_1):PAGE46_I14@MSTR_SCONN.SCONN288_H44441003(CHIPS)':
 'DQ'<6>: CDS_PINID='DQ(6)';
NET_NAME
'M_B_DQ<7>'
 '@BASEBOARD_FAB2_LIB.BASEBOARD_FAB2(SCH_1):M_B_DQ'<7>:
 C_SIGNAL='@baseboard_fab2_lib.baseboard_fab2(sch_1):m_b_dq(7)';
NODE_NAME     U5D1 AN80
 '@BASEBOARD_FAB2_LIB.BASEBOARD_FAB2(SCH_1):PAGE24_I172@CHPSET_LIB.SKX_EXT_B(CHIPS)':
 'DDR1_DQ'<7>: CDS_PINID='DDR1_DQ(7)';
NODE_NAME     J4G2 10
 '@BASEBOARD_FAB2_LIB.BASEBOARD_FAB2(SCH_1):PAGE45_I111@MSTR_SCONN.SCONN288_H44441004(CHIPS)':
 'DQ'<6>: CDS_PINID='DQ(6)';
NODE_NAME     J6U1 155
 '@BASEBOARD_FAB2_LIB.BASEBOARD_FAB2(SCH_1):PAGE46_I14@MSTR_SCONN.SCONN288_H44441003(CHIPS)':
 'DQ'<7>: CDS_PINID='DQ(7)';
NET_NAME
'M_B_DQ<8>'
 '@BASEBOARD_FAB2_LIB.BASEBOARD_FAB2(SCH_1):M_B_DQ'<8>:
 C_SIGNAL='@baseboard_fab2_lib.baseboard_fab2(sch_1):m_b_dq(8)';
NODE_NAME     U5D1 AH81
 '@BASEBOARD_FAB2_LIB.BASEBOARD_FAB2(SCH_1):PAGE24_I172@CHPSET_LIB.SKX_EXT_B(CHIPS)':
 'DDR1_DQ'<8>: CDS_PINID='DDR1_DQ(8)';
NODE_NAME     J4G2 161
 '@BASEBOARD_FAB2_LIB.BASEBOARD_FAB2(SCH_1):PAGE45_I111@MSTR_SCONN.SCONN288_H44441004(CHIPS)':
 'DQ'<9>: CDS_PINID='DQ(9)';
NODE_NAME     J6U1 16
 '@BASEBOARD_FAB2_LIB.BASEBOARD_FAB2(SCH_1):PAGE46_I14@MSTR_SCONN.SCONN288_H44441003(CHIPS)':
 'DQ'<8>: CDS_PINID='DQ(8)';
NET_NAME
'M_B_DQ<9>'
 '@BASEBOARD_FAB2_LIB.BASEBOARD_FAB2(SCH_1):M_B_DQ'<9>:
 C_SIGNAL='@baseboard_fab2_lib.baseboard_fab2(sch_1):m_b_dq(9)';
NODE_NAME     U5D1 AF79
 '@BASEBOARD_FAB2_LIB.BASEBOARD_FAB2(SCH_1):PAGE24_I172@CHPSET_LIB.SKX_EXT_B(CHIPS)':
 'DDR1_DQ'<9>: CDS_PINID='DDR1_DQ(9)';
NODE_NAME     J4G2 16
 '@BASEBOARD_FAB2_LIB.BASEBOARD_FAB2(SCH_1):PAGE45_I111@MSTR_SCONN.SCONN288_H44441004(CHIPS)':
 'DQ'<8>: CDS_PINID='DQ(8)';
NODE_NAME     J6U1 161
 '@BASEBOARD_FAB2_LIB.BASEBOARD_FAB2(SCH_1):PAGE46_I14@MSTR_SCONN.SCONN288_H44441003(CHIPS)':
 'DQ'<9>: CDS_PINID='DQ(9)';
NET_NAME
'M_B_DQS_DN<0>'
 '@BASEBOARD_FAB2_LIB.BASEBOARD_FAB2(SCH_1):M_B_DQS_DN'<0>:
 C_SIGNAL='@baseboard_fab2_lib.baseboard_fab2(sch_1):m_b_dqs_dn(0)';
NODE_NAME     U5D1 AP79
 '@BASEBOARD_FAB2_LIB.BASEBOARD_FAB2(SCH_1):PAGE24_I172@CHPSET_LIB.SKX_EXT_B(CHIPS)':
 'DDR1_DQS_DN'<0>: CDS_PINID='DDR1_DQS_DN(0)';
NODE_NAME     J4G2 152
 '@BASEBOARD_FAB2_LIB.BASEBOARD_FAB2(SCH_1):PAGE45_I61@MSTR_SCONN.SCONN288_H44441004(CHIPS)':
 'DQS0N': CDS_PINID='DQS0N';
NODE_NAME     J6U1 152
 '@BASEBOARD_FAB2_LIB.BASEBOARD_FAB2(SCH_1):PAGE46_I112@MSTR_SCONN.SCONN288_H44441003(CHIPS)':
 'DQS0N': CDS_PINID='DQS0N';
NET_NAME
'M_B_DQS_DN<10>'
 '@BASEBOARD_FAB2_LIB.BASEBOARD_FAB2(SCH_1):M_B_DQS_DN'<10>:
 C_SIGNAL='@baseboard_fab2_lib.baseboard_fab2(sch_1):m_b_dqs_dn(10)';
NODE_NAME     U5D1 AG82
 '@BASEBOARD_FAB2_LIB.BASEBOARD_FAB2(SCH_1):PAGE24_I172@CHPSET_LIB.SKX_EXT_B(CHIPS)':
 'DDR1_DQS_DN'<10>: CDS_PINID='DDR1_DQS_DN(10)';
NODE_NAME     J4G2 19
 '@BASEBOARD_FAB2_LIB.BASEBOARD_FAB2(SCH_1):PAGE45_I61@MSTR_SCONN.SCONN288_H44441004(CHIPS)':
 'DQS10N': CDS_PINID='DQS10N';
NODE_NAME     J6U1 19
 '@BASEBOARD_FAB2_LIB.BASEBOARD_FAB2(SCH_1):PAGE46_I112@MSTR_SCONN.SCONN288_H44441003(CHIPS)':
 'DQS10N': CDS_PINID='DQS10N';
NET_NAME
'M_B_DQS_DN<11>'
 '@BASEBOARD_FAB2_LIB.BASEBOARD_FAB2(SCH_1):M_B_DQS_DN'<11>:
 C_SIGNAL='@baseboard_fab2_lib.baseboard_fab2(sch_1):m_b_dqs_dn(11)';
NODE_NAME     U5D1 D79
 '@BASEBOARD_FAB2_LIB.BASEBOARD_FAB2(SCH_1):PAGE24_I172@CHPSET_LIB.SKX_EXT_B(CHIPS)':
 'DDR1_DQS_DN'<11>: CDS_PINID='DDR1_DQS_DN(11)';
NODE_NAME     J4G2 30
 '@BASEBOARD_FAB2_LIB.BASEBOARD_FAB2(SCH_1):PAGE45_I61@MSTR_SCONN.SCONN288_H44441004(CHIPS)':
 'DQS11N': CDS_PINID='DQS11N';
NODE_NAME     J6U1 30
 '@BASEBOARD_FAB2_LIB.BASEBOARD_FAB2(SCH_1):PAGE46_I112@MSTR_SCONN.SCONN288_H44441003(CHIPS)':
 'DQS11N': CDS_PINID='DQS11N';
NET_NAME
'M_B_DQS_DN<12>'
 '@BASEBOARD_FAB2_LIB.BASEBOARD_FAB2(SCH_1):M_B_DQS_DN'<12>:
 C_SIGNAL='@baseboard_fab2_lib.baseboard_fab2(sch_1):m_b_dqs_dn(12)';
NODE_NAME     U5D1 B73
 '@BASEBOARD_FAB2_LIB.BASEBOARD_FAB2(SCH_1):PAGE24_I172@CHPSET_LIB.SKX_EXT_B(CHIPS)':
 'DDR1_DQS_DN'<12>: CDS_PINID='DDR1_DQS_DN(12)';
NODE_NAME     J4G2 41
 '@BASEBOARD_FAB2_LIB.BASEBOARD_FAB2(SCH_1):PAGE45_I61@MSTR_SCONN.SCONN288_H44441004(CHIPS)':
 'DQS12N': CDS_PINID='DQS12N';
NODE_NAME     J6U1 41
 '@BASEBOARD_FAB2_LIB.BASEBOARD_FAB2(SCH_1):PAGE46_I112@MSTR_SCONN.SCONN288_H44441003(CHIPS)':
 'DQS12N': CDS_PINID='DQS12N';
NET_NAME
'M_B_DQS_DN<13>'
 '@BASEBOARD_FAB2_LIB.BASEBOARD_FAB2(SCH_1):M_B_DQS_DN'<13>:
 C_SIGNAL='@baseboard_fab2_lib.baseboard_fab2(sch_1):m_b_dqs_dn(13)';
NODE_NAME     U5D1 J42
 '@BASEBOARD_FAB2_LIB.BASEBOARD_FAB2(SCH_1):PAGE24_I172@CHPSET_LIB.SKX_EXT_B(CHIPS)':
 'DDR1_DQS_DN'<13>: CDS_PINID='DDR1_DQS_DN(13)';
NODE_NAME     J4G2 100
 '@BASEBOARD_FAB2_LIB.BASEBOARD_FAB2(SCH_1):PAGE45_I61@MSTR_SCONN.SCONN288_H44441004(CHIPS)':
 'DQS13N': CDS_PINID='DQS13N';
NODE_NAME     J6U1 100
 '@BASEBOARD_FAB2_LIB.BASEBOARD_FAB2(SCH_1):PAGE46_I112@MSTR_SCONN.SCONN288_H44441003(CHIPS)':
 'DQS13N': CDS_PINID='DQS13N';
NET_NAME
'M_B_DQS_DN<14>'
 '@BASEBOARD_FAB2_LIB.BASEBOARD_FAB2(SCH_1):M_B_DQS_DN'<14>:
 C_SIGNAL='@baseboard_fab2_lib.baseboard_fab2(sch_1):m_b_dqs_dn(14)';
NODE_NAME     U5D1 A34
 '@BASEBOARD_FAB2_LIB.BASEBOARD_FAB2(SCH_1):PAGE24_I172@CHPSET_LIB.SKX_EXT_B(CHIPS)':
 'DDR1_DQS_DN'<14>: CDS_PINID='DDR1_DQS_DN(14)';
NODE_NAME     J4G2 111
 '@BASEBOARD_FAB2_LIB.BASEBOARD_FAB2(SCH_1):PAGE45_I61@MSTR_SCONN.SCONN288_H44441004(CHIPS)':
 'DQS14N': CDS_PINID='DQS14N';
NODE_NAME     J6U1 111
 '@BASEBOARD_FAB2_LIB.BASEBOARD_FAB2(SCH_1):PAGE46_I112@MSTR_SCONN.SCONN288_H44441003(CHIPS)':
 'DQS14N': CDS_PINID='DQS14N';
NET_NAME
'M_B_DQS_DN<15>'
 '@BASEBOARD_FAB2_LIB.BASEBOARD_FAB2(SCH_1):M_B_DQS_DN'<15>:
 C_SIGNAL='@baseboard_fab2_lib.baseboard_fab2(sch_1):m_b_dqs_dn(15)';
NODE_NAME     U5D1 A28
 '@BASEBOARD_FAB2_LIB.BASEBOARD_FAB2(SCH_1):PAGE24_I172@CHPSET_LIB.SKX_EXT_B(CHIPS)':
 'DDR1_DQS_DN'<15>: CDS_PINID='DDR1_DQS_DN(15)';
NODE_NAME     J4G2 122
 '@BASEBOARD_FAB2_LIB.BASEBOARD_FAB2(SCH_1):PAGE45_I61@MSTR_SCONN.SCONN288_H44441004(CHIPS)':
 'DQS15N': CDS_PINID='DQS15N';
NODE_NAME     J6U1 122
 '@BASEBOARD_FAB2_LIB.BASEBOARD_FAB2(SCH_1):PAGE46_I112@MSTR_SCONN.SCONN288_H44441003(CHIPS)':
 'DQS15N': CDS_PINID='DQS15N';
NET_NAME
'M_B_DQS_DN<16>'
 '@BASEBOARD_FAB2_LIB.BASEBOARD_FAB2(SCH_1):M_B_DQS_DN'<16>:
 C_SIGNAL='@baseboard_fab2_lib.baseboard_fab2(sch_1):m_b_dqs_dn(16)';
NODE_NAME     U5D1 T27
 '@BASEBOARD_FAB2_LIB.BASEBOARD_FAB2(SCH_1):PAGE24_I172@CHPSET_LIB.SKX_EXT_B(CHIPS)':
 'DDR1_DQS_DN'<16>: CDS_PINID='DDR1_DQS_DN(16)';
NODE_NAME     J4G2 133
 '@BASEBOARD_FAB2_LIB.BASEBOARD_FAB2(SCH_1):PAGE45_I61@MSTR_SCONN.SCONN288_H44441004(CHIPS)':
 'DQS16N': CDS_PINID='DQS16N';
NODE_NAME     J6U1 133
 '@BASEBOARD_FAB2_LIB.BASEBOARD_FAB2(SCH_1):PAGE46_I112@MSTR_SCONN.SCONN288_H44441003(CHIPS)':
 'DQS16N': CDS_PINID='DQS16N';
NET_NAME
'M_B_DQS_DN<17>'
 '@BASEBOARD_FAB2_LIB.BASEBOARD_FAB2(SCH_1):M_B_DQS_DN'<17>:
 C_SIGNAL='@baseboard_fab2_lib.baseboard_fab2(sch_1):m_b_dqs_dn(17)';
NODE_NAME     U5D1 G68
 '@BASEBOARD_FAB2_LIB.BASEBOARD_FAB2(SCH_1):PAGE24_I172@CHPSET_LIB.SKX_EXT_B(CHIPS)':
 'DDR1_DQS_DN'<17>: CDS_PINID='DDR1_DQS_DN(17)';
NODE_NAME     J4G2 52
 '@BASEBOARD_FAB2_LIB.BASEBOARD_FAB2(SCH_1):PAGE45_I61@MSTR_SCONN.SCONN288_H44441004(CHIPS)':
 'DQS17N': CDS_PINID='DQS17N';
NODE_NAME     J6U1 52
 '@BASEBOARD_FAB2_LIB.BASEBOARD_FAB2(SCH_1):PAGE46_I112@MSTR_SCONN.SCONN288_H44441003(CHIPS)':
 'DQS17N': CDS_PINID='DQS17N';
NET_NAME
'M_B_DQS_DN<1>'
 '@BASEBOARD_FAB2_LIB.BASEBOARD_FAB2(SCH_1):M_B_DQS_DN'<1>:
 C_SIGNAL='@baseboard_fab2_lib.baseboard_fab2(sch_1):m_b_dqs_dn(1)';
NODE_NAME     U5D1 AD79
 '@BASEBOARD_FAB2_LIB.BASEBOARD_FAB2(SCH_1):PAGE24_I172@CHPSET_LIB.SKX_EXT_B(CHIPS)':
 'DDR1_DQS_DN'<1>: CDS_PINID='DDR1_DQS_DN(1)';
NODE_NAME     J4G2 163
 '@BASEBOARD_FAB2_LIB.BASEBOARD_FAB2(SCH_1):PAGE45_I61@MSTR_SCONN.SCONN288_H44441004(CHIPS)':
 'DQS1N': CDS_PINID='DQS1N';
NODE_NAME     J6U1 163
 '@BASEBOARD_FAB2_LIB.BASEBOARD_FAB2(SCH_1):PAGE46_I112@MSTR_SCONN.SCONN288_H44441003(CHIPS)':
 'DQS1N': CDS_PINID='DQS1N';
NET_NAME
'M_B_DQS_DN<2>'
 '@BASEBOARD_FAB2_LIB.BASEBOARD_FAB2(SCH_1):M_B_DQS_DN'<2>:
 C_SIGNAL='@baseboard_fab2_lib.baseboard_fab2(sch_1):m_b_dqs_dn(2)';
NODE_NAME     U5D1 K79
 '@BASEBOARD_FAB2_LIB.BASEBOARD_FAB2(SCH_1):PAGE24_I172@CHPSET_LIB.SKX_EXT_B(CHIPS)':
 'DDR1_DQS_DN'<2>: CDS_PINID='DDR1_DQS_DN(2)';
NODE_NAME     J4G2 174
 '@BASEBOARD_FAB2_LIB.BASEBOARD_FAB2(SCH_1):PAGE45_I61@MSTR_SCONN.SCONN288_H44441004(CHIPS)':
 'DQS2N': CDS_PINID='DQS2N';
NODE_NAME     J6U1 174
 '@BASEBOARD_FAB2_LIB.BASEBOARD_FAB2(SCH_1):PAGE46_I112@MSTR_SCONN.SCONN288_H44441003(CHIPS)':
 'DQS2N': CDS_PINID='DQS2N';
NET_NAME
'M_B_DQS_DN<3>'
 '@BASEBOARD_FAB2_LIB.BASEBOARD_FAB2(SCH_1):M_B_DQS_DN'<3>:
 C_SIGNAL='@baseboard_fab2_lib.baseboard_fab2(sch_1):m_b_dqs_dn(3)';
NODE_NAME     U5D1 H73
 '@BASEBOARD_FAB2_LIB.BASEBOARD_FAB2(SCH_1):PAGE24_I172@CHPSET_LIB.SKX_EXT_B(CHIPS)':
 'DDR1_DQS_DN'<3>: CDS_PINID='DDR1_DQS_DN(3)';
NODE_NAME     J4G2 185
 '@BASEBOARD_FAB2_LIB.BASEBOARD_FAB2(SCH_1):PAGE45_I61@MSTR_SCONN.SCONN288_H44441004(CHIPS)':
 'DQS3N': CDS_PINID='DQS3N';
NODE_NAME     J6U1 185
 '@BASEBOARD_FAB2_LIB.BASEBOARD_FAB2(SCH_1):PAGE46_I112@MSTR_SCONN.SCONN288_H44441003(CHIPS)':
 'DQS3N': CDS_PINID='DQS3N';
NET_NAME
'M_B_DQS_DN<4>'
 '@BASEBOARD_FAB2_LIB.BASEBOARD_FAB2(SCH_1):M_B_DQS_DN'<4>:
 C_SIGNAL='@baseboard_fab2_lib.baseboard_fab2(sch_1):m_b_dqs_dn(4)';
NODE_NAME     U5D1 N42
 '@BASEBOARD_FAB2_LIB.BASEBOARD_FAB2(SCH_1):PAGE24_I172@CHPSET_LIB.SKX_EXT_B(CHIPS)':
 'DDR1_DQS_DN'<4>: CDS_PINID='DDR1_DQS_DN(4)';
NODE_NAME     J4G2 244
 '@BASEBOARD_FAB2_LIB.BASEBOARD_FAB2(SCH_1):PAGE45_I61@MSTR_SCONN.SCONN288_H44441004(CHIPS)':
 'DQS4N': CDS_PINID='DQS4N';
NODE_NAME     J6U1 244
 '@BASEBOARD_FAB2_LIB.BASEBOARD_FAB2(SCH_1):PAGE46_I112@MSTR_SCONN.SCONN288_H44441003(CHIPS)':
 'DQS4N': CDS_PINID='DQS4N';
NET_NAME
'M_B_DQS_DN<5>'
 '@BASEBOARD_FAB2_LIB.BASEBOARD_FAB2(SCH_1):M_B_DQS_DN'<5>:
 C_SIGNAL='@baseboard_fab2_lib.baseboard_fab2(sch_1):m_b_dqs_dn(5)';
NODE_NAME     U5D1 G34
 '@BASEBOARD_FAB2_LIB.BASEBOARD_FAB2(SCH_1):PAGE24_I172@CHPSET_LIB.SKX_EXT_B(CHIPS)':
 'DDR1_DQS_DN'<5>: CDS_PINID='DDR1_DQS_DN(5)';
NODE_NAME     J4G2 255
 '@BASEBOARD_FAB2_LIB.BASEBOARD_FAB2(SCH_1):PAGE45_I61@MSTR_SCONN.SCONN288_H44441004(CHIPS)':
 'DQS5N': CDS_PINID='DQS5N';
NODE_NAME     J6U1 255
 '@BASEBOARD_FAB2_LIB.BASEBOARD_FAB2(SCH_1):PAGE46_I112@MSTR_SCONN.SCONN288_H44441003(CHIPS)':
 'DQS5N': CDS_PINID='DQS5N';
NET_NAME
'M_B_DQS_DN<6>'
 '@BASEBOARD_FAB2_LIB.BASEBOARD_FAB2(SCH_1):M_B_DQS_DN'<6>:
 C_SIGNAL='@baseboard_fab2_lib.baseboard_fab2(sch_1):m_b_dqs_dn(6)';
NODE_NAME     U5D1 G28
 '@BASEBOARD_FAB2_LIB.BASEBOARD_FAB2(SCH_1):PAGE24_I172@CHPSET_LIB.SKX_EXT_B(CHIPS)':
 'DDR1_DQS_DN'<6>: CDS_PINID='DDR1_DQS_DN(6)';
NODE_NAME     J4G2 266
 '@BASEBOARD_FAB2_LIB.BASEBOARD_FAB2(SCH_1):PAGE45_I61@MSTR_SCONN.SCONN288_H44441004(CHIPS)':
 'DQS6N': CDS_PINID='DQS6N';
NODE_NAME     J6U1 266
 '@BASEBOARD_FAB2_LIB.BASEBOARD_FAB2(SCH_1):PAGE46_I112@MSTR_SCONN.SCONN288_H44441003(CHIPS)':
 'DQS6N': CDS_PINID='DQS6N';
NET_NAME
'M_B_DQS_DN<7>'
 '@BASEBOARD_FAB2_LIB.BASEBOARD_FAB2(SCH_1):M_B_DQS_DN'<7>:
 C_SIGNAL='@baseboard_fab2_lib.baseboard_fab2(sch_1):m_b_dqs_dn(7)';
NODE_NAME     U5D1 AB27
 '@BASEBOARD_FAB2_LIB.BASEBOARD_FAB2(SCH_1):PAGE24_I172@CHPSET_LIB.SKX_EXT_B(CHIPS)':
 'DDR1_DQS_DN'<7>: CDS_PINID='DDR1_DQS_DN(7)';
NODE_NAME     J4G2 277
 '@BASEBOARD_FAB2_LIB.BASEBOARD_FAB2(SCH_1):PAGE45_I61@MSTR_SCONN.SCONN288_H44441004(CHIPS)':
 'DQS7N': CDS_PINID='DQS7N';
NODE_NAME     J6U1 277
 '@BASEBOARD_FAB2_LIB.BASEBOARD_FAB2(SCH_1):PAGE46_I112@MSTR_SCONN.SCONN288_H44441003(CHIPS)':
 'DQS7N': CDS_PINID='DQS7N';
NET_NAME
'M_B_DQS_DN<8>'
 '@BASEBOARD_FAB2_LIB.BASEBOARD_FAB2(SCH_1):M_B_DQS_DN'<8>:
 C_SIGNAL='@baseboard_fab2_lib.baseboard_fab2(sch_1):m_b_dqs_dn(8)';
NODE_NAME     U5D1 N68
 '@BASEBOARD_FAB2_LIB.BASEBOARD_FAB2(SCH_1):PAGE24_I172@CHPSET_LIB.SKX_EXT_B(CHIPS)':
 'DDR1_DQS_DN'<8>: CDS_PINID='DDR1_DQS_DN(8)';
NODE_NAME     J4G2 196
 '@BASEBOARD_FAB2_LIB.BASEBOARD_FAB2(SCH_1):PAGE45_I61@MSTR_SCONN.SCONN288_H44441004(CHIPS)':
 'DQS8N': CDS_PINID='DQS8N';
NODE_NAME     J6U1 196
 '@BASEBOARD_FAB2_LIB.BASEBOARD_FAB2(SCH_1):PAGE46_I112@MSTR_SCONN.SCONN288_H44441003(CHIPS)':
 'DQS8N': CDS_PINID='DQS8N';
NET_NAME
'M_B_DQS_DN<9>'
 '@BASEBOARD_FAB2_LIB.BASEBOARD_FAB2(SCH_1):M_B_DQS_DN'<9>:
 C_SIGNAL='@baseboard_fab2_lib.baseboard_fab2(sch_1):m_b_dqs_dn(9)';
NODE_NAME     U5D1 AU82
 '@BASEBOARD_FAB2_LIB.BASEBOARD_FAB2(SCH_1):PAGE24_I172@CHPSET_LIB.SKX_EXT_B(CHIPS)':
 'DDR1_DQS_DN'<9>: CDS_PINID='DDR1_DQS_DN(9)';
NODE_NAME     J4G2 8
 '@BASEBOARD_FAB2_LIB.BASEBOARD_FAB2(SCH_1):PAGE45_I61@MSTR_SCONN.SCONN288_H44441004(CHIPS)':
 'DQS9N': CDS_PINID='DQS9N';
NODE_NAME     J6U1 8
 '@BASEBOARD_FAB2_LIB.BASEBOARD_FAB2(SCH_1):PAGE46_I112@MSTR_SCONN.SCONN288_H44441003(CHIPS)':
 'DQS9N': CDS_PINID='DQS9N';
NET_NAME
'M_B_DQS_DP<0>'
 '@BASEBOARD_FAB2_LIB.BASEBOARD_FAB2(SCH_1):M_B_DQS_DP'<0>:
 C_SIGNAL='@baseboard_fab2_lib.baseboard_fab2(sch_1):m_b_dqs_dp(0)';
NODE_NAME     U5D1 AR80
 '@BASEBOARD_FAB2_LIB.BASEBOARD_FAB2(SCH_1):PAGE24_I172@CHPSET_LIB.SKX_EXT_B(CHIPS)':
 'DDR1_DQS_DP'<0>: CDS_PINID='DDR1_DQS_DP(0)';
NODE_NAME     J4G2 153
 '@BASEBOARD_FAB2_LIB.BASEBOARD_FAB2(SCH_1):PAGE45_I61@MSTR_SCONN.SCONN288_H44441004(CHIPS)':
 'DQS0P': CDS_PINID='DQS0P';
NODE_NAME     J6U1 153
 '@BASEBOARD_FAB2_LIB.BASEBOARD_FAB2(SCH_1):PAGE46_I112@MSTR_SCONN.SCONN288_H44441003(CHIPS)':
 'DQS0P': CDS_PINID='DQS0P';
NET_NAME
'M_B_DQS_DP<10>'
 '@BASEBOARD_FAB2_LIB.BASEBOARD_FAB2(SCH_1):M_B_DQS_DP'<10>:
 C_SIGNAL='@baseboard_fab2_lib.baseboard_fab2(sch_1):m_b_dqs_dp(10)';
NODE_NAME     U5D1 AF81
 '@BASEBOARD_FAB2_LIB.BASEBOARD_FAB2(SCH_1):PAGE24_I172@CHPSET_LIB.SKX_EXT_B(CHIPS)':
 'DDR1_DQS_DP'<10>: CDS_PINID='DDR1_DQS_DP(10)';
NODE_NAME     J4G2 18
 '@BASEBOARD_FAB2_LIB.BASEBOARD_FAB2(SCH_1):PAGE45_I61@MSTR_SCONN.SCONN288_H44441004(CHIPS)':
 'DQS10P': CDS_PINID='DQS10P';
NODE_NAME     J6U1 18
 '@BASEBOARD_FAB2_LIB.BASEBOARD_FAB2(SCH_1):PAGE46_I112@MSTR_SCONN.SCONN288_H44441003(CHIPS)':
 'DQS10P': CDS_PINID='DQS10P';
NET_NAME
'M_B_DQS_DP<11>'
 '@BASEBOARD_FAB2_LIB.BASEBOARD_FAB2(SCH_1):M_B_DQS_DP'<11>:
 C_SIGNAL='@baseboard_fab2_lib.baseboard_fab2(sch_1):m_b_dqs_dp(11)';
NODE_NAME     U5D1 F79
 '@BASEBOARD_FAB2_LIB.BASEBOARD_FAB2(SCH_1):PAGE24_I172@CHPSET_LIB.SKX_EXT_B(CHIPS)':
 'DDR1_DQS_DP'<11>: CDS_PINID='DDR1_DQS_DP(11)';
NODE_NAME     J4G2 29
 '@BASEBOARD_FAB2_LIB.BASEBOARD_FAB2(SCH_1):PAGE45_I61@MSTR_SCONN.SCONN288_H44441004(CHIPS)':
 'DQS11P': CDS_PINID='DQS11P';
NODE_NAME     J6U1 29
 '@BASEBOARD_FAB2_LIB.BASEBOARD_FAB2(SCH_1):PAGE46_I112@MSTR_SCONN.SCONN288_H44441003(CHIPS)':
 'DQS11P': CDS_PINID='DQS11P';
NET_NAME
'M_B_DQS_DP<12>'
 '@BASEBOARD_FAB2_LIB.BASEBOARD_FAB2(SCH_1):M_B_DQS_DP'<12>:
 C_SIGNAL='@baseboard_fab2_lib.baseboard_fab2(sch_1):m_b_dqs_dp(12)';
NODE_NAME     U5D1 D73
 '@BASEBOARD_FAB2_LIB.BASEBOARD_FAB2(SCH_1):PAGE24_I172@CHPSET_LIB.SKX_EXT_B(CHIPS)':
 'DDR1_DQS_DP'<12>: CDS_PINID='DDR1_DQS_DP(12)';
NODE_NAME     J4G2 40
 '@BASEBOARD_FAB2_LIB.BASEBOARD_FAB2(SCH_1):PAGE45_I61@MSTR_SCONN.SCONN288_H44441004(CHIPS)':
 'DQS12P': CDS_PINID='DQS12P';
NODE_NAME     J6U1 40
 '@BASEBOARD_FAB2_LIB.BASEBOARD_FAB2(SCH_1):PAGE46_I112@MSTR_SCONN.SCONN288_H44441003(CHIPS)':
 'DQS12P': CDS_PINID='DQS12P';
NET_NAME
'M_B_DQS_DP<13>'
 '@BASEBOARD_FAB2_LIB.BASEBOARD_FAB2(SCH_1):M_B_DQS_DP'<13>:
 C_SIGNAL='@baseboard_fab2_lib.baseboard_fab2(sch_1):m_b_dqs_dp(13)';
NODE_NAME     U5D1 L42
 '@BASEBOARD_FAB2_LIB.BASEBOARD_FAB2(SCH_1):PAGE24_I172@CHPSET_LIB.SKX_EXT_B(CHIPS)':
 'DDR1_DQS_DP'<13>: CDS_PINID='DDR1_DQS_DP(13)';
NODE_NAME     J4G2 99
 '@BASEBOARD_FAB2_LIB.BASEBOARD_FAB2(SCH_1):PAGE45_I61@MSTR_SCONN.SCONN288_H44441004(CHIPS)':
 'DQS13P': CDS_PINID='DQS13P';
NODE_NAME     J6U1 99
 '@BASEBOARD_FAB2_LIB.BASEBOARD_FAB2(SCH_1):PAGE46_I112@MSTR_SCONN.SCONN288_H44441003(CHIPS)':
 'DQS13P': CDS_PINID='DQS13P';
NET_NAME
'M_B_DQS_DP<14>'
 '@BASEBOARD_FAB2_LIB.BASEBOARD_FAB2(SCH_1):M_B_DQS_DP'<14>:
 C_SIGNAL='@baseboard_fab2_lib.baseboard_fab2(sch_1):m_b_dqs_dp(14)';
NODE_NAME     U5D1 C34
 '@BASEBOARD_FAB2_LIB.BASEBOARD_FAB2(SCH_1):PAGE24_I172@CHPSET_LIB.SKX_EXT_B(CHIPS)':
 'DDR1_DQS_DP'<14>: CDS_PINID='DDR1_DQS_DP(14)';
NODE_NAME     J4G2 110
 '@BASEBOARD_FAB2_LIB.BASEBOARD_FAB2(SCH_1):PAGE45_I61@MSTR_SCONN.SCONN288_H44441004(CHIPS)':
 'DQS14P': CDS_PINID='DQS14P';
NODE_NAME     J6U1 110
 '@BASEBOARD_FAB2_LIB.BASEBOARD_FAB2(SCH_1):PAGE46_I112@MSTR_SCONN.SCONN288_H44441003(CHIPS)':
 'DQS14P': CDS_PINID='DQS14P';
NET_NAME
'M_B_DQS_DP<15>'
 '@BASEBOARD_FAB2_LIB.BASEBOARD_FAB2(SCH_1):M_B_DQS_DP'<15>:
 C_SIGNAL='@baseboard_fab2_lib.baseboard_fab2(sch_1):m_b_dqs_dp(15)';
NODE_NAME     U5D1 C28
 '@BASEBOARD_FAB2_LIB.BASEBOARD_FAB2(SCH_1):PAGE24_I172@CHPSET_LIB.SKX_EXT_B(CHIPS)':
 'DDR1_DQS_DP'<15>: CDS_PINID='DDR1_DQS_DP(15)';
NODE_NAME     J4G2 121
 '@BASEBOARD_FAB2_LIB.BASEBOARD_FAB2(SCH_1):PAGE45_I61@MSTR_SCONN.SCONN288_H44441004(CHIPS)':
 'DQS15P': CDS_PINID='DQS15P';
NODE_NAME     J6U1 121
 '@BASEBOARD_FAB2_LIB.BASEBOARD_FAB2(SCH_1):PAGE46_I112@MSTR_SCONN.SCONN288_H44441003(CHIPS)':
 'DQS15P': CDS_PINID='DQS15P';
NET_NAME
'M_B_DQS_DP<16>'
 '@BASEBOARD_FAB2_LIB.BASEBOARD_FAB2(SCH_1):M_B_DQS_DP'<16>:
 C_SIGNAL='@baseboard_fab2_lib.baseboard_fab2(sch_1):m_b_dqs_dp(16)';
NODE_NAME     U5D1 V27
 '@BASEBOARD_FAB2_LIB.BASEBOARD_FAB2(SCH_1):PAGE24_I172@CHPSET_LIB.SKX_EXT_B(CHIPS)':
 'DDR1_DQS_DP'<16>: CDS_PINID='DDR1_DQS_DP(16)';
NODE_NAME     J4G2 132
 '@BASEBOARD_FAB2_LIB.BASEBOARD_FAB2(SCH_1):PAGE45_I61@MSTR_SCONN.SCONN288_H44441004(CHIPS)':
 'DQS16P': CDS_PINID='DQS16P';
NODE_NAME     J6U1 132
 '@BASEBOARD_FAB2_LIB.BASEBOARD_FAB2(SCH_1):PAGE46_I112@MSTR_SCONN.SCONN288_H44441003(CHIPS)':
 'DQS16P': CDS_PINID='DQS16P';
NET_NAME
'M_B_DQS_DP<17>'
 '@BASEBOARD_FAB2_LIB.BASEBOARD_FAB2(SCH_1):M_B_DQS_DP'<17>:
 C_SIGNAL='@baseboard_fab2_lib.baseboard_fab2(sch_1):m_b_dqs_dp(17)';
NODE_NAME     U5D1 J68
 '@BASEBOARD_FAB2_LIB.BASEBOARD_FAB2(SCH_1):PAGE24_I172@CHPSET_LIB.SKX_EXT_B(CHIPS)':
 'DDR1_DQS_DP'<17>: CDS_PINID='DDR1_DQS_DP(17)';
NODE_NAME     J4G2 51
 '@BASEBOARD_FAB2_LIB.BASEBOARD_FAB2(SCH_1):PAGE45_I61@MSTR_SCONN.SCONN288_H44441004(CHIPS)':
 'DQS17P': CDS_PINID='DQS17P';
NODE_NAME     J6U1 51
 '@BASEBOARD_FAB2_LIB.BASEBOARD_FAB2(SCH_1):PAGE46_I112@MSTR_SCONN.SCONN288_H44441003(CHIPS)':
 'DQS17P': CDS_PINID='DQS17P';
NET_NAME
'M_B_DQS_DP<1>'
 '@BASEBOARD_FAB2_LIB.BASEBOARD_FAB2(SCH_1):M_B_DQS_DP'<1>:
 C_SIGNAL='@baseboard_fab2_lib.baseboard_fab2(sch_1):m_b_dqs_dp(1)';
NODE_NAME     U5D1 AE80
 '@BASEBOARD_FAB2_LIB.BASEBOARD_FAB2(SCH_1):PAGE24_I172@CHPSET_LIB.SKX_EXT_B(CHIPS)':
 'DDR1_DQS_DP'<1>: CDS_PINID='DDR1_DQS_DP(1)';
NODE_NAME     J4G2 164
 '@BASEBOARD_FAB2_LIB.BASEBOARD_FAB2(SCH_1):PAGE45_I61@MSTR_SCONN.SCONN288_H44441004(CHIPS)':
 'DQS1P': CDS_PINID='DQS1P';
NODE_NAME     J6U1 164
 '@BASEBOARD_FAB2_LIB.BASEBOARD_FAB2(SCH_1):PAGE46_I112@MSTR_SCONN.SCONN288_H44441003(CHIPS)':
 'DQS1P': CDS_PINID='DQS1P';
NET_NAME
'M_B_DQS_DP<2>'
 '@BASEBOARD_FAB2_LIB.BASEBOARD_FAB2(SCH_1):M_B_DQS_DP'<2>:
 C_SIGNAL='@baseboard_fab2_lib.baseboard_fab2(sch_1):m_b_dqs_dp(2)';
NODE_NAME     U5D1 H79
 '@BASEBOARD_FAB2_LIB.BASEBOARD_FAB2(SCH_1):PAGE24_I172@CHPSET_LIB.SKX_EXT_B(CHIPS)':
 'DDR1_DQS_DP'<2>: CDS_PINID='DDR1_DQS_DP(2)';
NODE_NAME     J4G2 175
 '@BASEBOARD_FAB2_LIB.BASEBOARD_FAB2(SCH_1):PAGE45_I61@MSTR_SCONN.SCONN288_H44441004(CHIPS)':
 'DQS2P': CDS_PINID='DQS2P';
NODE_NAME     J6U1 175
 '@BASEBOARD_FAB2_LIB.BASEBOARD_FAB2(SCH_1):PAGE46_I112@MSTR_SCONN.SCONN288_H44441003(CHIPS)':
 'DQS2P': CDS_PINID='DQS2P';
NET_NAME
'M_B_DQS_DP<3>'
 '@BASEBOARD_FAB2_LIB.BASEBOARD_FAB2(SCH_1):M_B_DQS_DP'<3>:
 C_SIGNAL='@baseboard_fab2_lib.baseboard_fab2(sch_1):m_b_dqs_dp(3)';
NODE_NAME     U5D1 F73
 '@BASEBOARD_FAB2_LIB.BASEBOARD_FAB2(SCH_1):PAGE24_I172@CHPSET_LIB.SKX_EXT_B(CHIPS)':
 'DDR1_DQS_DP'<3>: CDS_PINID='DDR1_DQS_DP(3)';
NODE_NAME     J4G2 186
 '@BASEBOARD_FAB2_LIB.BASEBOARD_FAB2(SCH_1):PAGE45_I61@MSTR_SCONN.SCONN288_H44441004(CHIPS)':
 'DQS3P': CDS_PINID='DQS3P';
NODE_NAME     J6U1 186
 '@BASEBOARD_FAB2_LIB.BASEBOARD_FAB2(SCH_1):PAGE46_I112@MSTR_SCONN.SCONN288_H44441003(CHIPS)':
 'DQS3P': CDS_PINID='DQS3P';
NET_NAME
'M_B_DQS_DP<4>'
 '@BASEBOARD_FAB2_LIB.BASEBOARD_FAB2(SCH_1):M_B_DQS_DP'<4>:
 C_SIGNAL='@baseboard_fab2_lib.baseboard_fab2(sch_1):m_b_dqs_dp(4)';
NODE_NAME     U5D1 R42
 '@BASEBOARD_FAB2_LIB.BASEBOARD_FAB2(SCH_1):PAGE24_I172@CHPSET_LIB.SKX_EXT_B(CHIPS)':
 'DDR1_DQS_DP'<4>: CDS_PINID='DDR1_DQS_DP(4)';
NODE_NAME     J4G2 245
 '@BASEBOARD_FAB2_LIB.BASEBOARD_FAB2(SCH_1):PAGE45_I61@MSTR_SCONN.SCONN288_H44441004(CHIPS)':
 'DQS4P': CDS_PINID='DQS4P';
NODE_NAME     J6U1 245
 '@BASEBOARD_FAB2_LIB.BASEBOARD_FAB2(SCH_1):PAGE46_I112@MSTR_SCONN.SCONN288_H44441003(CHIPS)':
 'DQS4P': CDS_PINID='DQS4P';
NET_NAME
'M_B_DQS_DP<5>'
 '@BASEBOARD_FAB2_LIB.BASEBOARD_FAB2(SCH_1):M_B_DQS_DP'<5>:
 C_SIGNAL='@baseboard_fab2_lib.baseboard_fab2(sch_1):m_b_dqs_dp(5)';
NODE_NAME     U5D1 E34
 '@BASEBOARD_FAB2_LIB.BASEBOARD_FAB2(SCH_1):PAGE24_I172@CHPSET_LIB.SKX_EXT_B(CHIPS)':
 'DDR1_DQS_DP'<5>: CDS_PINID='DDR1_DQS_DP(5)';
NODE_NAME     J4G2 256
 '@BASEBOARD_FAB2_LIB.BASEBOARD_FAB2(SCH_1):PAGE45_I61@MSTR_SCONN.SCONN288_H44441004(CHIPS)':
 'DQS5P': CDS_PINID='DQS5P';
NODE_NAME     J6U1 256
 '@BASEBOARD_FAB2_LIB.BASEBOARD_FAB2(SCH_1):PAGE46_I112@MSTR_SCONN.SCONN288_H44441003(CHIPS)':
 'DQS5P': CDS_PINID='DQS5P';
NET_NAME
'M_B_DQS_DP<6>'
 '@BASEBOARD_FAB2_LIB.BASEBOARD_FAB2(SCH_1):M_B_DQS_DP'<6>:
 C_SIGNAL='@baseboard_fab2_lib.baseboard_fab2(sch_1):m_b_dqs_dp(6)';
NODE_NAME     U5D1 E28
 '@BASEBOARD_FAB2_LIB.BASEBOARD_FAB2(SCH_1):PAGE24_I172@CHPSET_LIB.SKX_EXT_B(CHIPS)':
 'DDR1_DQS_DP'<6>: CDS_PINID='DDR1_DQS_DP(6)';
NODE_NAME     J4G2 267
 '@BASEBOARD_FAB2_LIB.BASEBOARD_FAB2(SCH_1):PAGE45_I61@MSTR_SCONN.SCONN288_H44441004(CHIPS)':
 'DQS6P': CDS_PINID='DQS6P';
NODE_NAME     J6U1 267
 '@BASEBOARD_FAB2_LIB.BASEBOARD_FAB2(SCH_1):PAGE46_I112@MSTR_SCONN.SCONN288_H44441003(CHIPS)':
 'DQS6P': CDS_PINID='DQS6P';
NET_NAME
'M_B_DQS_DP<7>'
 '@BASEBOARD_FAB2_LIB.BASEBOARD_FAB2(SCH_1):M_B_DQS_DP'<7>:
 C_SIGNAL='@baseboard_fab2_lib.baseboard_fab2(sch_1):m_b_dqs_dp(7)';
NODE_NAME     U5D1 Y27
 '@BASEBOARD_FAB2_LIB.BASEBOARD_FAB2(SCH_1):PAGE24_I172@CHPSET_LIB.SKX_EXT_B(CHIPS)':
 'DDR1_DQS_DP'<7>: CDS_PINID='DDR1_DQS_DP(7)';
NODE_NAME     J4G2 278
 '@BASEBOARD_FAB2_LIB.BASEBOARD_FAB2(SCH_1):PAGE45_I61@MSTR_SCONN.SCONN288_H44441004(CHIPS)':
 'DQS7P': CDS_PINID='DQS7P';
NODE_NAME     J6U1 278
 '@BASEBOARD_FAB2_LIB.BASEBOARD_FAB2(SCH_1):PAGE46_I112@MSTR_SCONN.SCONN288_H44441003(CHIPS)':
 'DQS7P': CDS_PINID='DQS7P';
NET_NAME
'M_B_DQS_DP<8>'
 '@BASEBOARD_FAB2_LIB.BASEBOARD_FAB2(SCH_1):M_B_DQS_DP'<8>:
 C_SIGNAL='@baseboard_fab2_lib.baseboard_fab2(sch_1):m_b_dqs_dp(8)';
NODE_NAME     U5D1 L68
 '@BASEBOARD_FAB2_LIB.BASEBOARD_FAB2(SCH_1):PAGE24_I172@CHPSET_LIB.SKX_EXT_B(CHIPS)':
 'DDR1_DQS_DP'<8>: CDS_PINID='DDR1_DQS_DP(8)';
NODE_NAME     J4G2 197
 '@BASEBOARD_FAB2_LIB.BASEBOARD_FAB2(SCH_1):PAGE45_I61@MSTR_SCONN.SCONN288_H44441004(CHIPS)':
 'DQS8P': CDS_PINID='DQS8P';
NODE_NAME     J6U1 197
 '@BASEBOARD_FAB2_LIB.BASEBOARD_FAB2(SCH_1):PAGE46_I112@MSTR_SCONN.SCONN288_H44441003(CHIPS)':
 'DQS8P': CDS_PINID='DQS8P';
NET_NAME
'M_B_DQS_DP<9>'
 '@BASEBOARD_FAB2_LIB.BASEBOARD_FAB2(SCH_1):M_B_DQS_DP'<9>:
 C_SIGNAL='@baseboard_fab2_lib.baseboard_fab2(sch_1):m_b_dqs_dp(9)';
NODE_NAME     U5D1 AT81
 '@BASEBOARD_FAB2_LIB.BASEBOARD_FAB2(SCH_1):PAGE24_I172@CHPSET_LIB.SKX_EXT_B(CHIPS)':
 'DDR1_DQS_DP'<9>: CDS_PINID='DDR1_DQS_DP(9)';
NODE_NAME     J4G2 7
 '@BASEBOARD_FAB2_LIB.BASEBOARD_FAB2(SCH_1):PAGE45_I61@MSTR_SCONN.SCONN288_H44441004(CHIPS)':
 'DQS9P': CDS_PINID='DQS9P';
NODE_NAME     J6U1 7
 '@BASEBOARD_FAB2_LIB.BASEBOARD_FAB2(SCH_1):PAGE46_I112@MSTR_SCONN.SCONN288_H44441003(CHIPS)':
 'DQS9P': CDS_PINID='DQS9P';
NET_NAME
'M_B_ECC<0>'
 '@BASEBOARD_FAB2_LIB.BASEBOARD_FAB2(SCH_1):M_B_ECC'<0>:
 C_SIGNAL='@baseboard_fab2_lib.baseboard_fab2(sch_1):m_b_ecc(0)';
NODE_NAME     U5D1 J70
 '@BASEBOARD_FAB2_LIB.BASEBOARD_FAB2(SCH_1):PAGE24_I172@CHPSET_LIB.SKX_EXT_B(CHIPS)':
 'DDR1_ECC'<0>: CDS_PINID='DDR1_ECC(0)';
NODE_NAME     J4G2 194
 '@BASEBOARD_FAB2_LIB.BASEBOARD_FAB2(SCH_1):PAGE45_I111@MSTR_SCONN.SCONN288_H44441004(CHIPS)':
 'CB'<1>: CDS_PINID='CB(1)';
NODE_NAME     J6U1 49
 '@BASEBOARD_FAB2_LIB.BASEBOARD_FAB2(SCH_1):PAGE46_I14@MSTR_SCONN.SCONN288_H44441003(CHIPS)':
 'CB'<0>: CDS_PINID='CB(0)';
NET_NAME
'M_B_ECC<1>'
 '@BASEBOARD_FAB2_LIB.BASEBOARD_FAB2(SCH_1):M_B_ECC'<1>:
 C_SIGNAL='@baseboard_fab2_lib.baseboard_fab2(sch_1):m_b_ecc(1)';
NODE_NAME     U5D1 H69
 '@BASEBOARD_FAB2_LIB.BASEBOARD_FAB2(SCH_1):PAGE24_I172@CHPSET_LIB.SKX_EXT_B(CHIPS)':
 'DDR1_ECC'<1>: CDS_PINID='DDR1_ECC(1)';
NODE_NAME     J4G2 49
 '@BASEBOARD_FAB2_LIB.BASEBOARD_FAB2(SCH_1):PAGE45_I111@MSTR_SCONN.SCONN288_H44441004(CHIPS)':
 'CB'<0>: CDS_PINID='CB(0)';
NODE_NAME     J6U1 194
 '@BASEBOARD_FAB2_LIB.BASEBOARD_FAB2(SCH_1):PAGE46_I14@MSTR_SCONN.SCONN288_H44441003(CHIPS)':
 'CB'<1>: CDS_PINID='CB(1)';
NET_NAME
'M_B_ECC<2>'
 '@BASEBOARD_FAB2_LIB.BASEBOARD_FAB2(SCH_1):M_B_ECC'<2>:
 C_SIGNAL='@baseboard_fab2_lib.baseboard_fab2(sch_1):m_b_ecc(2)';
NODE_NAME     U5D1 J66
 '@BASEBOARD_FAB2_LIB.BASEBOARD_FAB2(SCH_1):PAGE24_I172@CHPSET_LIB.SKX_EXT_B(CHIPS)':
 'DDR1_ECC'<2>: CDS_PINID='DDR1_ECC(2)';
NODE_NAME     J4G2 201
 '@BASEBOARD_FAB2_LIB.BASEBOARD_FAB2(SCH_1):PAGE45_I111@MSTR_SCONN.SCONN288_H44441004(CHIPS)':
 'CB'<3>: CDS_PINID='CB(3)';
NODE_NAME     J6U1 56
 '@BASEBOARD_FAB2_LIB.BASEBOARD_FAB2(SCH_1):PAGE46_I14@MSTR_SCONN.SCONN288_H44441003(CHIPS)':
 'CB'<2>: CDS_PINID='CB(2)';
NET_NAME
'M_B_ECC<3>'
 '@BASEBOARD_FAB2_LIB.BASEBOARD_FAB2(SCH_1):M_B_ECC'<3>:
 C_SIGNAL='@baseboard_fab2_lib.baseboard_fab2(sch_1):m_b_ecc(3)';
NODE_NAME     U5D1 L66
 '@BASEBOARD_FAB2_LIB.BASEBOARD_FAB2(SCH_1):PAGE24_I172@CHPSET_LIB.SKX_EXT_B(CHIPS)':
 'DDR1_ECC'<3>: CDS_PINID='DDR1_ECC(3)';
NODE_NAME     J4G2 56
 '@BASEBOARD_FAB2_LIB.BASEBOARD_FAB2(SCH_1):PAGE45_I111@MSTR_SCONN.SCONN288_H44441004(CHIPS)':
 'CB'<2>: CDS_PINID='CB(2)';
NODE_NAME     J6U1 201
 '@BASEBOARD_FAB2_LIB.BASEBOARD_FAB2(SCH_1):PAGE46_I14@MSTR_SCONN.SCONN288_H44441003(CHIPS)':
 'CB'<3>: CDS_PINID='CB(3)';
NET_NAME
'M_B_ECC<4>'
 '@BASEBOARD_FAB2_LIB.BASEBOARD_FAB2(SCH_1):M_B_ECC'<4>:
 C_SIGNAL='@baseboard_fab2_lib.baseboard_fab2(sch_1):m_b_ecc(4)';
NODE_NAME     U5D1 L70
 '@BASEBOARD_FAB2_LIB.BASEBOARD_FAB2(SCH_1):PAGE24_I172@CHPSET_LIB.SKX_EXT_B(CHIPS)':
 'DDR1_ECC'<4>: CDS_PINID='DDR1_ECC(4)';
NODE_NAME     J4G2 192
 '@BASEBOARD_FAB2_LIB.BASEBOARD_FAB2(SCH_1):PAGE45_I111@MSTR_SCONN.SCONN288_H44441004(CHIPS)':
 'CB'<5>: CDS_PINID='CB(5)';
NODE_NAME     J6U1 47
 '@BASEBOARD_FAB2_LIB.BASEBOARD_FAB2(SCH_1):PAGE46_I14@MSTR_SCONN.SCONN288_H44441003(CHIPS)':
 'CB'<4>: CDS_PINID='CB(4)';
NET_NAME
'M_B_ECC<5>'
 '@BASEBOARD_FAB2_LIB.BASEBOARD_FAB2(SCH_1):M_B_ECC'<5>:
 C_SIGNAL='@baseboard_fab2_lib.baseboard_fab2(sch_1):m_b_ecc(5)';
NODE_NAME     U5D1 M69
 '@BASEBOARD_FAB2_LIB.BASEBOARD_FAB2(SCH_1):PAGE24_I172@CHPSET_LIB.SKX_EXT_B(CHIPS)':
 'DDR1_ECC'<5>: CDS_PINID='DDR1_ECC(5)';
NODE_NAME     J4G2 47
 '@BASEBOARD_FAB2_LIB.BASEBOARD_FAB2(SCH_1):PAGE45_I111@MSTR_SCONN.SCONN288_H44441004(CHIPS)':
 'CB'<4>: CDS_PINID='CB(4)';
NODE_NAME     J6U1 192
 '@BASEBOARD_FAB2_LIB.BASEBOARD_FAB2(SCH_1):PAGE46_I14@MSTR_SCONN.SCONN288_H44441003(CHIPS)':
 'CB'<5>: CDS_PINID='CB(5)';
NET_NAME
'M_B_ECC<6>'
 '@BASEBOARD_FAB2_LIB.BASEBOARD_FAB2(SCH_1):M_B_ECC'<6>:
 C_SIGNAL='@baseboard_fab2_lib.baseboard_fab2(sch_1):m_b_ecc(6)';
NODE_NAME     U5D1 H67
 '@BASEBOARD_FAB2_LIB.BASEBOARD_FAB2(SCH_1):PAGE24_I172@CHPSET_LIB.SKX_EXT_B(CHIPS)':
 'DDR1_ECC'<6>: CDS_PINID='DDR1_ECC(6)';
NODE_NAME     J4G2 199
 '@BASEBOARD_FAB2_LIB.BASEBOARD_FAB2(SCH_1):PAGE45_I111@MSTR_SCONN.SCONN288_H44441004(CHIPS)':
 'CB'<7>: CDS_PINID='CB(7)';
NODE_NAME     J6U1 54
 '@BASEBOARD_FAB2_LIB.BASEBOARD_FAB2(SCH_1):PAGE46_I14@MSTR_SCONN.SCONN288_H44441003(CHIPS)':
 'CB'<6>: CDS_PINID='CB(6)';
NET_NAME
'M_B_ECC<7>'
 '@BASEBOARD_FAB2_LIB.BASEBOARD_FAB2(SCH_1):M_B_ECC'<7>:
 C_SIGNAL='@baseboard_fab2_lib.baseboard_fab2(sch_1):m_b_ecc(7)';
NODE_NAME     U5D1 M67
 '@BASEBOARD_FAB2_LIB.BASEBOARD_FAB2(SCH_1):PAGE24_I172@CHPSET_LIB.SKX_EXT_B(CHIPS)':
 'DDR1_ECC'<7>: CDS_PINID='DDR1_ECC(7)';
NODE_NAME     J4G2 54
 '@BASEBOARD_FAB2_LIB.BASEBOARD_FAB2(SCH_1):PAGE45_I111@MSTR_SCONN.SCONN288_H44441004(CHIPS)':
 'CB'<6>: CDS_PINID='CB(6)';
NODE_NAME     J6U1 199
 '@BASEBOARD_FAB2_LIB.BASEBOARD_FAB2(SCH_1):PAGE46_I14@MSTR_SCONN.SCONN288_H44441003(CHIPS)':
 'CB'<7>: CDS_PINID='CB(7)';
NET_NAME
'M_B_MA<0>'
 '@BASEBOARD_FAB2_LIB.BASEBOARD_FAB2(SCH_1):M_B_MA'<0>:
 C_SIGNAL='@baseboard_fab2_lib.baseboard_fab2(sch_1):m_b_ma(0)';
NODE_NAME     U5D1 J52
 '@BASEBOARD_FAB2_LIB.BASEBOARD_FAB2(SCH_1):PAGE24_I172@CHPSET_LIB.SKX_EXT_B(CHIPS)':
 'DDR1_MA'<0>: CDS_PINID='DDR1_MA(0)';
NODE_NAME     J4G2 79
 '@BASEBOARD_FAB2_LIB.BASEBOARD_FAB2(SCH_1):PAGE45_I111@MSTR_SCONN.SCONN288_H44441004(CHIPS)':
 'A0': CDS_PINID='A0';
NODE_NAME     J6U1 79
 '@BASEBOARD_FAB2_LIB.BASEBOARD_FAB2(SCH_1):PAGE46_I14@MSTR_SCONN.SCONN288_H44441003(CHIPS)':
 'A0': CDS_PINID='A0';
NET_NAME
'M_B_MA<10>'
 '@BASEBOARD_FAB2_LIB.BASEBOARD_FAB2(SCH_1):M_B_MA'<10>:
 C_SIGNAL='@baseboard_fab2_lib.baseboard_fab2(sch_1):m_b_ma(10)';
NODE_NAME     U5D1 M55
 '@BASEBOARD_FAB2_LIB.BASEBOARD_FAB2(SCH_1):PAGE24_I172@CHPSET_LIB.SKX_EXT_B(CHIPS)':
 'DDR1_MA'<10>: CDS_PINID='DDR1_MA(10)';
NODE_NAME     J4G2 225
 '@BASEBOARD_FAB2_LIB.BASEBOARD_FAB2(SCH_1):PAGE45_I111@MSTR_SCONN.SCONN288_H44441004(CHIPS)':
 'A10': CDS_PINID='A10';
NODE_NAME     J6U1 225
 '@BASEBOARD_FAB2_LIB.BASEBOARD_FAB2(SCH_1):PAGE46_I14@MSTR_SCONN.SCONN288_H44441003(CHIPS)':
 'A10': CDS_PINID='A10';
NET_NAME
'M_B_MA<11>'
 '@BASEBOARD_FAB2_LIB.BASEBOARD_FAB2(SCH_1):M_B_MA'<11>:
 C_SIGNAL='@baseboard_fab2_lib.baseboard_fab2(sch_1):m_b_ma(11)';
NODE_NAME     U5D1 R60
 '@BASEBOARD_FAB2_LIB.BASEBOARD_FAB2(SCH_1):PAGE24_I172@CHPSET_LIB.SKX_EXT_B(CHIPS)':
 'DDR1_MA'<11>: CDS_PINID='DDR1_MA(11)';
NODE_NAME     J4G2 210
 '@BASEBOARD_FAB2_LIB.BASEBOARD_FAB2(SCH_1):PAGE45_I111@MSTR_SCONN.SCONN288_H44441004(CHIPS)':
 'A11': CDS_PINID='A11';
NODE_NAME     J6U1 210
 '@BASEBOARD_FAB2_LIB.BASEBOARD_FAB2(SCH_1):PAGE46_I14@MSTR_SCONN.SCONN288_H44441003(CHIPS)':
 'A11': CDS_PINID='A11';
NET_NAME
'M_B_MA<12>'
 '@BASEBOARD_FAB2_LIB.BASEBOARD_FAB2(SCH_1):M_B_MA'<12>:
 C_SIGNAL='@baseboard_fab2_lib.baseboard_fab2(sch_1):m_b_ma(12)';
NODE_NAME     U5D1 T61
 '@BASEBOARD_FAB2_LIB.BASEBOARD_FAB2(SCH_1):PAGE24_I172@CHPSET_LIB.SKX_EXT_B(CHIPS)':
 'DDR1_MA'<12>: CDS_PINID='DDR1_MA(12)';
NODE_NAME     J4G2 65
 '@BASEBOARD_FAB2_LIB.BASEBOARD_FAB2(SCH_1):PAGE45_I111@MSTR_SCONN.SCONN288_H44441004(CHIPS)':
 'A12': CDS_PINID='A12';
NODE_NAME     J6U1 65
 '@BASEBOARD_FAB2_LIB.BASEBOARD_FAB2(SCH_1):PAGE46_I14@MSTR_SCONN.SCONN288_H44441003(CHIPS)':
 'A12': CDS_PINID='A12';
NET_NAME
'M_B_MA<13>'
 '@BASEBOARD_FAB2_LIB.BASEBOARD_FAB2(SCH_1):M_B_MA'<13>:
 C_SIGNAL='@baseboard_fab2_lib.baseboard_fab2(sch_1):m_b_ma(13)';
NODE_NAME     U5D1 M51
 '@BASEBOARD_FAB2_LIB.BASEBOARD_FAB2(SCH_1):PAGE24_I172@CHPSET_LIB.SKX_EXT_B(CHIPS)':
 'DDR1_MA'<13>: CDS_PINID='DDR1_MA(13)';
NODE_NAME     J4G2 232
 '@BASEBOARD_FAB2_LIB.BASEBOARD_FAB2(SCH_1):PAGE45_I111@MSTR_SCONN.SCONN288_H44441004(CHIPS)':
 'A13': CDS_PINID='A13';
NODE_NAME     J6U1 232
 '@BASEBOARD_FAB2_LIB.BASEBOARD_FAB2(SCH_1):PAGE46_I14@MSTR_SCONN.SCONN288_H44441003(CHIPS)':
 'A13': CDS_PINID='A13';
NET_NAME
'M_B_MA<14>'
 '@BASEBOARD_FAB2_LIB.BASEBOARD_FAB2(SCH_1):M_B_MA'<14>:
 C_SIGNAL='@baseboard_fab2_lib.baseboard_fab2(sch_1):m_b_ma(14)';
NODE_NAME     U5D1 T51
 '@BASEBOARD_FAB2_LIB.BASEBOARD_FAB2(SCH_1):PAGE24_I172@CHPSET_LIB.SKX_EXT_B(CHIPS)':
 'DDR1_MA'<14>: CDS_PINID='DDR1_MA(14)';
NODE_NAME     J4G2 228
 '@BASEBOARD_FAB2_LIB.BASEBOARD_FAB2(SCH_1):PAGE45_I111@MSTR_SCONN.SCONN288_H44441004(CHIPS)':
 'A14_WE_N': CDS_PINID='A14_WE_N';
NODE_NAME     J6U1 228
 '@BASEBOARD_FAB2_LIB.BASEBOARD_FAB2(SCH_1):PAGE46_I14@MSTR_SCONN.SCONN288_H44441003(CHIPS)':
 'A14_WE_N': CDS_PINID='A14_WE_N';
NET_NAME
'M_B_MA<15>'
 '@BASEBOARD_FAB2_LIB.BASEBOARD_FAB2(SCH_1):M_B_MA'<15>:
 C_SIGNAL='@baseboard_fab2_lib.baseboard_fab2(sch_1):m_b_ma(15)';
NODE_NAME     U5D1 N52
 '@BASEBOARD_FAB2_LIB.BASEBOARD_FAB2(SCH_1):PAGE24_I172@CHPSET_LIB.SKX_EXT_B(CHIPS)':
 'DDR1_MA'<15>: CDS_PINID='DDR1_MA(15)';
NODE_NAME     J4G2 86
 '@BASEBOARD_FAB2_LIB.BASEBOARD_FAB2(SCH_1):PAGE45_I111@MSTR_SCONN.SCONN288_H44441004(CHIPS)':
 'A15_CAS_N': CDS_PINID='A15_CAS_N';
NODE_NAME     J6U1 86
 '@BASEBOARD_FAB2_LIB.BASEBOARD_FAB2(SCH_1):PAGE46_I14@MSTR_SCONN.SCONN288_H44441003(CHIPS)':
 'A15_CAS_N': CDS_PINID='A15_CAS_N';
NET_NAME
'M_B_MA<16>'
 '@BASEBOARD_FAB2_LIB.BASEBOARD_FAB2(SCH_1):M_B_MA'<16>:
 C_SIGNAL='@baseboard_fab2_lib.baseboard_fab2(sch_1):m_b_ma(16)';
NODE_NAME     U5D1 R52
 '@BASEBOARD_FAB2_LIB.BASEBOARD_FAB2(SCH_1):PAGE24_I172@CHPSET_LIB.SKX_EXT_B(CHIPS)':
 'DDR1_MA'<16>: CDS_PINID='DDR1_MA(16)';
NODE_NAME     J4G2 82
 '@BASEBOARD_FAB2_LIB.BASEBOARD_FAB2(SCH_1):PAGE45_I111@MSTR_SCONN.SCONN288_H44441004(CHIPS)':
 'A16_RAS_N': CDS_PINID='A16_RAS_N';
NODE_NAME     J6U1 82
 '@BASEBOARD_FAB2_LIB.BASEBOARD_FAB2(SCH_1):PAGE46_I14@MSTR_SCONN.SCONN288_H44441003(CHIPS)':
 'A16_RAS_N': CDS_PINID='A16_RAS_N';
NET_NAME
'M_B_MA<17>'
 '@BASEBOARD_FAB2_LIB.BASEBOARD_FAB2(SCH_1):M_B_MA'<17>:
 C_SIGNAL='@baseboard_fab2_lib.baseboard_fab2(sch_1):m_b_ma(17)';
NODE_NAME     U5D1 N48
 '@BASEBOARD_FAB2_LIB.BASEBOARD_FAB2(SCH_1):PAGE24_I172@CHPSET_LIB.SKX_EXT_B(CHIPS)':
 'DDR1_MA'<17>: CDS_PINID='DDR1_MA(17)';
NODE_NAME     J4G2 234
 '@BASEBOARD_FAB2_LIB.BASEBOARD_FAB2(SCH_1):PAGE45_I111@MSTR_SCONN.SCONN288_H44441004(CHIPS)':
 'A17': CDS_PINID='A17';
NODE_NAME     J6U1 234
 '@BASEBOARD_FAB2_LIB.BASEBOARD_FAB2(SCH_1):PAGE46_I14@MSTR_SCONN.SCONN288_H44441003(CHIPS)':
 'A17': CDS_PINID='A17';
NET_NAME
'M_B_MA<1>'
 '@BASEBOARD_FAB2_LIB.BASEBOARD_FAB2(SCH_1):M_B_MA'<1>:
 C_SIGNAL='@baseboard_fab2_lib.baseboard_fab2(sch_1):m_b_ma(1)';
NODE_NAME     U5D1 J58
 '@BASEBOARD_FAB2_LIB.BASEBOARD_FAB2(SCH_1):PAGE24_I172@CHPSET_LIB.SKX_EXT_B(CHIPS)':
 'DDR1_MA'<1>: CDS_PINID='DDR1_MA(1)';
NODE_NAME     J4G2 72
 '@BASEBOARD_FAB2_LIB.BASEBOARD_FAB2(SCH_1):PAGE45_I111@MSTR_SCONN.SCONN288_H44441004(CHIPS)':
 'A1': CDS_PINID='A1';
NODE_NAME     J6U1 72
 '@BASEBOARD_FAB2_LIB.BASEBOARD_FAB2(SCH_1):PAGE46_I14@MSTR_SCONN.SCONN288_H44441003(CHIPS)':
 'A1': CDS_PINID='A1';
NET_NAME
'M_B_MA<2>'
 '@BASEBOARD_FAB2_LIB.BASEBOARD_FAB2(SCH_1):M_B_MA'<2>:
 C_SIGNAL='@baseboard_fab2_lib.baseboard_fab2(sch_1):m_b_ma(2)';
NODE_NAME     U5D1 K57
 '@BASEBOARD_FAB2_LIB.BASEBOARD_FAB2(SCH_1):PAGE24_I172@CHPSET_LIB.SKX_EXT_B(CHIPS)':
 'DDR1_MA'<2>: CDS_PINID='DDR1_MA(2)';
NODE_NAME     J4G2 216
 '@BASEBOARD_FAB2_LIB.BASEBOARD_FAB2(SCH_1):PAGE45_I111@MSTR_SCONN.SCONN288_H44441004(CHIPS)':
 'A2': CDS_PINID='A2';
NODE_NAME     J6U1 216
 '@BASEBOARD_FAB2_LIB.BASEBOARD_FAB2(SCH_1):PAGE46_I14@MSTR_SCONN.SCONN288_H44441003(CHIPS)':
 'A2': CDS_PINID='A2';
NET_NAME
'M_B_MA<3>'
 '@BASEBOARD_FAB2_LIB.BASEBOARD_FAB2(SCH_1):M_B_MA'<3>:
 C_SIGNAL='@baseboard_fab2_lib.baseboard_fab2(sch_1):m_b_ma(3)';
NODE_NAME     U5D1 N58
 '@BASEBOARD_FAB2_LIB.BASEBOARD_FAB2(SCH_1):PAGE24_I172@CHPSET_LIB.SKX_EXT_B(CHIPS)':
 'DDR1_MA'<3>: CDS_PINID='DDR1_MA(3)';
NODE_NAME     J4G2 71
 '@BASEBOARD_FAB2_LIB.BASEBOARD_FAB2(SCH_1):PAGE45_I111@MSTR_SCONN.SCONN288_H44441004(CHIPS)':
 'A3': CDS_PINID='A3';
NODE_NAME     J6U1 71
 '@BASEBOARD_FAB2_LIB.BASEBOARD_FAB2(SCH_1):PAGE46_I14@MSTR_SCONN.SCONN288_H44441003(CHIPS)':
 'A3': CDS_PINID='A3';
NET_NAME
'M_B_MA<4>'
 '@BASEBOARD_FAB2_LIB.BASEBOARD_FAB2(SCH_1):M_B_MA'<4>:
 C_SIGNAL='@baseboard_fab2_lib.baseboard_fab2(sch_1):m_b_ma(4)';
NODE_NAME     U5D1 M59
 '@BASEBOARD_FAB2_LIB.BASEBOARD_FAB2(SCH_1):PAGE24_I172@CHPSET_LIB.SKX_EXT_B(CHIPS)':
 'DDR1_MA'<4>: CDS_PINID='DDR1_MA(4)';
NODE_NAME     J4G2 214
 '@BASEBOARD_FAB2_LIB.BASEBOARD_FAB2(SCH_1):PAGE45_I111@MSTR_SCONN.SCONN288_H44441004(CHIPS)':
 'A4': CDS_PINID='A4';
NODE_NAME     J6U1 214
 '@BASEBOARD_FAB2_LIB.BASEBOARD_FAB2(SCH_1):PAGE46_I14@MSTR_SCONN.SCONN288_H44441003(CHIPS)':
 'A4': CDS_PINID='A4';
NET_NAME
'M_B_MA<5>'
 '@BASEBOARD_FAB2_LIB.BASEBOARD_FAB2(SCH_1):M_B_MA'<5>:
 C_SIGNAL='@baseboard_fab2_lib.baseboard_fab2(sch_1):m_b_ma(5)';
NODE_NAME     U5D1 R58
 '@BASEBOARD_FAB2_LIB.BASEBOARD_FAB2(SCH_1):PAGE24_I172@CHPSET_LIB.SKX_EXT_B(CHIPS)':
 'DDR1_MA'<5>: CDS_PINID='DDR1_MA(5)';
NODE_NAME     J4G2 213
 '@BASEBOARD_FAB2_LIB.BASEBOARD_FAB2(SCH_1):PAGE45_I111@MSTR_SCONN.SCONN288_H44441004(CHIPS)':
 'A5': CDS_PINID='A5';
NODE_NAME     J6U1 213
 '@BASEBOARD_FAB2_LIB.BASEBOARD_FAB2(SCH_1):PAGE46_I14@MSTR_SCONN.SCONN288_H44441003(CHIPS)':
 'A5': CDS_PINID='A5';
NET_NAME
'M_B_MA<6>'
 '@BASEBOARD_FAB2_LIB.BASEBOARD_FAB2(SCH_1):M_B_MA'<6>:
 C_SIGNAL='@baseboard_fab2_lib.baseboard_fab2(sch_1):m_b_ma(6)';
NODE_NAME     U5D1 T59
 '@BASEBOARD_FAB2_LIB.BASEBOARD_FAB2(SCH_1):PAGE24_I172@CHPSET_LIB.SKX_EXT_B(CHIPS)':
 'DDR1_MA'<6>: CDS_PINID='DDR1_MA(6)';
NODE_NAME     J4G2 69
 '@BASEBOARD_FAB2_LIB.BASEBOARD_FAB2(SCH_1):PAGE45_I111@MSTR_SCONN.SCONN288_H44441004(CHIPS)':
 'A6': CDS_PINID='A6';
NODE_NAME     J6U1 69
 '@BASEBOARD_FAB2_LIB.BASEBOARD_FAB2(SCH_1):PAGE46_I14@MSTR_SCONN.SCONN288_H44441003(CHIPS)':
 'A6': CDS_PINID='A6';
NET_NAME
'M_B_MA<7>'
 '@BASEBOARD_FAB2_LIB.BASEBOARD_FAB2(SCH_1):M_B_MA'<7>:
 C_SIGNAL='@baseboard_fab2_lib.baseboard_fab2(sch_1):m_b_ma(7)';
NODE_NAME     U5D1 V61
 '@BASEBOARD_FAB2_LIB.BASEBOARD_FAB2(SCH_1):PAGE24_I172@CHPSET_LIB.SKX_EXT_B(CHIPS)':
 'DDR1_MA'<7>: CDS_PINID='DDR1_MA(7)';
NODE_NAME     J4G2 211
 '@BASEBOARD_FAB2_LIB.BASEBOARD_FAB2(SCH_1):PAGE45_I111@MSTR_SCONN.SCONN288_H44441004(CHIPS)':
 'A7': CDS_PINID='A7';
NODE_NAME     J6U1 211
 '@BASEBOARD_FAB2_LIB.BASEBOARD_FAB2(SCH_1):PAGE46_I14@MSTR_SCONN.SCONN288_H44441003(CHIPS)':
 'A7': CDS_PINID='A7';
NET_NAME
'M_B_MA<8>'
 '@BASEBOARD_FAB2_LIB.BASEBOARD_FAB2(SCH_1):M_B_MA'<8>:
 C_SIGNAL='@baseboard_fab2_lib.baseboard_fab2(sch_1):m_b_ma(8)';
NODE_NAME     U5D1 W60
 '@BASEBOARD_FAB2_LIB.BASEBOARD_FAB2(SCH_1):PAGE24_I172@CHPSET_LIB.SKX_EXT_B(CHIPS)':
 'DDR1_MA'<8>: CDS_PINID='DDR1_MA(8)';
NODE_NAME     J4G2 68
 '@BASEBOARD_FAB2_LIB.BASEBOARD_FAB2(SCH_1):PAGE45_I111@MSTR_SCONN.SCONN288_H44441004(CHIPS)':
 'A8': CDS_PINID='A8';
NODE_NAME     J6U1 68
 '@BASEBOARD_FAB2_LIB.BASEBOARD_FAB2(SCH_1):PAGE46_I14@MSTR_SCONN.SCONN288_H44441003(CHIPS)':
 'A8': CDS_PINID='A8';
NET_NAME
'M_B_MA<9>'
 '@BASEBOARD_FAB2_LIB.BASEBOARD_FAB2(SCH_1):M_B_MA'<9>:
 C_SIGNAL='@baseboard_fab2_lib.baseboard_fab2(sch_1):m_b_ma(9)';
NODE_NAME     U5D1 K59
 '@BASEBOARD_FAB2_LIB.BASEBOARD_FAB2(SCH_1):PAGE24_I172@CHPSET_LIB.SKX_EXT_B(CHIPS)':
 'DDR1_MA'<9>: CDS_PINID='DDR1_MA(9)';
NODE_NAME     J4G2 66
 '@BASEBOARD_FAB2_LIB.BASEBOARD_FAB2(SCH_1):PAGE45_I111@MSTR_SCONN.SCONN288_H44441004(CHIPS)':
 'A9': CDS_PINID='A9';
NODE_NAME     J6U1 66
 '@BASEBOARD_FAB2_LIB.BASEBOARD_FAB2(SCH_1):PAGE46_I14@MSTR_SCONN.SCONN288_H44441003(CHIPS)':
 'A9': CDS_PINID='A9';
NET_NAME
'M_B_ODT<0>'
 '@BASEBOARD_FAB2_LIB.BASEBOARD_FAB2(SCH_1):M_B_ODT'<0>:
 C_SIGNAL='@baseboard_fab2_lib.baseboard_fab2(sch_1):m_b_odt(0)';
NODE_NAME     U5D1 N50
 '@BASEBOARD_FAB2_LIB.BASEBOARD_FAB2(SCH_1):PAGE24_I172@CHPSET_LIB.SKX_EXT_B(CHIPS)':
 'DDR1_ODT'<0>: CDS_PINID='DDR1_ODT(0)';
NODE_NAME     J4G2 87
 '@BASEBOARD_FAB2_LIB.BASEBOARD_FAB2(SCH_1):PAGE45_I111@MSTR_SCONN.SCONN288_H44441004(CHIPS)':
 'ODT'<0>: CDS_PINID='ODT(0)';
NET_NAME
'M_B_ODT<1>'
 '@BASEBOARD_FAB2_LIB.BASEBOARD_FAB2(SCH_1):M_B_ODT'<1>:
 C_SIGNAL='@baseboard_fab2_lib.baseboard_fab2(sch_1):m_b_odt(1)';
NODE_NAME     U5D1 R48
 '@BASEBOARD_FAB2_LIB.BASEBOARD_FAB2(SCH_1):PAGE24_I172@CHPSET_LIB.SKX_EXT_B(CHIPS)':
 'DDR1_ODT'<1>: CDS_PINID='DDR1_ODT(1)';
NODE_NAME     J4G2 91
 '@BASEBOARD_FAB2_LIB.BASEBOARD_FAB2(SCH_1):PAGE45_I111@MSTR_SCONN.SCONN288_H44441004(CHIPS)':
 'ODT'<1>: CDS_PINID='ODT(1)';
NET_NAME
'M_B_ODT<2>'
 '@BASEBOARD_FAB2_LIB.BASEBOARD_FAB2(SCH_1):M_B_ODT'<2>:
 C_SIGNAL='@baseboard_fab2_lib.baseboard_fab2(sch_1):m_b_odt(2)';
NODE_NAME     U5D1 M49
 '@BASEBOARD_FAB2_LIB.BASEBOARD_FAB2(SCH_1):PAGE24_I172@CHPSET_LIB.SKX_EXT_B(CHIPS)':
 'DDR1_ODT'<2>: CDS_PINID='DDR1_ODT(2)';
NODE_NAME     J6U1 87
 '@BASEBOARD_FAB2_LIB.BASEBOARD_FAB2(SCH_1):PAGE46_I14@MSTR_SCONN.SCONN288_H44441003(CHIPS)':
 'ODT'<0>: CDS_PINID='ODT(0)';
NET_NAME
'M_B_ODT<3>'
 '@BASEBOARD_FAB2_LIB.BASEBOARD_FAB2(SCH_1):M_B_ODT'<3>:
 C_SIGNAL='@baseboard_fab2_lib.baseboard_fab2(sch_1):m_b_odt(3)';
NODE_NAME     U5D1 T47
 '@BASEBOARD_FAB2_LIB.BASEBOARD_FAB2(SCH_1):PAGE24_I172@CHPSET_LIB.SKX_EXT_B(CHIPS)':
 'DDR1_ODT'<3>: CDS_PINID='DDR1_ODT(3)';
NODE_NAME     J6U1 91
 '@BASEBOARD_FAB2_LIB.BASEBOARD_FAB2(SCH_1):PAGE46_I14@MSTR_SCONN.SCONN288_H44441003(CHIPS)':
 'ODT'<1>: CDS_PINID='ODT(1)';
NET_NAME
'M_B_PAR'
 '@BASEBOARD_FAB2_LIB.BASEBOARD_FAB2(SCH_1):M_B_PAR':
 C_SIGNAL='@baseboard_fab2_lib.baseboard_fab2(sch_1):m_b_par';
NODE_NAME     U5D1 K53
 '@BASEBOARD_FAB2_LIB.BASEBOARD_FAB2(SCH_1):PAGE24_I172@CHPSET_LIB.SKX_EXT_B(CHIPS)':
 'DDR1_PAR': CDS_PINID='DDR1_PAR';
NODE_NAME     J4G2 222
 '@BASEBOARD_FAB2_LIB.BASEBOARD_FAB2(SCH_1):PAGE45_I111@MSTR_SCONN.SCONN288_H44441004(CHIPS)':
 'PAR': CDS_PINID='PAR';
NODE_NAME     J6U1 222
 '@BASEBOARD_FAB2_LIB.BASEBOARD_FAB2(SCH_1):PAGE46_I14@MSTR_SCONN.SCONN288_H44441003(CHIPS)':
 'PAR': CDS_PINID='PAR';
NET_NAME
'M_B_VREF'
 '@BASEBOARD_FAB2_LIB.BASEBOARD_FAB2(SCH_1):M_B_VREF':
 C_SIGNAL='@baseboard_fab2_lib.baseboard_fab2(sch_1):m_b_vref';
NODE_NAME     J4G2 146
 '@BASEBOARD_FAB2_LIB.BASEBOARD_FAB2(SCH_1):PAGE45_I111@MSTR_SCONN.SCONN288_H44441004(CHIPS)':
 'VREFCA': CDS_PINID='VREFCA';
NODE_NAME     C4G3 1
 '@BASEBOARD_FAB2_LIB.BASEBOARD_FAB2(SCH_1):PAGE45_I179@DEV_DISCRETE.CAP_A(CHIPS)':
 'A': CDS_PINID='A';
NODE_NAME     C6U9 1
 '@BASEBOARD_FAB2_LIB.BASEBOARD_FAB2(SCH_1):PAGE46_I5@DEV_DISCRETE.CAP_A(CHIPS)':
 'A': CDS_PINID='A';
NODE_NAME     J6U1 146
 '@BASEBOARD_FAB2_LIB.BASEBOARD_FAB2(SCH_1):PAGE46_I14@MSTR_SCONN.SCONN288_H44441003(CHIPS)':
 'VREFCA': CDS_PINID='VREFCA';
NODE_NAME     R4G2 2
 '@BASEBOARD_FAB2_LIB.BASEBOARD_FAB2(SCH_1):PAGE98_I38@MSTR_DISCRETE.RES(CHIPS)':
 'B': CDS_PINID='B';
NODE_NAME     R4G3 1
 '@BASEBOARD_FAB2_LIB.BASEBOARD_FAB2(SCH_1):PAGE98_I40@MSTR_DISCRETE.RES(CHIPS)':
 'A': CDS_PINID='A';
NODE_NAME     R4G1 2
 '@BASEBOARD_FAB2_LIB.BASEBOARD_FAB2(SCH_1):PAGE98_I42@MSTR_DISCRETE.RES(CHIPS)':
 'B': CDS_PINID='B';
NET_NAME
'M_C_ACT_N'
 '@BASEBOARD_FAB2_LIB.BASEBOARD_FAB2(SCH_1):M_C_ACT_N':
 C_SIGNAL='@baseboard_fab2_lib.baseboard_fab2(sch_1):m_c_act_n';
NODE_NAME     U5D1 AB61
 '@BASEBOARD_FAB2_LIB.BASEBOARD_FAB2(SCH_1):PAGE25_I172@CHPSET_LIB.SKX_EXT_B(CHIPS)':
 'DDR2_ACT_N': CDS_PINID='DDR2_ACT_N';
NODE_NAME     J4G3 62
 '@BASEBOARD_FAB2_LIB.BASEBOARD_FAB2(SCH_1):PAGE47_I111@MSTR_SCONN.SCONN288_H44441004(CHIPS)':
 'ACT_N': CDS_PINID='ACT_N';
NODE_NAME     J6U2 62
 '@BASEBOARD_FAB2_LIB.BASEBOARD_FAB2(SCH_1):PAGE48_I111@MSTR_SCONN.SCONN288_H44441003(CHIPS)':
 'ACT_N': CDS_PINID='ACT_N';
NET_NAME
'M_C_ALERT_N'
 '@BASEBOARD_FAB2_LIB.BASEBOARD_FAB2(SCH_1):M_C_ALERT_N':
 C_SIGNAL='@baseboard_fab2_lib.baseboard_fab2(sch_1):m_c_alert_n';
NODE_NAME     U5D1 AD61
 '@BASEBOARD_FAB2_LIB.BASEBOARD_FAB2(SCH_1):PAGE25_I172@CHPSET_LIB.SKX_EXT_B(CHIPS)':
 'DDR2_ALERT_N': CDS_PINID='DDR2_ALERT_N';
NODE_NAME     J4G3 208
 '@BASEBOARD_FAB2_LIB.BASEBOARD_FAB2(SCH_1):PAGE47_I111@MSTR_SCONN.SCONN288_H44441004(CHIPS)':
 'ALERT_N': CDS_PINID='ALERT_N';
NODE_NAME     J6U2 208
 '@BASEBOARD_FAB2_LIB.BASEBOARD_FAB2(SCH_1):PAGE48_I111@MSTR_SCONN.SCONN288_H44441003(CHIPS)':
 'ALERT_N': CDS_PINID='ALERT_N';
NET_NAME
'M_C_BA<0>'
 '@BASEBOARD_FAB2_LIB.BASEBOARD_FAB2(SCH_1):M_C_BA'<0>:
 C_SIGNAL='@baseboard_fab2_lib.baseboard_fab2(sch_1):m_c_ba(0)';
NODE_NAME     U5D1 W52
 '@BASEBOARD_FAB2_LIB.BASEBOARD_FAB2(SCH_1):PAGE25_I172@CHPSET_LIB.SKX_EXT_B(CHIPS)':
 'DDR2_BA'<0>: CDS_PINID='DDR2_BA(0)';
NODE_NAME     J4G3 81
 '@BASEBOARD_FAB2_LIB.BASEBOARD_FAB2(SCH_1):PAGE47_I111@MSTR_SCONN.SCONN288_H44441004(CHIPS)':
 'BA'<0>: CDS_PINID='BA(0)';
NODE_NAME     J6U2 81
 '@BASEBOARD_FAB2_LIB.BASEBOARD_FAB2(SCH_1):PAGE48_I111@MSTR_SCONN.SCONN288_H44441003(CHIPS)':
 'BA'<0>: CDS_PINID='BA(0)';
NET_NAME
'M_C_BA<1>'
 '@BASEBOARD_FAB2_LIB.BASEBOARD_FAB2(SCH_1):M_C_BA'<1>:
 C_SIGNAL='@baseboard_fab2_lib.baseboard_fab2(sch_1):m_c_ba(1)';
NODE_NAME     U5D1 AE56
 '@BASEBOARD_FAB2_LIB.BASEBOARD_FAB2(SCH_1):PAGE25_I172@CHPSET_LIB.SKX_EXT_B(CHIPS)':
 'DDR2_BA'<1>: CDS_PINID='DDR2_BA(1)';
NODE_NAME     J4G3 224
 '@BASEBOARD_FAB2_LIB.BASEBOARD_FAB2(SCH_1):PAGE47_I111@MSTR_SCONN.SCONN288_H44441004(CHIPS)':
 'BA'<1>: CDS_PINID='BA(1)';
NODE_NAME     J6U2 224
 '@BASEBOARD_FAB2_LIB.BASEBOARD_FAB2(SCH_1):PAGE48_I111@MSTR_SCONN.SCONN288_H44441003(CHIPS)':
 'BA'<1>: CDS_PINID='BA(1)';
NET_NAME
'M_C_BG<0>'
 '@BASEBOARD_FAB2_LIB.BASEBOARD_FAB2(SCH_1):M_C_BG'<0>:
 C_SIGNAL='@baseboard_fab2_lib.baseboard_fab2(sch_1):m_c_bg(0)';
NODE_NAME     U5D1 AA60
 '@BASEBOARD_FAB2_LIB.BASEBOARD_FAB2(SCH_1):PAGE25_I172@CHPSET_LIB.SKX_EXT_B(CHIPS)':
 'DDR2_BG'<0>: CDS_PINID='DDR2_BG(0)';
NODE_NAME     J4G3 63
 '@BASEBOARD_FAB2_LIB.BASEBOARD_FAB2(SCH_1):PAGE47_I111@MSTR_SCONN.SCONN288_H44441004(CHIPS)':
 'BG'<0>: CDS_PINID='BG(0)';
NODE_NAME     J6U2 63
 '@BASEBOARD_FAB2_LIB.BASEBOARD_FAB2(SCH_1):PAGE48_I111@MSTR_SCONN.SCONN288_H44441003(CHIPS)':
 'BG'<0>: CDS_PINID='BG(0)';
NET_NAME
'M_C_BG<1>'
 '@BASEBOARD_FAB2_LIB.BASEBOARD_FAB2(SCH_1):M_C_BG'<1>:
 C_SIGNAL='@baseboard_fab2_lib.baseboard_fab2(sch_1):m_c_bg(1)';
NODE_NAME     U5D1 AE62
 '@BASEBOARD_FAB2_LIB.BASEBOARD_FAB2(SCH_1):PAGE25_I172@CHPSET_LIB.SKX_EXT_B(CHIPS)':
 'DDR2_BG'<1>: CDS_PINID='DDR2_BG(1)';
NODE_NAME     J4G3 207
 '@BASEBOARD_FAB2_LIB.BASEBOARD_FAB2(SCH_1):PAGE47_I111@MSTR_SCONN.SCONN288_H44441004(CHIPS)':
 'BG'<1>: CDS_PINID='BG(1)';
NODE_NAME     J6U2 207
 '@BASEBOARD_FAB2_LIB.BASEBOARD_FAB2(SCH_1):PAGE48_I111@MSTR_SCONN.SCONN288_H44441003(CHIPS)':
 'BG'<1>: CDS_PINID='BG(1)';
NET_NAME
'M_C_C<2>'
 '@BASEBOARD_FAB2_LIB.BASEBOARD_FAB2(SCH_1):M_C_C'<2>:
 C_SIGNAL='@baseboard_fab2_lib.baseboard_fab2(sch_1):m_c_c(2)';
NODE_NAME     U5D1 AB45
 '@BASEBOARD_FAB2_LIB.BASEBOARD_FAB2(SCH_1):PAGE25_I172@CHPSET_LIB.SKX_EXT_B(CHIPS)':
 'DDR2_CID'<2>: CDS_PINID='DDR2_CID(2)';
NODE_NAME     J4G3 235
 '@BASEBOARD_FAB2_LIB.BASEBOARD_FAB2(SCH_1):PAGE47_I111@MSTR_SCONN.SCONN288_H44441004(CHIPS)':
 'C'<2>: CDS_PINID='C(2)';
NODE_NAME     J6U2 235
 '@BASEBOARD_FAB2_LIB.BASEBOARD_FAB2(SCH_1):PAGE48_I111@MSTR_SCONN.SCONN288_H44441003(CHIPS)':
 'C'<2>: CDS_PINID='C(2)';
NET_NAME
'M_C_CKE<0>'
 '@BASEBOARD_FAB2_LIB.BASEBOARD_FAB2(SCH_1):M_C_CKE'<0>:
 C_SIGNAL='@baseboard_fab2_lib.baseboard_fab2(sch_1):m_c_cke(0)';
NODE_NAME     U5D1 AA62
 '@BASEBOARD_FAB2_LIB.BASEBOARD_FAB2(SCH_1):PAGE25_I172@CHPSET_LIB.SKX_EXT_B(CHIPS)':
 'DDR2_CKE'<0>: CDS_PINID='DDR2_CKE(0)';
NODE_NAME     J4G3 60
 '@BASEBOARD_FAB2_LIB.BASEBOARD_FAB2(SCH_1):PAGE47_I111@MSTR_SCONN.SCONN288_H44441004(CHIPS)':
 'CKE'<0>: CDS_PINID='CKE(0)';
NET_NAME
'M_C_CKE<1>'
 '@BASEBOARD_FAB2_LIB.BASEBOARD_FAB2(SCH_1):M_C_CKE'<1>:
 C_SIGNAL='@baseboard_fab2_lib.baseboard_fab2(sch_1):m_c_cke(1)';
NODE_NAME     U5D1 AD63
 '@BASEBOARD_FAB2_LIB.BASEBOARD_FAB2(SCH_1):PAGE25_I172@CHPSET_LIB.SKX_EXT_B(CHIPS)':
 'DDR2_CKE'<1>: CDS_PINID='DDR2_CKE(1)';
NODE_NAME     J4G3 203
 '@BASEBOARD_FAB2_LIB.BASEBOARD_FAB2(SCH_1):PAGE47_I111@MSTR_SCONN.SCONN288_H44441004(CHIPS)':
 'CKE'<1>: CDS_PINID='CKE(1)';
NET_NAME
'M_C_CKE<2>'
 '@BASEBOARD_FAB2_LIB.BASEBOARD_FAB2(SCH_1):M_C_CKE'<2>:
 C_SIGNAL='@baseboard_fab2_lib.baseboard_fab2(sch_1):m_c_cke(2)';
NODE_NAME     U5D1 V63
 '@BASEBOARD_FAB2_LIB.BASEBOARD_FAB2(SCH_1):PAGE25_I172@CHPSET_LIB.SKX_EXT_B(CHIPS)':
 'DDR2_CKE'<2>: CDS_PINID='DDR2_CKE(2)';
NODE_NAME     J6U2 60
 '@BASEBOARD_FAB2_LIB.BASEBOARD_FAB2(SCH_1):PAGE48_I111@MSTR_SCONN.SCONN288_H44441003(CHIPS)':
 'CKE'<0>: CDS_PINID='CKE(0)';
NET_NAME
'M_C_CKE<3>'
 '@BASEBOARD_FAB2_LIB.BASEBOARD_FAB2(SCH_1):M_C_CKE'<3>:
 C_SIGNAL='@baseboard_fab2_lib.baseboard_fab2(sch_1):m_c_cke(3)';
NODE_NAME     U5D1 AB63
 '@BASEBOARD_FAB2_LIB.BASEBOARD_FAB2(SCH_1):PAGE25_I172@CHPSET_LIB.SKX_EXT_B(CHIPS)':
 'DDR2_CKE'<3>: CDS_PINID='DDR2_CKE(3)';
NODE_NAME     J6U2 203
 '@BASEBOARD_FAB2_LIB.BASEBOARD_FAB2(SCH_1):PAGE48_I111@MSTR_SCONN.SCONN288_H44441003(CHIPS)':
 'CKE'<1>: CDS_PINID='CKE(1)';
NET_NAME
'M_C_CLK_DN<0>'
 '@BASEBOARD_FAB2_LIB.BASEBOARD_FAB2(SCH_1):M_C_CLK_DN'<0>:
 C_SIGNAL='@baseboard_fab2_lib.baseboard_fab2(sch_1):m_c_clk_dn(0)';
NODE_NAME     U5D1 AA54
 '@BASEBOARD_FAB2_LIB.BASEBOARD_FAB2(SCH_1):PAGE25_I172@CHPSET_LIB.SKX_EXT_B(CHIPS)':
 'DDR2_CLK_DN'<0>: CDS_PINID='DDR2_CLK_DN(0)';
NODE_NAME     J4G3 75
 '@BASEBOARD_FAB2_LIB.BASEBOARD_FAB2(SCH_1):PAGE47_I111@MSTR_SCONN.SCONN288_H44441004(CHIPS)':
 'CK0N': CDS_PINID='CK0N';
NET_NAME
'M_C_CLK_DN<1>'
 '@BASEBOARD_FAB2_LIB.BASEBOARD_FAB2(SCH_1):M_C_CLK_DN'<1>:
 C_SIGNAL='@baseboard_fab2_lib.baseboard_fab2(sch_1):m_c_clk_dn(1)';
NODE_NAME     U5D1 W54
 '@BASEBOARD_FAB2_LIB.BASEBOARD_FAB2(SCH_1):PAGE25_I172@CHPSET_LIB.SKX_EXT_B(CHIPS)':
 'DDR2_CLK_DN'<1>: CDS_PINID='DDR2_CLK_DN(1)';
NODE_NAME     J4G3 219
 '@BASEBOARD_FAB2_LIB.BASEBOARD_FAB2(SCH_1):PAGE47_I111@MSTR_SCONN.SCONN288_H44441004(CHIPS)':
 'CK1N': CDS_PINID='CK1N';
NET_NAME
'M_C_CLK_DN<2>'
 '@BASEBOARD_FAB2_LIB.BASEBOARD_FAB2(SCH_1):M_C_CLK_DN'<2>:
 C_SIGNAL='@baseboard_fab2_lib.baseboard_fab2(sch_1):m_c_clk_dn(2)';
NODE_NAME     U5D1 AA56
 '@BASEBOARD_FAB2_LIB.BASEBOARD_FAB2(SCH_1):PAGE25_I172@CHPSET_LIB.SKX_EXT_B(CHIPS)':
 'DDR2_CLK_DN'<2>: CDS_PINID='DDR2_CLK_DN(2)';
NODE_NAME     J6U2 75
 '@BASEBOARD_FAB2_LIB.BASEBOARD_FAB2(SCH_1):PAGE48_I111@MSTR_SCONN.SCONN288_H44441003(CHIPS)':
 'CK0N': CDS_PINID='CK0N';
NET_NAME
'M_C_CLK_DN<3>'
 '@BASEBOARD_FAB2_LIB.BASEBOARD_FAB2(SCH_1):M_C_CLK_DN'<3>:
 C_SIGNAL='@baseboard_fab2_lib.baseboard_fab2(sch_1):m_c_clk_dn(3)';
NODE_NAME     U5D1 W56
 '@BASEBOARD_FAB2_LIB.BASEBOARD_FAB2(SCH_1):PAGE25_I172@CHPSET_LIB.SKX_EXT_B(CHIPS)':
 'DDR2_CLK_DN'<3>: CDS_PINID='DDR2_CLK_DN(3)';
NODE_NAME     J6U2 219
 '@BASEBOARD_FAB2_LIB.BASEBOARD_FAB2(SCH_1):PAGE48_I111@MSTR_SCONN.SCONN288_H44441003(CHIPS)':
 'CK1N': CDS_PINID='CK1N';
NET_NAME
'M_C_CLK_DP<0>'
 '@BASEBOARD_FAB2_LIB.BASEBOARD_FAB2(SCH_1):M_C_CLK_DP'<0>:
 C_SIGNAL='@baseboard_fab2_lib.baseboard_fab2(sch_1):m_c_clk_dp(0)';
NODE_NAME     U5D1 AB55
 '@BASEBOARD_FAB2_LIB.BASEBOARD_FAB2(SCH_1):PAGE25_I172@CHPSET_LIB.SKX_EXT_B(CHIPS)':
 'DDR2_CLK_DP'<0>: CDS_PINID='DDR2_CLK_DP(0)';
NODE_NAME     J4G3 74
 '@BASEBOARD_FAB2_LIB.BASEBOARD_FAB2(SCH_1):PAGE47_I111@MSTR_SCONN.SCONN288_H44441004(CHIPS)':
 'CK0P': CDS_PINID='CK0P';
NET_NAME
'M_C_CLK_DP<1>'
 '@BASEBOARD_FAB2_LIB.BASEBOARD_FAB2(SCH_1):M_C_CLK_DP'<1>:
 C_SIGNAL='@baseboard_fab2_lib.baseboard_fab2(sch_1):m_c_clk_dp(1)';
NODE_NAME     U5D1 V55
 '@BASEBOARD_FAB2_LIB.BASEBOARD_FAB2(SCH_1):PAGE25_I172@CHPSET_LIB.SKX_EXT_B(CHIPS)':
 'DDR2_CLK_DP'<1>: CDS_PINID='DDR2_CLK_DP(1)';
NODE_NAME     J4G3 218
 '@BASEBOARD_FAB2_LIB.BASEBOARD_FAB2(SCH_1):PAGE47_I111@MSTR_SCONN.SCONN288_H44441004(CHIPS)':
 'CK1P': CDS_PINID='CK1P';
NET_NAME
'M_C_CLK_DP<2>'
 '@BASEBOARD_FAB2_LIB.BASEBOARD_FAB2(SCH_1):M_C_CLK_DP'<2>:
 C_SIGNAL='@baseboard_fab2_lib.baseboard_fab2(sch_1):m_c_clk_dp(2)';
NODE_NAME     U5D1 AB57
 '@BASEBOARD_FAB2_LIB.BASEBOARD_FAB2(SCH_1):PAGE25_I172@CHPSET_LIB.SKX_EXT_B(CHIPS)':
 'DDR2_CLK_DP'<2>: CDS_PINID='DDR2_CLK_DP(2)';
NODE_NAME     J6U2 74
 '@BASEBOARD_FAB2_LIB.BASEBOARD_FAB2(SCH_1):PAGE48_I111@MSTR_SCONN.SCONN288_H44441003(CHIPS)':
 'CK0P': CDS_PINID='CK0P';
NET_NAME
'M_C_CLK_DP<3>'
 '@BASEBOARD_FAB2_LIB.BASEBOARD_FAB2(SCH_1):M_C_CLK_DP'<3>:
 C_SIGNAL='@baseboard_fab2_lib.baseboard_fab2(sch_1):m_c_clk_dp(3)';
NODE_NAME     U5D1 V57
 '@BASEBOARD_FAB2_LIB.BASEBOARD_FAB2(SCH_1):PAGE25_I172@CHPSET_LIB.SKX_EXT_B(CHIPS)':
 'DDR2_CLK_DP'<3>: CDS_PINID='DDR2_CLK_DP(3)';
NODE_NAME     J6U2 218
 '@BASEBOARD_FAB2_LIB.BASEBOARD_FAB2(SCH_1):PAGE48_I111@MSTR_SCONN.SCONN288_H44441003(CHIPS)':
 'CK1P': CDS_PINID='CK1P';
NET_NAME
'M_C_CPU_VREF'
 '@BASEBOARD_FAB2_LIB.BASEBOARD_FAB2(SCH_1):M_C_CPU_VREF':
 C_SIGNAL='@baseboard_fab2_lib.baseboard_fab2(sch_1):m_c_cpu_vref';
NODE_NAME     U5D1 AH63
 '@BASEBOARD_FAB2_LIB.BASEBOARD_FAB2(SCH_1):PAGE21_I259@CHPSET_LIB.SKX_EXT_B(CHIPS)':
 'DDR2_CAVREF': CDS_PINID='DDR2_CAVREF';
NODE_NAME     R4G20 1
 '@BASEBOARD_FAB2_LIB.BASEBOARD_FAB2(SCH_1):PAGE98_I50@MSTR_DISCRETE.RES(CHIPS)':
 'A': CDS_PINID='A';
NODE_NAME     C4G17 1
 '@BASEBOARD_FAB2_LIB.BASEBOARD_FAB2(SCH_1):PAGE98_I51@DEV_DISCRETE.CAP_A(CHIPS)':
 'A': CDS_PINID='A';
NET_NAME
'M_C_CS_N<0>'
 '@BASEBOARD_FAB2_LIB.BASEBOARD_FAB2(SCH_1):M_C_CS_N'<0>:
 C_SIGNAL='@baseboard_fab2_lib.baseboard_fab2(sch_1):m_c_cs_n(0)';
NODE_NAME     U5D1 V51
 '@BASEBOARD_FAB2_LIB.BASEBOARD_FAB2(SCH_1):PAGE25_I172@CHPSET_LIB.SKX_EXT_B(CHIPS)':
 'DDR2_CS_N'<0>: CDS_PINID='DDR2_CS_N(0)';
NODE_NAME     J4G3 84
 '@BASEBOARD_FAB2_LIB.BASEBOARD_FAB2(SCH_1):PAGE47_I111@MSTR_SCONN.SCONN288_H44441004(CHIPS)':
 'S0_N': CDS_PINID='S0_N';
NET_NAME
'M_C_CS_N<1>'
 '@BASEBOARD_FAB2_LIB.BASEBOARD_FAB2(SCH_1):M_C_CS_N'<1>:
 C_SIGNAL='@baseboard_fab2_lib.baseboard_fab2(sch_1):m_c_cs_n(1)';
NODE_NAME     U5D1 AB49
 '@BASEBOARD_FAB2_LIB.BASEBOARD_FAB2(SCH_1):PAGE25_I172@CHPSET_LIB.SKX_EXT_B(CHIPS)':
 'DDR2_CS_N'<1>: CDS_PINID='DDR2_CS_N(1)';
NODE_NAME     J4G3 89
 '@BASEBOARD_FAB2_LIB.BASEBOARD_FAB2(SCH_1):PAGE47_I111@MSTR_SCONN.SCONN288_H44441004(CHIPS)':
 'S1_N': CDS_PINID='S1_N';
NET_NAME
'M_C_CS_N<2>'
 '@BASEBOARD_FAB2_LIB.BASEBOARD_FAB2(SCH_1):M_C_CS_N'<2>:
 C_SIGNAL='@baseboard_fab2_lib.baseboard_fab2(sch_1):m_c_cs_n(2)';
NODE_NAME     U5D1 W46
 '@BASEBOARD_FAB2_LIB.BASEBOARD_FAB2(SCH_1):PAGE25_I172@CHPSET_LIB.SKX_EXT_B(CHIPS)':
 'DDR2_CS_N'<2>: CDS_PINID='DDR2_CS_N(2)';
NODE_NAME     J4G3 93
 '@BASEBOARD_FAB2_LIB.BASEBOARD_FAB2(SCH_1):PAGE47_I111@MSTR_SCONN.SCONN288_H44441004(CHIPS)':
 'S2_N_C'<0>: CDS_PINID='S2_N_C(0)';
NET_NAME
'M_C_CS_N<3>'
 '@BASEBOARD_FAB2_LIB.BASEBOARD_FAB2(SCH_1):M_C_CS_N'<3>:
 C_SIGNAL='@baseboard_fab2_lib.baseboard_fab2(sch_1):m_c_cs_n(3)';
NODE_NAME     U5D1 AA46
 '@BASEBOARD_FAB2_LIB.BASEBOARD_FAB2(SCH_1):PAGE25_I172@CHPSET_LIB.SKX_EXT_B(CHIPS)':
 'DDR2_CS_N'<3>: CDS_PINID='DDR2_CS_N(3)';
NODE_NAME     J4G3 237
 '@BASEBOARD_FAB2_LIB.BASEBOARD_FAB2(SCH_1):PAGE47_I111@MSTR_SCONN.SCONN288_H44441004(CHIPS)':
 'S3_N_C'<1>: CDS_PINID='S3_N_C(1)';
NET_NAME
'M_C_CS_N<4>'
 '@BASEBOARD_FAB2_LIB.BASEBOARD_FAB2(SCH_1):M_C_CS_N'<4>:
 C_SIGNAL='@baseboard_fab2_lib.baseboard_fab2(sch_1):m_c_cs_n(4)';
NODE_NAME     U5D1 AB51
 '@BASEBOARD_FAB2_LIB.BASEBOARD_FAB2(SCH_1):PAGE25_I172@CHPSET_LIB.SKX_EXT_B(CHIPS)':
 'DDR2_CS_N'<4>: CDS_PINID='DDR2_CS_N(4)';
NODE_NAME     J6U2 84
 '@BASEBOARD_FAB2_LIB.BASEBOARD_FAB2(SCH_1):PAGE48_I111@MSTR_SCONN.SCONN288_H44441003(CHIPS)':
 'S0_N': CDS_PINID='S0_N';
NET_NAME
'M_C_CS_N<5>'
 '@BASEBOARD_FAB2_LIB.BASEBOARD_FAB2(SCH_1):M_C_CS_N'<5>:
 C_SIGNAL='@baseboard_fab2_lib.baseboard_fab2(sch_1):m_c_cs_n(5)';
NODE_NAME     U5D1 W48
 '@BASEBOARD_FAB2_LIB.BASEBOARD_FAB2(SCH_1):PAGE25_I172@CHPSET_LIB.SKX_EXT_B(CHIPS)':
 'DDR2_CS_N'<5>: CDS_PINID='DDR2_CS_N(5)';
NODE_NAME     J6U2 89
 '@BASEBOARD_FAB2_LIB.BASEBOARD_FAB2(SCH_1):PAGE48_I111@MSTR_SCONN.SCONN288_H44441003(CHIPS)':
 'S1_N': CDS_PINID='S1_N';
NET_NAME
'M_C_CS_N<6>'
 '@BASEBOARD_FAB2_LIB.BASEBOARD_FAB2(SCH_1):M_C_CS_N'<6>:
 C_SIGNAL='@baseboard_fab2_lib.baseboard_fab2(sch_1):m_c_cs_n(6)';
NODE_NAME     U5D1 T45
 '@BASEBOARD_FAB2_LIB.BASEBOARD_FAB2(SCH_1):PAGE25_I172@CHPSET_LIB.SKX_EXT_B(CHIPS)':
 'DDR2_CS_N'<6>: CDS_PINID='DDR2_CS_N(6)';
NODE_NAME     J6U2 93
 '@BASEBOARD_FAB2_LIB.BASEBOARD_FAB2(SCH_1):PAGE48_I111@MSTR_SCONN.SCONN288_H44441003(CHIPS)':
 'S2_N_C'<0>: CDS_PINID='S2_N_C(0)';
NET_NAME
'M_C_CS_N<7>'
 '@BASEBOARD_FAB2_LIB.BASEBOARD_FAB2(SCH_1):M_C_CS_N'<7>:
 C_SIGNAL='@baseboard_fab2_lib.baseboard_fab2(sch_1):m_c_cs_n(7)';
NODE_NAME     U5D1 V45
 '@BASEBOARD_FAB2_LIB.BASEBOARD_FAB2(SCH_1):PAGE25_I172@CHPSET_LIB.SKX_EXT_B(CHIPS)':
 'DDR2_CS_N'<7>: CDS_PINID='DDR2_CS_N(7)';
NODE_NAME     J6U2 237
 '@BASEBOARD_FAB2_LIB.BASEBOARD_FAB2(SCH_1):PAGE48_I111@MSTR_SCONN.SCONN288_H44441003(CHIPS)':
 'S3_N_C'<1>: CDS_PINID='S3_N_C(1)';
NET_NAME
'M_C_DQ<0>'
 '@BASEBOARD_FAB2_LIB.BASEBOARD_FAB2(SCH_1):M_C_DQ'<0>:
 C_SIGNAL='@baseboard_fab2_lib.baseboard_fab2(sch_1):m_c_dq(0)';
NODE_NAME     U5D1 AR76
 '@BASEBOARD_FAB2_LIB.BASEBOARD_FAB2(SCH_1):PAGE25_I172@CHPSET_LIB.SKX_EXT_B(CHIPS)':
 'DDR2_DQ'<0>: CDS_PINID='DDR2_DQ(0)';
NODE_NAME     J4G3 150
 '@BASEBOARD_FAB2_LIB.BASEBOARD_FAB2(SCH_1):PAGE47_I111@MSTR_SCONN.SCONN288_H44441004(CHIPS)':
 'DQ'<1>: CDS_PINID='DQ(1)';
NODE_NAME     J6U2 5
 '@BASEBOARD_FAB2_LIB.BASEBOARD_FAB2(SCH_1):PAGE48_I111@MSTR_SCONN.SCONN288_H44441003(CHIPS)':
 'DQ'<0>: CDS_PINID='DQ(0)';
NET_NAME
'M_C_DQ<10>'
 '@BASEBOARD_FAB2_LIB.BASEBOARD_FAB2(SCH_1):M_C_DQ'<10>:
 C_SIGNAL='@baseboard_fab2_lib.baseboard_fab2(sch_1):m_c_dq(10)';
NODE_NAME     U5D1 Y77
 '@BASEBOARD_FAB2_LIB.BASEBOARD_FAB2(SCH_1):PAGE25_I172@CHPSET_LIB.SKX_EXT_B(CHIPS)':
 'DDR2_DQ'<10>: CDS_PINID='DDR2_DQ(10)';
NODE_NAME     J4G3 168
 '@BASEBOARD_FAB2_LIB.BASEBOARD_FAB2(SCH_1):PAGE47_I111@MSTR_SCONN.SCONN288_H44441004(CHIPS)':
 'DQ'<11>: CDS_PINID='DQ(11)';
NODE_NAME     J6U2 23
 '@BASEBOARD_FAB2_LIB.BASEBOARD_FAB2(SCH_1):PAGE48_I111@MSTR_SCONN.SCONN288_H44441003(CHIPS)':
 'DQ'<10>: CDS_PINID='DQ(10)';
NET_NAME
'M_C_DQ<11>'
 '@BASEBOARD_FAB2_LIB.BASEBOARD_FAB2(SCH_1):M_C_DQ'<11>:
 C_SIGNAL='@baseboard_fab2_lib.baseboard_fab2(sch_1):m_c_dq(11)';
NODE_NAME     U5D1 W76
 '@BASEBOARD_FAB2_LIB.BASEBOARD_FAB2(SCH_1):PAGE25_I172@CHPSET_LIB.SKX_EXT_B(CHIPS)':
 'DDR2_DQ'<11>: CDS_PINID='DDR2_DQ(11)';
NODE_NAME     J4G3 23
 '@BASEBOARD_FAB2_LIB.BASEBOARD_FAB2(SCH_1):PAGE47_I111@MSTR_SCONN.SCONN288_H44441004(CHIPS)':
 'DQ'<10>: CDS_PINID='DQ(10)';
NODE_NAME     J6U2 168
 '@BASEBOARD_FAB2_LIB.BASEBOARD_FAB2(SCH_1):PAGE48_I111@MSTR_SCONN.SCONN288_H44441003(CHIPS)':
 'DQ'<11>: CDS_PINID='DQ(11)';
NET_NAME
'M_C_DQ<12>'
 '@BASEBOARD_FAB2_LIB.BASEBOARD_FAB2(SCH_1):M_C_DQ'<12>:
 C_SIGNAL='@baseboard_fab2_lib.baseboard_fab2(sch_1):m_c_dq(12)';
NODE_NAME     U5D1 AF75
 '@BASEBOARD_FAB2_LIB.BASEBOARD_FAB2(SCH_1):PAGE25_I172@CHPSET_LIB.SKX_EXT_B(CHIPS)':
 'DDR2_DQ'<12>: CDS_PINID='DDR2_DQ(12)';
NODE_NAME     J4G3 159
 '@BASEBOARD_FAB2_LIB.BASEBOARD_FAB2(SCH_1):PAGE47_I111@MSTR_SCONN.SCONN288_H44441004(CHIPS)':
 'DQ'<13>: CDS_PINID='DQ(13)';
NODE_NAME     J6U2 14
 '@BASEBOARD_FAB2_LIB.BASEBOARD_FAB2(SCH_1):PAGE48_I111@MSTR_SCONN.SCONN288_H44441003(CHIPS)':
 'DQ'<12>: CDS_PINID='DQ(12)';
NET_NAME
'M_C_DQ<13>'
 '@BASEBOARD_FAB2_LIB.BASEBOARD_FAB2(SCH_1):M_C_DQ'<13>:
 C_SIGNAL='@baseboard_fab2_lib.baseboard_fab2(sch_1):m_c_dq(13)';
NODE_NAME     U5D1 AE74
 '@BASEBOARD_FAB2_LIB.BASEBOARD_FAB2(SCH_1):PAGE25_I172@CHPSET_LIB.SKX_EXT_B(CHIPS)':
 'DDR2_DQ'<13>: CDS_PINID='DDR2_DQ(13)';
NODE_NAME     J4G3 14
 '@BASEBOARD_FAB2_LIB.BASEBOARD_FAB2(SCH_1):PAGE47_I111@MSTR_SCONN.SCONN288_H44441004(CHIPS)':
 'DQ'<12>: CDS_PINID='DQ(12)';
NODE_NAME     J6U2 159
 '@BASEBOARD_FAB2_LIB.BASEBOARD_FAB2(SCH_1):PAGE48_I111@MSTR_SCONN.SCONN288_H44441003(CHIPS)':
 'DQ'<13>: CDS_PINID='DQ(13)';
NET_NAME
'M_C_DQ<14>'
 '@BASEBOARD_FAB2_LIB.BASEBOARD_FAB2(SCH_1):M_C_DQ'<14>:
 C_SIGNAL='@baseboard_fab2_lib.baseboard_fab2(sch_1):m_c_dq(14)';
NODE_NAME     U5D1 AB77
 '@BASEBOARD_FAB2_LIB.BASEBOARD_FAB2(SCH_1):PAGE25_I172@CHPSET_LIB.SKX_EXT_B(CHIPS)':
 'DDR2_DQ'<14>: CDS_PINID='DDR2_DQ(14)';
NODE_NAME     J4G3 166
 '@BASEBOARD_FAB2_LIB.BASEBOARD_FAB2(SCH_1):PAGE47_I111@MSTR_SCONN.SCONN288_H44441004(CHIPS)':
 'DQ'<15>: CDS_PINID='DQ(15)';
NODE_NAME     J6U2 21
 '@BASEBOARD_FAB2_LIB.BASEBOARD_FAB2(SCH_1):PAGE48_I111@MSTR_SCONN.SCONN288_H44441003(CHIPS)':
 'DQ'<14>: CDS_PINID='DQ(14)';
NET_NAME
'M_C_DQ<15>'
 '@BASEBOARD_FAB2_LIB.BASEBOARD_FAB2(SCH_1):M_C_DQ'<15>:
 C_SIGNAL='@baseboard_fab2_lib.baseboard_fab2(sch_1):m_c_dq(15)';
NODE_NAME     U5D1 Y75
 '@BASEBOARD_FAB2_LIB.BASEBOARD_FAB2(SCH_1):PAGE25_I172@CHPSET_LIB.SKX_EXT_B(CHIPS)':
 'DDR2_DQ'<15>: CDS_PINID='DDR2_DQ(15)';
NODE_NAME     J4G3 21
 '@BASEBOARD_FAB2_LIB.BASEBOARD_FAB2(SCH_1):PAGE47_I111@MSTR_SCONN.SCONN288_H44441004(CHIPS)':
 'DQ'<14>: CDS_PINID='DQ(14)';
NODE_NAME     J6U2 166
 '@BASEBOARD_FAB2_LIB.BASEBOARD_FAB2(SCH_1):PAGE48_I111@MSTR_SCONN.SCONN288_H44441003(CHIPS)':
 'DQ'<15>: CDS_PINID='DQ(15)';
NET_NAME
'M_C_DQ<16>'
 '@BASEBOARD_FAB2_LIB.BASEBOARD_FAB2(SCH_1):M_C_DQ'<16>:
 C_SIGNAL='@baseboard_fab2_lib.baseboard_fab2(sch_1):m_c_dq(16)';
NODE_NAME     U5D1 W72
 '@BASEBOARD_FAB2_LIB.BASEBOARD_FAB2(SCH_1):PAGE25_I172@CHPSET_LIB.SKX_EXT_B(CHIPS)':
 'DDR2_DQ'<16>: CDS_PINID='DDR2_DQ(16)';
NODE_NAME     J4G3 172
 '@BASEBOARD_FAB2_LIB.BASEBOARD_FAB2(SCH_1):PAGE47_I111@MSTR_SCONN.SCONN288_H44441004(CHIPS)':
 'DQ'<17>: CDS_PINID='DQ(17)';
NODE_NAME     J6U2 27
 '@BASEBOARD_FAB2_LIB.BASEBOARD_FAB2(SCH_1):PAGE48_I111@MSTR_SCONN.SCONN288_H44441003(CHIPS)':
 'DQ'<16>: CDS_PINID='DQ(16)';
NET_NAME
'M_C_DQ<17>'
 '@BASEBOARD_FAB2_LIB.BASEBOARD_FAB2(SCH_1):M_C_DQ'<17>:
 C_SIGNAL='@baseboard_fab2_lib.baseboard_fab2(sch_1):m_c_dq(17)';
NODE_NAME     U5D1 AA70
 '@BASEBOARD_FAB2_LIB.BASEBOARD_FAB2(SCH_1):PAGE25_I172@CHPSET_LIB.SKX_EXT_B(CHIPS)':
 'DDR2_DQ'<17>: CDS_PINID='DDR2_DQ(17)';
NODE_NAME     J4G3 27
 '@BASEBOARD_FAB2_LIB.BASEBOARD_FAB2(SCH_1):PAGE47_I111@MSTR_SCONN.SCONN288_H44441004(CHIPS)':
 'DQ'<16>: CDS_PINID='DQ(16)';
NODE_NAME     J6U2 172
 '@BASEBOARD_FAB2_LIB.BASEBOARD_FAB2(SCH_1):PAGE48_I111@MSTR_SCONN.SCONN288_H44441003(CHIPS)':
 'DQ'<17>: CDS_PINID='DQ(17)';
NET_NAME
'M_C_DQ<18>'
 '@BASEBOARD_FAB2_LIB.BASEBOARD_FAB2(SCH_1):M_C_DQ'<18>:
 C_SIGNAL='@baseboard_fab2_lib.baseboard_fab2(sch_1):m_c_dq(18)';
NODE_NAME     U5D1 R70
 '@BASEBOARD_FAB2_LIB.BASEBOARD_FAB2(SCH_1):PAGE25_I172@CHPSET_LIB.SKX_EXT_B(CHIPS)':
 'DDR2_DQ'<18>: CDS_PINID='DDR2_DQ(18)';
NODE_NAME     J4G3 179
 '@BASEBOARD_FAB2_LIB.BASEBOARD_FAB2(SCH_1):PAGE47_I111@MSTR_SCONN.SCONN288_H44441004(CHIPS)':
 'DQ'<19>: CDS_PINID='DQ(19)';
NODE_NAME     J6U2 34
 '@BASEBOARD_FAB2_LIB.BASEBOARD_FAB2(SCH_1):PAGE48_I111@MSTR_SCONN.SCONN288_H44441003(CHIPS)':
 'DQ'<18>: CDS_PINID='DQ(18)';
NET_NAME
'M_C_DQ<19>'
 '@BASEBOARD_FAB2_LIB.BASEBOARD_FAB2(SCH_1):M_C_DQ'<19>:
 C_SIGNAL='@baseboard_fab2_lib.baseboard_fab2(sch_1):m_c_dq(19)';
NODE_NAME     U5D1 T69
 '@BASEBOARD_FAB2_LIB.BASEBOARD_FAB2(SCH_1):PAGE25_I172@CHPSET_LIB.SKX_EXT_B(CHIPS)':
 'DDR2_DQ'<19>: CDS_PINID='DDR2_DQ(19)';
NODE_NAME     J4G3 34
 '@BASEBOARD_FAB2_LIB.BASEBOARD_FAB2(SCH_1):PAGE47_I111@MSTR_SCONN.SCONN288_H44441004(CHIPS)':
 'DQ'<18>: CDS_PINID='DQ(18)';
NODE_NAME     J6U2 179
 '@BASEBOARD_FAB2_LIB.BASEBOARD_FAB2(SCH_1):PAGE48_I111@MSTR_SCONN.SCONN288_H44441003(CHIPS)':
 'DQ'<19>: CDS_PINID='DQ(19)';
NET_NAME
'M_C_DQ<1>'
 '@BASEBOARD_FAB2_LIB.BASEBOARD_FAB2(SCH_1):M_C_DQ'<1>:
 C_SIGNAL='@baseboard_fab2_lib.baseboard_fab2(sch_1):m_c_dq(1)';
NODE_NAME     U5D1 AN74
 '@BASEBOARD_FAB2_LIB.BASEBOARD_FAB2(SCH_1):PAGE25_I172@CHPSET_LIB.SKX_EXT_B(CHIPS)':
 'DDR2_DQ'<1>: CDS_PINID='DDR2_DQ(1)';
NODE_NAME     J4G3 5
 '@BASEBOARD_FAB2_LIB.BASEBOARD_FAB2(SCH_1):PAGE47_I111@MSTR_SCONN.SCONN288_H44441004(CHIPS)':
 'DQ'<0>: CDS_PINID='DQ(0)';
NODE_NAME     J6U2 150
 '@BASEBOARD_FAB2_LIB.BASEBOARD_FAB2(SCH_1):PAGE48_I111@MSTR_SCONN.SCONN288_H44441003(CHIPS)':
 'DQ'<1>: CDS_PINID='DQ(1)';
NET_NAME
'M_C_DQ<20>'
 '@BASEBOARD_FAB2_LIB.BASEBOARD_FAB2(SCH_1):M_C_DQ'<20>:
 C_SIGNAL='@baseboard_fab2_lib.baseboard_fab2(sch_1):m_c_dq(20)';
NODE_NAME     U5D1 AA72
 '@BASEBOARD_FAB2_LIB.BASEBOARD_FAB2(SCH_1):PAGE25_I172@CHPSET_LIB.SKX_EXT_B(CHIPS)':
 'DDR2_DQ'<20>: CDS_PINID='DDR2_DQ(20)';
NODE_NAME     J4G3 170
 '@BASEBOARD_FAB2_LIB.BASEBOARD_FAB2(SCH_1):PAGE47_I111@MSTR_SCONN.SCONN288_H44441004(CHIPS)':
 'DQ'<21>: CDS_PINID='DQ(21)';
NODE_NAME     J6U2 25
 '@BASEBOARD_FAB2_LIB.BASEBOARD_FAB2(SCH_1):PAGE48_I111@MSTR_SCONN.SCONN288_H44441003(CHIPS)':
 'DQ'<20>: CDS_PINID='DQ(20)';
NET_NAME
'M_C_DQ<21>'
 '@BASEBOARD_FAB2_LIB.BASEBOARD_FAB2(SCH_1):M_C_DQ'<21>:
 C_SIGNAL='@baseboard_fab2_lib.baseboard_fab2(sch_1):m_c_dq(21)';
NODE_NAME     U5D1 AB71
 '@BASEBOARD_FAB2_LIB.BASEBOARD_FAB2(SCH_1):PAGE25_I172@CHPSET_LIB.SKX_EXT_B(CHIPS)':
 'DDR2_DQ'<21>: CDS_PINID='DDR2_DQ(21)';
NODE_NAME     J4G3 25
 '@BASEBOARD_FAB2_LIB.BASEBOARD_FAB2(SCH_1):PAGE47_I111@MSTR_SCONN.SCONN288_H44441004(CHIPS)':
 'DQ'<20>: CDS_PINID='DQ(20)';
NODE_NAME     J6U2 170
 '@BASEBOARD_FAB2_LIB.BASEBOARD_FAB2(SCH_1):PAGE48_I111@MSTR_SCONN.SCONN288_H44441003(CHIPS)':
 'DQ'<21>: CDS_PINID='DQ(21)';
NET_NAME
'M_C_DQ<22>'
 '@BASEBOARD_FAB2_LIB.BASEBOARD_FAB2(SCH_1):M_C_DQ'<22>:
 C_SIGNAL='@baseboard_fab2_lib.baseboard_fab2(sch_1):m_c_dq(22)';
NODE_NAME     U5D1 T71
 '@BASEBOARD_FAB2_LIB.BASEBOARD_FAB2(SCH_1):PAGE25_I172@CHPSET_LIB.SKX_EXT_B(CHIPS)':
 'DDR2_DQ'<22>: CDS_PINID='DDR2_DQ(22)';
NODE_NAME     J4G3 177
 '@BASEBOARD_FAB2_LIB.BASEBOARD_FAB2(SCH_1):PAGE47_I111@MSTR_SCONN.SCONN288_H44441004(CHIPS)':
 'DQ'<23>: CDS_PINID='DQ(23)';
NODE_NAME     J6U2 32
 '@BASEBOARD_FAB2_LIB.BASEBOARD_FAB2(SCH_1):PAGE48_I111@MSTR_SCONN.SCONN288_H44441003(CHIPS)':
 'DQ'<22>: CDS_PINID='DQ(22)';
NET_NAME
'M_C_DQ<23>'
 '@BASEBOARD_FAB2_LIB.BASEBOARD_FAB2(SCH_1):M_C_DQ'<23>:
 C_SIGNAL='@baseboard_fab2_lib.baseboard_fab2(sch_1):m_c_dq(23)';
NODE_NAME     U5D1 V69
 '@BASEBOARD_FAB2_LIB.BASEBOARD_FAB2(SCH_1):PAGE25_I172@CHPSET_LIB.SKX_EXT_B(CHIPS)':
 'DDR2_DQ'<23>: CDS_PINID='DDR2_DQ(23)';
NODE_NAME     J4G3 32
 '@BASEBOARD_FAB2_LIB.BASEBOARD_FAB2(SCH_1):PAGE47_I111@MSTR_SCONN.SCONN288_H44441004(CHIPS)':
 'DQ'<22>: CDS_PINID='DQ(22)';
NODE_NAME     J6U2 177
 '@BASEBOARD_FAB2_LIB.BASEBOARD_FAB2(SCH_1):PAGE48_I111@MSTR_SCONN.SCONN288_H44441003(CHIPS)':
 'DQ'<23>: CDS_PINID='DQ(23)';
NET_NAME
'M_C_DQ<24>'
 '@BASEBOARD_FAB2_LIB.BASEBOARD_FAB2(SCH_1):M_C_DQ'<24>:
 C_SIGNAL='@baseboard_fab2_lib.baseboard_fab2(sch_1):m_c_dq(24)';
NODE_NAME     U5D1 AM67
 '@BASEBOARD_FAB2_LIB.BASEBOARD_FAB2(SCH_1):PAGE25_I172@CHPSET_LIB.SKX_EXT_B(CHIPS)':
 'DDR2_DQ'<24>: CDS_PINID='DDR2_DQ(24)';
NODE_NAME     J4G3 183
 '@BASEBOARD_FAB2_LIB.BASEBOARD_FAB2(SCH_1):PAGE47_I111@MSTR_SCONN.SCONN288_H44441004(CHIPS)':
 'DQ'<25>: CDS_PINID='DQ(25)';
NODE_NAME     J6U2 38
 '@BASEBOARD_FAB2_LIB.BASEBOARD_FAB2(SCH_1):PAGE48_I111@MSTR_SCONN.SCONN288_H44441003(CHIPS)':
 'DQ'<24>: CDS_PINID='DQ(24)';
NET_NAME
'M_C_DQ<25>'
 '@BASEBOARD_FAB2_LIB.BASEBOARD_FAB2(SCH_1):M_C_DQ'<25>:
 C_SIGNAL='@baseboard_fab2_lib.baseboard_fab2(sch_1):m_c_dq(25)';
NODE_NAME     U5D1 AT67
 '@BASEBOARD_FAB2_LIB.BASEBOARD_FAB2(SCH_1):PAGE25_I172@CHPSET_LIB.SKX_EXT_B(CHIPS)':
 'DDR2_DQ'<25>: CDS_PINID='DDR2_DQ(25)';
NODE_NAME     J4G3 38
 '@BASEBOARD_FAB2_LIB.BASEBOARD_FAB2(SCH_1):PAGE47_I111@MSTR_SCONN.SCONN288_H44441004(CHIPS)':
 'DQ'<24>: CDS_PINID='DQ(24)';
NODE_NAME     J6U2 183
 '@BASEBOARD_FAB2_LIB.BASEBOARD_FAB2(SCH_1):PAGE48_I111@MSTR_SCONN.SCONN288_H44441003(CHIPS)':
 'DQ'<25>: CDS_PINID='DQ(25)';
NET_NAME
'M_C_DQ<26>'
 '@BASEBOARD_FAB2_LIB.BASEBOARD_FAB2(SCH_1):M_C_DQ'<26>:
 C_SIGNAL='@baseboard_fab2_lib.baseboard_fab2(sch_1):m_c_dq(26)';
NODE_NAME     U5D1 AN64
 '@BASEBOARD_FAB2_LIB.BASEBOARD_FAB2(SCH_1):PAGE25_I172@CHPSET_LIB.SKX_EXT_B(CHIPS)':
 'DDR2_DQ'<26>: CDS_PINID='DDR2_DQ(26)';
NODE_NAME     J4G3 190
 '@BASEBOARD_FAB2_LIB.BASEBOARD_FAB2(SCH_1):PAGE47_I111@MSTR_SCONN.SCONN288_H44441004(CHIPS)':
 'DQ'<27>: CDS_PINID='DQ(27)';
NODE_NAME     J6U2 45
 '@BASEBOARD_FAB2_LIB.BASEBOARD_FAB2(SCH_1):PAGE48_I111@MSTR_SCONN.SCONN288_H44441003(CHIPS)':
 'DQ'<26>: CDS_PINID='DQ(26)';
NET_NAME
'M_C_DQ<27>'
 '@BASEBOARD_FAB2_LIB.BASEBOARD_FAB2(SCH_1):M_C_DQ'<27>:
 C_SIGNAL='@baseboard_fab2_lib.baseboard_fab2(sch_1):m_c_dq(27)';
NODE_NAME     U5D1 AR64
 '@BASEBOARD_FAB2_LIB.BASEBOARD_FAB2(SCH_1):PAGE25_I172@CHPSET_LIB.SKX_EXT_B(CHIPS)':
 'DDR2_DQ'<27>: CDS_PINID='DDR2_DQ(27)';
NODE_NAME     J4G3 45
 '@BASEBOARD_FAB2_LIB.BASEBOARD_FAB2(SCH_1):PAGE47_I111@MSTR_SCONN.SCONN288_H44441004(CHIPS)':
 'DQ'<26>: CDS_PINID='DQ(26)';
NODE_NAME     J6U2 190
 '@BASEBOARD_FAB2_LIB.BASEBOARD_FAB2(SCH_1):PAGE48_I111@MSTR_SCONN.SCONN288_H44441003(CHIPS)':
 'DQ'<27>: CDS_PINID='DQ(27)';
NET_NAME
'M_C_DQ<28>'
 '@BASEBOARD_FAB2_LIB.BASEBOARD_FAB2(SCH_1):M_C_DQ'<28>:
 C_SIGNAL='@baseboard_fab2_lib.baseboard_fab2(sch_1):m_c_dq(28)';
NODE_NAME     U5D1 AN68
 '@BASEBOARD_FAB2_LIB.BASEBOARD_FAB2(SCH_1):PAGE25_I172@CHPSET_LIB.SKX_EXT_B(CHIPS)':
 'DDR2_DQ'<28>: CDS_PINID='DDR2_DQ(28)';
NODE_NAME     J4G3 181
 '@BASEBOARD_FAB2_LIB.BASEBOARD_FAB2(SCH_1):PAGE47_I111@MSTR_SCONN.SCONN288_H44441004(CHIPS)':
 'DQ'<29>: CDS_PINID='DQ(29)';
NODE_NAME     J6U2 36
 '@BASEBOARD_FAB2_LIB.BASEBOARD_FAB2(SCH_1):PAGE48_I111@MSTR_SCONN.SCONN288_H44441003(CHIPS)':
 'DQ'<28>: CDS_PINID='DQ(28)';
NET_NAME
'M_C_DQ<29>'
 '@BASEBOARD_FAB2_LIB.BASEBOARD_FAB2(SCH_1):M_C_DQ'<29>:
 C_SIGNAL='@baseboard_fab2_lib.baseboard_fab2(sch_1):m_c_dq(29)';
NODE_NAME     U5D1 AR68
 '@BASEBOARD_FAB2_LIB.BASEBOARD_FAB2(SCH_1):PAGE25_I172@CHPSET_LIB.SKX_EXT_B(CHIPS)':
 'DDR2_DQ'<29>: CDS_PINID='DDR2_DQ(29)';
NODE_NAME     J4G3 36
 '@BASEBOARD_FAB2_LIB.BASEBOARD_FAB2(SCH_1):PAGE47_I111@MSTR_SCONN.SCONN288_H44441004(CHIPS)':
 'DQ'<28>: CDS_PINID='DQ(28)';
NODE_NAME     J6U2 181
 '@BASEBOARD_FAB2_LIB.BASEBOARD_FAB2(SCH_1):PAGE48_I111@MSTR_SCONN.SCONN288_H44441003(CHIPS)':
 'DQ'<29>: CDS_PINID='DQ(29)';
NET_NAME
'M_C_DQ<2>'
 '@BASEBOARD_FAB2_LIB.BASEBOARD_FAB2(SCH_1):M_C_DQ'<2>:
 C_SIGNAL='@baseboard_fab2_lib.baseboard_fab2(sch_1):m_c_dq(2)';
NODE_NAME     U5D1 AK77
 '@BASEBOARD_FAB2_LIB.BASEBOARD_FAB2(SCH_1):PAGE25_I172@CHPSET_LIB.SKX_EXT_B(CHIPS)':
 'DDR2_DQ'<2>: CDS_PINID='DDR2_DQ(2)';
NODE_NAME     J4G3 157
 '@BASEBOARD_FAB2_LIB.BASEBOARD_FAB2(SCH_1):PAGE47_I111@MSTR_SCONN.SCONN288_H44441004(CHIPS)':
 'DQ'<3>: CDS_PINID='DQ(3)';
NODE_NAME     J6U2 12
 '@BASEBOARD_FAB2_LIB.BASEBOARD_FAB2(SCH_1):PAGE48_I111@MSTR_SCONN.SCONN288_H44441003(CHIPS)':
 'DQ'<2>: CDS_PINID='DQ(2)';
NET_NAME
'M_C_DQ<30>'
 '@BASEBOARD_FAB2_LIB.BASEBOARD_FAB2(SCH_1):M_C_DQ'<30>:
 C_SIGNAL='@baseboard_fab2_lib.baseboard_fab2(sch_1):m_c_dq(30)';
NODE_NAME     U5D1 AM65
 '@BASEBOARD_FAB2_LIB.BASEBOARD_FAB2(SCH_1):PAGE25_I172@CHPSET_LIB.SKX_EXT_B(CHIPS)':
 'DDR2_DQ'<30>: CDS_PINID='DDR2_DQ(30)';
NODE_NAME     J4G3 188
 '@BASEBOARD_FAB2_LIB.BASEBOARD_FAB2(SCH_1):PAGE47_I111@MSTR_SCONN.SCONN288_H44441004(CHIPS)':
 'DQ'<31>: CDS_PINID='DQ(31)';
NODE_NAME     J6U2 43
 '@BASEBOARD_FAB2_LIB.BASEBOARD_FAB2(SCH_1):PAGE48_I111@MSTR_SCONN.SCONN288_H44441003(CHIPS)':
 'DQ'<30>: CDS_PINID='DQ(30)';
NET_NAME
'M_C_DQ<31>'
 '@BASEBOARD_FAB2_LIB.BASEBOARD_FAB2(SCH_1):M_C_DQ'<31>:
 C_SIGNAL='@baseboard_fab2_lib.baseboard_fab2(sch_1):m_c_dq(31)';
NODE_NAME     U5D1 AT65
 '@BASEBOARD_FAB2_LIB.BASEBOARD_FAB2(SCH_1):PAGE25_I172@CHPSET_LIB.SKX_EXT_B(CHIPS)':
 'DDR2_DQ'<31>: CDS_PINID='DDR2_DQ(31)';
NODE_NAME     J4G3 43
 '@BASEBOARD_FAB2_LIB.BASEBOARD_FAB2(SCH_1):PAGE47_I111@MSTR_SCONN.SCONN288_H44441004(CHIPS)':
 'DQ'<30>: CDS_PINID='DQ(30)';
NODE_NAME     J6U2 188
 '@BASEBOARD_FAB2_LIB.BASEBOARD_FAB2(SCH_1):PAGE48_I111@MSTR_SCONN.SCONN288_H44441003(CHIPS)':
 'DQ'<31>: CDS_PINID='DQ(31)';
NET_NAME
'M_C_DQ<32>'
 '@BASEBOARD_FAB2_LIB.BASEBOARD_FAB2(SCH_1):M_C_DQ'<32>:
 C_SIGNAL='@baseboard_fab2_lib.baseboard_fab2(sch_1):m_c_dq(32)';
NODE_NAME     U5D1 U40
 '@BASEBOARD_FAB2_LIB.BASEBOARD_FAB2(SCH_1):PAGE25_I172@CHPSET_LIB.SKX_EXT_B(CHIPS)':
 'DDR2_DQ'<32>: CDS_PINID='DDR2_DQ(32)';
NODE_NAME     J4G3 242
 '@BASEBOARD_FAB2_LIB.BASEBOARD_FAB2(SCH_1):PAGE47_I111@MSTR_SCONN.SCONN288_H44441004(CHIPS)':
 'DQ'<33>: CDS_PINID='DQ(33)';
NODE_NAME     J6U2 97
 '@BASEBOARD_FAB2_LIB.BASEBOARD_FAB2(SCH_1):PAGE48_I111@MSTR_SCONN.SCONN288_H44441003(CHIPS)':
 'DQ'<32>: CDS_PINID='DQ(32)';
NET_NAME
'M_C_DQ<33>'
 '@BASEBOARD_FAB2_LIB.BASEBOARD_FAB2(SCH_1):M_C_DQ'<33>:
 C_SIGNAL='@baseboard_fab2_lib.baseboard_fab2(sch_1):m_c_dq(33)';
NODE_NAME     U5D1 AA40
 '@BASEBOARD_FAB2_LIB.BASEBOARD_FAB2(SCH_1):PAGE25_I172@CHPSET_LIB.SKX_EXT_B(CHIPS)':
 'DDR2_DQ'<33>: CDS_PINID='DDR2_DQ(33)';
NODE_NAME     J4G3 97
 '@BASEBOARD_FAB2_LIB.BASEBOARD_FAB2(SCH_1):PAGE47_I111@MSTR_SCONN.SCONN288_H44441004(CHIPS)':
 'DQ'<32>: CDS_PINID='DQ(32)';
NODE_NAME     J6U2 242
 '@BASEBOARD_FAB2_LIB.BASEBOARD_FAB2(SCH_1):PAGE48_I111@MSTR_SCONN.SCONN288_H44441003(CHIPS)':
 'DQ'<33>: CDS_PINID='DQ(33)';
NET_NAME
'M_C_DQ<34>'
 '@BASEBOARD_FAB2_LIB.BASEBOARD_FAB2(SCH_1):M_C_DQ'<34>:
 C_SIGNAL='@baseboard_fab2_lib.baseboard_fab2(sch_1):m_c_dq(34)';
NODE_NAME     U5D1 V37
 '@BASEBOARD_FAB2_LIB.BASEBOARD_FAB2(SCH_1):PAGE25_I172@CHPSET_LIB.SKX_EXT_B(CHIPS)':
 'DDR2_DQ'<34>: CDS_PINID='DDR2_DQ(34)';
NODE_NAME     J4G3 249
 '@BASEBOARD_FAB2_LIB.BASEBOARD_FAB2(SCH_1):PAGE47_I111@MSTR_SCONN.SCONN288_H44441004(CHIPS)':
 'DQ'<35>: CDS_PINID='DQ(35)';
NODE_NAME     J6U2 104
 '@BASEBOARD_FAB2_LIB.BASEBOARD_FAB2(SCH_1):PAGE48_I111@MSTR_SCONN.SCONN288_H44441003(CHIPS)':
 'DQ'<34>: CDS_PINID='DQ(34)';
NET_NAME
'M_C_DQ<35>'
 '@BASEBOARD_FAB2_LIB.BASEBOARD_FAB2(SCH_1):M_C_DQ'<35>:
 C_SIGNAL='@baseboard_fab2_lib.baseboard_fab2(sch_1):m_c_dq(35)';
NODE_NAME     U5D1 Y37
 '@BASEBOARD_FAB2_LIB.BASEBOARD_FAB2(SCH_1):PAGE25_I172@CHPSET_LIB.SKX_EXT_B(CHIPS)':
 'DDR2_DQ'<35>: CDS_PINID='DDR2_DQ(35)';
NODE_NAME     J4G3 104
 '@BASEBOARD_FAB2_LIB.BASEBOARD_FAB2(SCH_1):PAGE47_I111@MSTR_SCONN.SCONN288_H44441004(CHIPS)':
 'DQ'<34>: CDS_PINID='DQ(34)';
NODE_NAME     J6U2 249
 '@BASEBOARD_FAB2_LIB.BASEBOARD_FAB2(SCH_1):PAGE48_I111@MSTR_SCONN.SCONN288_H44441003(CHIPS)':
 'DQ'<35>: CDS_PINID='DQ(35)';
NET_NAME
'M_C_DQ<36>'
 '@BASEBOARD_FAB2_LIB.BASEBOARD_FAB2(SCH_1):M_C_DQ'<36>:
 C_SIGNAL='@baseboard_fab2_lib.baseboard_fab2(sch_1):m_c_dq(36)';
NODE_NAME     U5D1 V41
 '@BASEBOARD_FAB2_LIB.BASEBOARD_FAB2(SCH_1):PAGE25_I172@CHPSET_LIB.SKX_EXT_B(CHIPS)':
 'DDR2_DQ'<36>: CDS_PINID='DDR2_DQ(36)';
NODE_NAME     J4G3 240
 '@BASEBOARD_FAB2_LIB.BASEBOARD_FAB2(SCH_1):PAGE47_I111@MSTR_SCONN.SCONN288_H44441004(CHIPS)':
 'DQ'<37>: CDS_PINID='DQ(37)';
NODE_NAME     J6U2 95
 '@BASEBOARD_FAB2_LIB.BASEBOARD_FAB2(SCH_1):PAGE48_I111@MSTR_SCONN.SCONN288_H44441003(CHIPS)':
 'DQ'<36>: CDS_PINID='DQ(36)';
NET_NAME
'M_C_DQ<37>'
 '@BASEBOARD_FAB2_LIB.BASEBOARD_FAB2(SCH_1):M_C_DQ'<37>:
 C_SIGNAL='@baseboard_fab2_lib.baseboard_fab2(sch_1):m_c_dq(37)';
NODE_NAME     U5D1 Y41
 '@BASEBOARD_FAB2_LIB.BASEBOARD_FAB2(SCH_1):PAGE25_I172@CHPSET_LIB.SKX_EXT_B(CHIPS)':
 'DDR2_DQ'<37>: CDS_PINID='DDR2_DQ(37)';
NODE_NAME     J4G3 95
 '@BASEBOARD_FAB2_LIB.BASEBOARD_FAB2(SCH_1):PAGE47_I111@MSTR_SCONN.SCONN288_H44441004(CHIPS)':
 'DQ'<36>: CDS_PINID='DQ(36)';
NODE_NAME     J6U2 240
 '@BASEBOARD_FAB2_LIB.BASEBOARD_FAB2(SCH_1):PAGE48_I111@MSTR_SCONN.SCONN288_H44441003(CHIPS)':
 'DQ'<37>: CDS_PINID='DQ(37)';
NET_NAME
'M_C_DQ<38>'
 '@BASEBOARD_FAB2_LIB.BASEBOARD_FAB2(SCH_1):M_C_DQ'<38>:
 C_SIGNAL='@baseboard_fab2_lib.baseboard_fab2(sch_1):m_c_dq(38)';
NODE_NAME     U5D1 U38
 '@BASEBOARD_FAB2_LIB.BASEBOARD_FAB2(SCH_1):PAGE25_I172@CHPSET_LIB.SKX_EXT_B(CHIPS)':
 'DDR2_DQ'<38>: CDS_PINID='DDR2_DQ(38)';
NODE_NAME     J4G3 247
 '@BASEBOARD_FAB2_LIB.BASEBOARD_FAB2(SCH_1):PAGE47_I111@MSTR_SCONN.SCONN288_H44441004(CHIPS)':
 'DQ'<39>: CDS_PINID='DQ(39)';
NODE_NAME     J6U2 102
 '@BASEBOARD_FAB2_LIB.BASEBOARD_FAB2(SCH_1):PAGE48_I111@MSTR_SCONN.SCONN288_H44441003(CHIPS)':
 'DQ'<38>: CDS_PINID='DQ(38)';
NET_NAME
'M_C_DQ<39>'
 '@BASEBOARD_FAB2_LIB.BASEBOARD_FAB2(SCH_1):M_C_DQ'<39>:
 C_SIGNAL='@baseboard_fab2_lib.baseboard_fab2(sch_1):m_c_dq(39)';
NODE_NAME     U5D1 AA38
 '@BASEBOARD_FAB2_LIB.BASEBOARD_FAB2(SCH_1):PAGE25_I172@CHPSET_LIB.SKX_EXT_B(CHIPS)':
 'DDR2_DQ'<39>: CDS_PINID='DDR2_DQ(39)';
NODE_NAME     J4G3 102
 '@BASEBOARD_FAB2_LIB.BASEBOARD_FAB2(SCH_1):PAGE47_I111@MSTR_SCONN.SCONN288_H44441004(CHIPS)':
 'DQ'<38>: CDS_PINID='DQ(38)';
NODE_NAME     J6U2 247
 '@BASEBOARD_FAB2_LIB.BASEBOARD_FAB2(SCH_1):PAGE48_I111@MSTR_SCONN.SCONN288_H44441003(CHIPS)':
 'DQ'<39>: CDS_PINID='DQ(39)';
NET_NAME
'M_C_DQ<3>'
 '@BASEBOARD_FAB2_LIB.BASEBOARD_FAB2(SCH_1):M_C_DQ'<3>:
 C_SIGNAL='@baseboard_fab2_lib.baseboard_fab2(sch_1):m_c_dq(3)';
NODE_NAME     U5D1 AJ76
 '@BASEBOARD_FAB2_LIB.BASEBOARD_FAB2(SCH_1):PAGE25_I172@CHPSET_LIB.SKX_EXT_B(CHIPS)':
 'DDR2_DQ'<3>: CDS_PINID='DDR2_DQ(3)';
NODE_NAME     J4G3 12
 '@BASEBOARD_FAB2_LIB.BASEBOARD_FAB2(SCH_1):PAGE47_I111@MSTR_SCONN.SCONN288_H44441004(CHIPS)':
 'DQ'<2>: CDS_PINID='DQ(2)';
NODE_NAME     J6U2 157
 '@BASEBOARD_FAB2_LIB.BASEBOARD_FAB2(SCH_1):PAGE48_I111@MSTR_SCONN.SCONN288_H44441003(CHIPS)':
 'DQ'<3>: CDS_PINID='DQ(3)';
NET_NAME
'M_C_DQ<40>'
 '@BASEBOARD_FAB2_LIB.BASEBOARD_FAB2(SCH_1):M_C_DQ'<40>:
 C_SIGNAL='@baseboard_fab2_lib.baseboard_fab2(sch_1):m_c_dq(40)';
NODE_NAME     U5D1 U34
 '@BASEBOARD_FAB2_LIB.BASEBOARD_FAB2(SCH_1):PAGE25_I172@CHPSET_LIB.SKX_EXT_B(CHIPS)':
 'DDR2_DQ'<40>: CDS_PINID='DDR2_DQ(40)';
NODE_NAME     J4G3 253
 '@BASEBOARD_FAB2_LIB.BASEBOARD_FAB2(SCH_1):PAGE47_I111@MSTR_SCONN.SCONN288_H44441004(CHIPS)':
 'DQ'<41>: CDS_PINID='DQ(41)';
NODE_NAME     J6U2 108
 '@BASEBOARD_FAB2_LIB.BASEBOARD_FAB2(SCH_1):PAGE48_I111@MSTR_SCONN.SCONN288_H44441003(CHIPS)':
 'DQ'<40>: CDS_PINID='DQ(40)';
NET_NAME
'M_C_DQ<41>'
 '@BASEBOARD_FAB2_LIB.BASEBOARD_FAB2(SCH_1):M_C_DQ'<41>:
 C_SIGNAL='@baseboard_fab2_lib.baseboard_fab2(sch_1):m_c_dq(41)';
NODE_NAME     U5D1 AA34
 '@BASEBOARD_FAB2_LIB.BASEBOARD_FAB2(SCH_1):PAGE25_I172@CHPSET_LIB.SKX_EXT_B(CHIPS)':
 'DDR2_DQ'<41>: CDS_PINID='DDR2_DQ(41)';
NODE_NAME     J4G3 108
 '@BASEBOARD_FAB2_LIB.BASEBOARD_FAB2(SCH_1):PAGE47_I111@MSTR_SCONN.SCONN288_H44441004(CHIPS)':
 'DQ'<40>: CDS_PINID='DQ(40)';
NODE_NAME     J6U2 253
 '@BASEBOARD_FAB2_LIB.BASEBOARD_FAB2(SCH_1):PAGE48_I111@MSTR_SCONN.SCONN288_H44441003(CHIPS)':
 'DQ'<41>: CDS_PINID='DQ(41)';
NET_NAME
'M_C_DQ<42>'
 '@BASEBOARD_FAB2_LIB.BASEBOARD_FAB2(SCH_1):M_C_DQ'<42>:
 C_SIGNAL='@baseboard_fab2_lib.baseboard_fab2(sch_1):m_c_dq(42)';
NODE_NAME     U5D1 V31
 '@BASEBOARD_FAB2_LIB.BASEBOARD_FAB2(SCH_1):PAGE25_I172@CHPSET_LIB.SKX_EXT_B(CHIPS)':
 'DDR2_DQ'<42>: CDS_PINID='DDR2_DQ(42)';
NODE_NAME     J4G3 260
 '@BASEBOARD_FAB2_LIB.BASEBOARD_FAB2(SCH_1):PAGE47_I111@MSTR_SCONN.SCONN288_H44441004(CHIPS)':
 'DQ'<43>: CDS_PINID='DQ(43)';
NODE_NAME     J6U2 115
 '@BASEBOARD_FAB2_LIB.BASEBOARD_FAB2(SCH_1):PAGE48_I111@MSTR_SCONN.SCONN288_H44441003(CHIPS)':
 'DQ'<42>: CDS_PINID='DQ(42)';
NET_NAME
'M_C_DQ<43>'
 '@BASEBOARD_FAB2_LIB.BASEBOARD_FAB2(SCH_1):M_C_DQ'<43>:
 C_SIGNAL='@baseboard_fab2_lib.baseboard_fab2(sch_1):m_c_dq(43)';
NODE_NAME     U5D1 Y31
 '@BASEBOARD_FAB2_LIB.BASEBOARD_FAB2(SCH_1):PAGE25_I172@CHPSET_LIB.SKX_EXT_B(CHIPS)':
 'DDR2_DQ'<43>: CDS_PINID='DDR2_DQ(43)';
NODE_NAME     J4G3 115
 '@BASEBOARD_FAB2_LIB.BASEBOARD_FAB2(SCH_1):PAGE47_I111@MSTR_SCONN.SCONN288_H44441004(CHIPS)':
 'DQ'<42>: CDS_PINID='DQ(42)';
NODE_NAME     J6U2 260
 '@BASEBOARD_FAB2_LIB.BASEBOARD_FAB2(SCH_1):PAGE48_I111@MSTR_SCONN.SCONN288_H44441003(CHIPS)':
 'DQ'<43>: CDS_PINID='DQ(43)';
NET_NAME
'M_C_DQ<44>'
 '@BASEBOARD_FAB2_LIB.BASEBOARD_FAB2(SCH_1):M_C_DQ'<44>:
 C_SIGNAL='@baseboard_fab2_lib.baseboard_fab2(sch_1):m_c_dq(44)';
NODE_NAME     U5D1 V35
 '@BASEBOARD_FAB2_LIB.BASEBOARD_FAB2(SCH_1):PAGE25_I172@CHPSET_LIB.SKX_EXT_B(CHIPS)':
 'DDR2_DQ'<44>: CDS_PINID='DDR2_DQ(44)';
NODE_NAME     J4G3 251
 '@BASEBOARD_FAB2_LIB.BASEBOARD_FAB2(SCH_1):PAGE47_I111@MSTR_SCONN.SCONN288_H44441004(CHIPS)':
 'DQ'<45>: CDS_PINID='DQ(45)';
NODE_NAME     J6U2 106
 '@BASEBOARD_FAB2_LIB.BASEBOARD_FAB2(SCH_1):PAGE48_I111@MSTR_SCONN.SCONN288_H44441003(CHIPS)':
 'DQ'<44>: CDS_PINID='DQ(44)';
NET_NAME
'M_C_DQ<45>'
 '@BASEBOARD_FAB2_LIB.BASEBOARD_FAB2(SCH_1):M_C_DQ'<45>:
 C_SIGNAL='@baseboard_fab2_lib.baseboard_fab2(sch_1):m_c_dq(45)';
NODE_NAME     U5D1 Y35
 '@BASEBOARD_FAB2_LIB.BASEBOARD_FAB2(SCH_1):PAGE25_I172@CHPSET_LIB.SKX_EXT_B(CHIPS)':
 'DDR2_DQ'<45>: CDS_PINID='DDR2_DQ(45)';
NODE_NAME     J4G3 106
 '@BASEBOARD_FAB2_LIB.BASEBOARD_FAB2(SCH_1):PAGE47_I111@MSTR_SCONN.SCONN288_H44441004(CHIPS)':
 'DQ'<44>: CDS_PINID='DQ(44)';
NODE_NAME     J6U2 251
 '@BASEBOARD_FAB2_LIB.BASEBOARD_FAB2(SCH_1):PAGE48_I111@MSTR_SCONN.SCONN288_H44441003(CHIPS)':
 'DQ'<45>: CDS_PINID='DQ(45)';
NET_NAME
'M_C_DQ<46>'
 '@BASEBOARD_FAB2_LIB.BASEBOARD_FAB2(SCH_1):M_C_DQ'<46>:
 C_SIGNAL='@baseboard_fab2_lib.baseboard_fab2(sch_1):m_c_dq(46)';
NODE_NAME     U5D1 U32
 '@BASEBOARD_FAB2_LIB.BASEBOARD_FAB2(SCH_1):PAGE25_I172@CHPSET_LIB.SKX_EXT_B(CHIPS)':
 'DDR2_DQ'<46>: CDS_PINID='DDR2_DQ(46)';
NODE_NAME     J4G3 258
 '@BASEBOARD_FAB2_LIB.BASEBOARD_FAB2(SCH_1):PAGE47_I111@MSTR_SCONN.SCONN288_H44441004(CHIPS)':
 'DQ'<47>: CDS_PINID='DQ(47)';
NODE_NAME     J6U2 113
 '@BASEBOARD_FAB2_LIB.BASEBOARD_FAB2(SCH_1):PAGE48_I111@MSTR_SCONN.SCONN288_H44441003(CHIPS)':
 'DQ'<46>: CDS_PINID='DQ(46)';
NET_NAME
'M_C_DQ<47>'
 '@BASEBOARD_FAB2_LIB.BASEBOARD_FAB2(SCH_1):M_C_DQ'<47>:
 C_SIGNAL='@baseboard_fab2_lib.baseboard_fab2(sch_1):m_c_dq(47)';
NODE_NAME     U5D1 AA32
 '@BASEBOARD_FAB2_LIB.BASEBOARD_FAB2(SCH_1):PAGE25_I172@CHPSET_LIB.SKX_EXT_B(CHIPS)':
 'DDR2_DQ'<47>: CDS_PINID='DDR2_DQ(47)';
NODE_NAME     J4G3 113
 '@BASEBOARD_FAB2_LIB.BASEBOARD_FAB2(SCH_1):PAGE47_I111@MSTR_SCONN.SCONN288_H44441004(CHIPS)':
 'DQ'<46>: CDS_PINID='DQ(46)';
NODE_NAME     J6U2 258
 '@BASEBOARD_FAB2_LIB.BASEBOARD_FAB2(SCH_1):PAGE48_I111@MSTR_SCONN.SCONN288_H44441003(CHIPS)':
 'DQ'<47>: CDS_PINID='DQ(47)';
NET_NAME
'M_C_DQ<48>'
 '@BASEBOARD_FAB2_LIB.BASEBOARD_FAB2(SCH_1):M_C_DQ'<48>:
 C_SIGNAL='@baseboard_fab2_lib.baseboard_fab2(sch_1):m_c_dq(48)';
NODE_NAME     U5D1 AD31
 '@BASEBOARD_FAB2_LIB.BASEBOARD_FAB2(SCH_1):PAGE25_I172@CHPSET_LIB.SKX_EXT_B(CHIPS)':
 'DDR2_DQ'<48>: CDS_PINID='DDR2_DQ(48)';
NODE_NAME     J4G3 264
 '@BASEBOARD_FAB2_LIB.BASEBOARD_FAB2(SCH_1):PAGE47_I111@MSTR_SCONN.SCONN288_H44441004(CHIPS)':
 'DQ'<49>: CDS_PINID='DQ(49)';
NODE_NAME     J6U2 119
 '@BASEBOARD_FAB2_LIB.BASEBOARD_FAB2(SCH_1):PAGE48_I111@MSTR_SCONN.SCONN288_H44441003(CHIPS)':
 'DQ'<48>: CDS_PINID='DQ(48)';
NET_NAME
'M_C_DQ<49>'
 '@BASEBOARD_FAB2_LIB.BASEBOARD_FAB2(SCH_1):M_C_DQ'<49>:
 C_SIGNAL='@baseboard_fab2_lib.baseboard_fab2(sch_1):m_c_dq(49)';
NODE_NAME     U5D1 AH31
 '@BASEBOARD_FAB2_LIB.BASEBOARD_FAB2(SCH_1):PAGE25_I172@CHPSET_LIB.SKX_EXT_B(CHIPS)':
 'DDR2_DQ'<49>: CDS_PINID='DDR2_DQ(49)';
NODE_NAME     J4G3 119
 '@BASEBOARD_FAB2_LIB.BASEBOARD_FAB2(SCH_1):PAGE47_I111@MSTR_SCONN.SCONN288_H44441004(CHIPS)':
 'DQ'<48>: CDS_PINID='DQ(48)';
NODE_NAME     J6U2 264
 '@BASEBOARD_FAB2_LIB.BASEBOARD_FAB2(SCH_1):PAGE48_I111@MSTR_SCONN.SCONN288_H44441003(CHIPS)':
 'DQ'<49>: CDS_PINID='DQ(49)';
NET_NAME
'M_C_DQ<4>'
 '@BASEBOARD_FAB2_LIB.BASEBOARD_FAB2(SCH_1):M_C_DQ'<4>:
 C_SIGNAL='@baseboard_fab2_lib.baseboard_fab2(sch_1):m_c_dq(4)';
NODE_NAME     U5D1 AT75
 '@BASEBOARD_FAB2_LIB.BASEBOARD_FAB2(SCH_1):PAGE25_I172@CHPSET_LIB.SKX_EXT_B(CHIPS)':
 'DDR2_DQ'<4>: CDS_PINID='DDR2_DQ(4)';
NODE_NAME     J4G3 148
 '@BASEBOARD_FAB2_LIB.BASEBOARD_FAB2(SCH_1):PAGE47_I111@MSTR_SCONN.SCONN288_H44441004(CHIPS)':
 'DQ'<5>: CDS_PINID='DQ(5)';
NODE_NAME     J6U2 3
 '@BASEBOARD_FAB2_LIB.BASEBOARD_FAB2(SCH_1):PAGE48_I111@MSTR_SCONN.SCONN288_H44441003(CHIPS)':
 'DQ'<4>: CDS_PINID='DQ(4)';
NET_NAME
'M_C_DQ<50>'
 '@BASEBOARD_FAB2_LIB.BASEBOARD_FAB2(SCH_1):M_C_DQ'<50>:
 C_SIGNAL='@baseboard_fab2_lib.baseboard_fab2(sch_1):m_c_dq(50)';
NODE_NAME     U5D1 AE28
 '@BASEBOARD_FAB2_LIB.BASEBOARD_FAB2(SCH_1):PAGE25_I172@CHPSET_LIB.SKX_EXT_B(CHIPS)':
 'DDR2_DQ'<50>: CDS_PINID='DDR2_DQ(50)';
NODE_NAME     J4G3 271
 '@BASEBOARD_FAB2_LIB.BASEBOARD_FAB2(SCH_1):PAGE47_I111@MSTR_SCONN.SCONN288_H44441004(CHIPS)':
 'DQ'<51>: CDS_PINID='DQ(51)';
NODE_NAME     J6U2 126
 '@BASEBOARD_FAB2_LIB.BASEBOARD_FAB2(SCH_1):PAGE48_I111@MSTR_SCONN.SCONN288_H44441003(CHIPS)':
 'DQ'<50>: CDS_PINID='DQ(50)';
NET_NAME
'M_C_DQ<51>'
 '@BASEBOARD_FAB2_LIB.BASEBOARD_FAB2(SCH_1):M_C_DQ'<51>:
 C_SIGNAL='@baseboard_fab2_lib.baseboard_fab2(sch_1):m_c_dq(51)';
NODE_NAME     U5D1 AG28
 '@BASEBOARD_FAB2_LIB.BASEBOARD_FAB2(SCH_1):PAGE25_I172@CHPSET_LIB.SKX_EXT_B(CHIPS)':
 'DDR2_DQ'<51>: CDS_PINID='DDR2_DQ(51)';
NODE_NAME     J4G3 126
 '@BASEBOARD_FAB2_LIB.BASEBOARD_FAB2(SCH_1):PAGE47_I111@MSTR_SCONN.SCONN288_H44441004(CHIPS)':
 'DQ'<50>: CDS_PINID='DQ(50)';
NODE_NAME     J6U2 271
 '@BASEBOARD_FAB2_LIB.BASEBOARD_FAB2(SCH_1):PAGE48_I111@MSTR_SCONN.SCONN288_H44441003(CHIPS)':
 'DQ'<51>: CDS_PINID='DQ(51)';
NET_NAME
'M_C_DQ<52>'
 '@BASEBOARD_FAB2_LIB.BASEBOARD_FAB2(SCH_1):M_C_DQ'<52>:
 C_SIGNAL='@baseboard_fab2_lib.baseboard_fab2(sch_1):m_c_dq(52)';
NODE_NAME     U5D1 AE32
 '@BASEBOARD_FAB2_LIB.BASEBOARD_FAB2(SCH_1):PAGE25_I172@CHPSET_LIB.SKX_EXT_B(CHIPS)':
 'DDR2_DQ'<52>: CDS_PINID='DDR2_DQ(52)';
NODE_NAME     J4G3 262
 '@BASEBOARD_FAB2_LIB.BASEBOARD_FAB2(SCH_1):PAGE47_I111@MSTR_SCONN.SCONN288_H44441004(CHIPS)':
 'DQ'<53>: CDS_PINID='DQ(53)';
NODE_NAME     J6U2 117
 '@BASEBOARD_FAB2_LIB.BASEBOARD_FAB2(SCH_1):PAGE48_I111@MSTR_SCONN.SCONN288_H44441003(CHIPS)':
 'DQ'<52>: CDS_PINID='DQ(52)';
NET_NAME
'M_C_DQ<53>'
 '@BASEBOARD_FAB2_LIB.BASEBOARD_FAB2(SCH_1):M_C_DQ'<53>:
 C_SIGNAL='@baseboard_fab2_lib.baseboard_fab2(sch_1):m_c_dq(53)';
NODE_NAME     U5D1 AG32
 '@BASEBOARD_FAB2_LIB.BASEBOARD_FAB2(SCH_1):PAGE25_I172@CHPSET_LIB.SKX_EXT_B(CHIPS)':
 'DDR2_DQ'<53>: CDS_PINID='DDR2_DQ(53)';
NODE_NAME     J4G3 117
 '@BASEBOARD_FAB2_LIB.BASEBOARD_FAB2(SCH_1):PAGE47_I111@MSTR_SCONN.SCONN288_H44441004(CHIPS)':
 'DQ'<52>: CDS_PINID='DQ(52)';
NODE_NAME     J6U2 262
 '@BASEBOARD_FAB2_LIB.BASEBOARD_FAB2(SCH_1):PAGE48_I111@MSTR_SCONN.SCONN288_H44441003(CHIPS)':
 'DQ'<53>: CDS_PINID='DQ(53)';
NET_NAME
'M_C_DQ<54>'
 '@BASEBOARD_FAB2_LIB.BASEBOARD_FAB2(SCH_1):M_C_DQ'<54>:
 C_SIGNAL='@baseboard_fab2_lib.baseboard_fab2(sch_1):m_c_dq(54)';
NODE_NAME     U5D1 AD29
 '@BASEBOARD_FAB2_LIB.BASEBOARD_FAB2(SCH_1):PAGE25_I172@CHPSET_LIB.SKX_EXT_B(CHIPS)':
 'DDR2_DQ'<54>: CDS_PINID='DDR2_DQ(54)';
NODE_NAME     J4G3 269
 '@BASEBOARD_FAB2_LIB.BASEBOARD_FAB2(SCH_1):PAGE47_I111@MSTR_SCONN.SCONN288_H44441004(CHIPS)':
 'DQ'<55>: CDS_PINID='DQ(55)';
NODE_NAME     J6U2 124
 '@BASEBOARD_FAB2_LIB.BASEBOARD_FAB2(SCH_1):PAGE48_I111@MSTR_SCONN.SCONN288_H44441003(CHIPS)':
 'DQ'<54>: CDS_PINID='DQ(54)';
NET_NAME
'M_C_DQ<55>'
 '@BASEBOARD_FAB2_LIB.BASEBOARD_FAB2(SCH_1):M_C_DQ'<55>:
 C_SIGNAL='@baseboard_fab2_lib.baseboard_fab2(sch_1):m_c_dq(55)';
NODE_NAME     U5D1 AH29
 '@BASEBOARD_FAB2_LIB.BASEBOARD_FAB2(SCH_1):PAGE25_I172@CHPSET_LIB.SKX_EXT_B(CHIPS)':
 'DDR2_DQ'<55>: CDS_PINID='DDR2_DQ(55)';
NODE_NAME     J4G3 124
 '@BASEBOARD_FAB2_LIB.BASEBOARD_FAB2(SCH_1):PAGE47_I111@MSTR_SCONN.SCONN288_H44441004(CHIPS)':
 'DQ'<54>: CDS_PINID='DQ(54)';
NODE_NAME     J6U2 269
 '@BASEBOARD_FAB2_LIB.BASEBOARD_FAB2(SCH_1):PAGE48_I111@MSTR_SCONN.SCONN288_H44441003(CHIPS)':
 'DQ'<55>: CDS_PINID='DQ(55)';
NET_NAME
'M_C_DQ<56>'
 '@BASEBOARD_FAB2_LIB.BASEBOARD_FAB2(SCH_1):M_C_DQ'<56>:
 C_SIGNAL='@baseboard_fab2_lib.baseboard_fab2(sch_1):m_c_dq(56)';
NODE_NAME     U5D1 AD25
 '@BASEBOARD_FAB2_LIB.BASEBOARD_FAB2(SCH_1):PAGE25_I172@CHPSET_LIB.SKX_EXT_B(CHIPS)':
 'DDR2_DQ'<56>: CDS_PINID='DDR2_DQ(56)';
NODE_NAME     J4G3 275
 '@BASEBOARD_FAB2_LIB.BASEBOARD_FAB2(SCH_1):PAGE47_I111@MSTR_SCONN.SCONN288_H44441004(CHIPS)':
 'DQ'<57>: CDS_PINID='DQ(57)';
NODE_NAME     J6U2 130
 '@BASEBOARD_FAB2_LIB.BASEBOARD_FAB2(SCH_1):PAGE48_I111@MSTR_SCONN.SCONN288_H44441003(CHIPS)':
 'DQ'<56>: CDS_PINID='DQ(56)';
NET_NAME
'M_C_DQ<57>'
 '@BASEBOARD_FAB2_LIB.BASEBOARD_FAB2(SCH_1):M_C_DQ'<57>:
 C_SIGNAL='@baseboard_fab2_lib.baseboard_fab2(sch_1):m_c_dq(57)';
NODE_NAME     U5D1 AH25
 '@BASEBOARD_FAB2_LIB.BASEBOARD_FAB2(SCH_1):PAGE25_I172@CHPSET_LIB.SKX_EXT_B(CHIPS)':
 'DDR2_DQ'<57>: CDS_PINID='DDR2_DQ(57)';
NODE_NAME     J4G3 130
 '@BASEBOARD_FAB2_LIB.BASEBOARD_FAB2(SCH_1):PAGE47_I111@MSTR_SCONN.SCONN288_H44441004(CHIPS)':
 'DQ'<56>: CDS_PINID='DQ(56)';
NODE_NAME     J6U2 275
 '@BASEBOARD_FAB2_LIB.BASEBOARD_FAB2(SCH_1):PAGE48_I111@MSTR_SCONN.SCONN288_H44441003(CHIPS)':
 'DQ'<57>: CDS_PINID='DQ(57)';
NET_NAME
'M_C_DQ<58>'
 '@BASEBOARD_FAB2_LIB.BASEBOARD_FAB2(SCH_1):M_C_DQ'<58>:
 C_SIGNAL='@baseboard_fab2_lib.baseboard_fab2(sch_1):m_c_dq(58)';
NODE_NAME     U5D1 AE22
 '@BASEBOARD_FAB2_LIB.BASEBOARD_FAB2(SCH_1):PAGE25_I172@CHPSET_LIB.SKX_EXT_B(CHIPS)':
 'DDR2_DQ'<58>: CDS_PINID='DDR2_DQ(58)';
NODE_NAME     J4G3 282
 '@BASEBOARD_FAB2_LIB.BASEBOARD_FAB2(SCH_1):PAGE47_I111@MSTR_SCONN.SCONN288_H44441004(CHIPS)':
 'DQ'<59>: CDS_PINID='DQ(59)';
NODE_NAME     J6U2 137
 '@BASEBOARD_FAB2_LIB.BASEBOARD_FAB2(SCH_1):PAGE48_I111@MSTR_SCONN.SCONN288_H44441003(CHIPS)':
 'DQ'<58>: CDS_PINID='DQ(58)';
NET_NAME
'M_C_DQ<59>'
 '@BASEBOARD_FAB2_LIB.BASEBOARD_FAB2(SCH_1):M_C_DQ'<59>:
 C_SIGNAL='@baseboard_fab2_lib.baseboard_fab2(sch_1):m_c_dq(59)';
NODE_NAME     U5D1 AG22
 '@BASEBOARD_FAB2_LIB.BASEBOARD_FAB2(SCH_1):PAGE25_I172@CHPSET_LIB.SKX_EXT_B(CHIPS)':
 'DDR2_DQ'<59>: CDS_PINID='DDR2_DQ(59)';
NODE_NAME     J4G3 137
 '@BASEBOARD_FAB2_LIB.BASEBOARD_FAB2(SCH_1):PAGE47_I111@MSTR_SCONN.SCONN288_H44441004(CHIPS)':
 'DQ'<58>: CDS_PINID='DQ(58)';
NODE_NAME     J6U2 282
 '@BASEBOARD_FAB2_LIB.BASEBOARD_FAB2(SCH_1):PAGE48_I111@MSTR_SCONN.SCONN288_H44441003(CHIPS)':
 'DQ'<59>: CDS_PINID='DQ(59)';
NET_NAME
'M_C_DQ<5>'
 '@BASEBOARD_FAB2_LIB.BASEBOARD_FAB2(SCH_1):M_C_DQ'<5>:
 C_SIGNAL='@baseboard_fab2_lib.baseboard_fab2(sch_1):m_c_dq(5)';
NODE_NAME     U5D1 AR74
 '@BASEBOARD_FAB2_LIB.BASEBOARD_FAB2(SCH_1):PAGE25_I172@CHPSET_LIB.SKX_EXT_B(CHIPS)':
 'DDR2_DQ'<5>: CDS_PINID='DDR2_DQ(5)';
NODE_NAME     J4G3 3
 '@BASEBOARD_FAB2_LIB.BASEBOARD_FAB2(SCH_1):PAGE47_I111@MSTR_SCONN.SCONN288_H44441004(CHIPS)':
 'DQ'<4>: CDS_PINID='DQ(4)';
NODE_NAME     J6U2 148
 '@BASEBOARD_FAB2_LIB.BASEBOARD_FAB2(SCH_1):PAGE48_I111@MSTR_SCONN.SCONN288_H44441003(CHIPS)':
 'DQ'<5>: CDS_PINID='DQ(5)';
NET_NAME
'M_C_DQ<60>'
 '@BASEBOARD_FAB2_LIB.BASEBOARD_FAB2(SCH_1):M_C_DQ'<60>:
 C_SIGNAL='@baseboard_fab2_lib.baseboard_fab2(sch_1):m_c_dq(60)';
NODE_NAME     U5D1 AE26
 '@BASEBOARD_FAB2_LIB.BASEBOARD_FAB2(SCH_1):PAGE25_I172@CHPSET_LIB.SKX_EXT_B(CHIPS)':
 'DDR2_DQ'<60>: CDS_PINID='DDR2_DQ(60)';
NODE_NAME     J4G3 273
 '@BASEBOARD_FAB2_LIB.BASEBOARD_FAB2(SCH_1):PAGE47_I111@MSTR_SCONN.SCONN288_H44441004(CHIPS)':
 'DQ'<61>: CDS_PINID='DQ(61)';
NODE_NAME     J6U2 128
 '@BASEBOARD_FAB2_LIB.BASEBOARD_FAB2(SCH_1):PAGE48_I111@MSTR_SCONN.SCONN288_H44441003(CHIPS)':
 'DQ'<60>: CDS_PINID='DQ(60)';
NET_NAME
'M_C_DQ<61>'
 '@BASEBOARD_FAB2_LIB.BASEBOARD_FAB2(SCH_1):M_C_DQ'<61>:
 C_SIGNAL='@baseboard_fab2_lib.baseboard_fab2(sch_1):m_c_dq(61)';
NODE_NAME     U5D1 AG26
 '@BASEBOARD_FAB2_LIB.BASEBOARD_FAB2(SCH_1):PAGE25_I172@CHPSET_LIB.SKX_EXT_B(CHIPS)':
 'DDR2_DQ'<61>: CDS_PINID='DDR2_DQ(61)';
NODE_NAME     J4G3 128
 '@BASEBOARD_FAB2_LIB.BASEBOARD_FAB2(SCH_1):PAGE47_I111@MSTR_SCONN.SCONN288_H44441004(CHIPS)':
 'DQ'<60>: CDS_PINID='DQ(60)';
NODE_NAME     J6U2 273
 '@BASEBOARD_FAB2_LIB.BASEBOARD_FAB2(SCH_1):PAGE48_I111@MSTR_SCONN.SCONN288_H44441003(CHIPS)':
 'DQ'<61>: CDS_PINID='DQ(61)';
NET_NAME
'M_C_DQ<62>'
 '@BASEBOARD_FAB2_LIB.BASEBOARD_FAB2(SCH_1):M_C_DQ'<62>:
 C_SIGNAL='@baseboard_fab2_lib.baseboard_fab2(sch_1):m_c_dq(62)';
NODE_NAME     U5D1 AD23
 '@BASEBOARD_FAB2_LIB.BASEBOARD_FAB2(SCH_1):PAGE25_I172@CHPSET_LIB.SKX_EXT_B(CHIPS)':
 'DDR2_DQ'<62>: CDS_PINID='DDR2_DQ(62)';
NODE_NAME     J4G3 280
 '@BASEBOARD_FAB2_LIB.BASEBOARD_FAB2(SCH_1):PAGE47_I111@MSTR_SCONN.SCONN288_H44441004(CHIPS)':
 'DQ'<63>: CDS_PINID='DQ(63)';
NODE_NAME     J6U2 135
 '@BASEBOARD_FAB2_LIB.BASEBOARD_FAB2(SCH_1):PAGE48_I111@MSTR_SCONN.SCONN288_H44441003(CHIPS)':
 'DQ'<62>: CDS_PINID='DQ(62)';
NET_NAME
'M_C_DQ<63>'
 '@BASEBOARD_FAB2_LIB.BASEBOARD_FAB2(SCH_1):M_C_DQ'<63>:
 C_SIGNAL='@baseboard_fab2_lib.baseboard_fab2(sch_1):m_c_dq(63)';
NODE_NAME     U5D1 AH23
 '@BASEBOARD_FAB2_LIB.BASEBOARD_FAB2(SCH_1):PAGE25_I172@CHPSET_LIB.SKX_EXT_B(CHIPS)':
 'DDR2_DQ'<63>: CDS_PINID='DDR2_DQ(63)';
NODE_NAME     J4G3 135
 '@BASEBOARD_FAB2_LIB.BASEBOARD_FAB2(SCH_1):PAGE47_I111@MSTR_SCONN.SCONN288_H44441004(CHIPS)':
 'DQ'<62>: CDS_PINID='DQ(62)';
NODE_NAME     J6U2 280
 '@BASEBOARD_FAB2_LIB.BASEBOARD_FAB2(SCH_1):PAGE48_I111@MSTR_SCONN.SCONN288_H44441003(CHIPS)':
 'DQ'<63>: CDS_PINID='DQ(63)';
NET_NAME
'M_C_DQ<6>'
 '@BASEBOARD_FAB2_LIB.BASEBOARD_FAB2(SCH_1):M_C_DQ'<6>:
 C_SIGNAL='@baseboard_fab2_lib.baseboard_fab2(sch_1):m_c_dq(6)';
NODE_NAME     U5D1 AM77
 '@BASEBOARD_FAB2_LIB.BASEBOARD_FAB2(SCH_1):PAGE25_I172@CHPSET_LIB.SKX_EXT_B(CHIPS)':
 'DDR2_DQ'<6>: CDS_PINID='DDR2_DQ(6)';
NODE_NAME     J4G3 155
 '@BASEBOARD_FAB2_LIB.BASEBOARD_FAB2(SCH_1):PAGE47_I111@MSTR_SCONN.SCONN288_H44441004(CHIPS)':
 'DQ'<7>: CDS_PINID='DQ(7)';
NODE_NAME     J6U2 10
 '@BASEBOARD_FAB2_LIB.BASEBOARD_FAB2(SCH_1):PAGE48_I111@MSTR_SCONN.SCONN288_H44441003(CHIPS)':
 'DQ'<6>: CDS_PINID='DQ(6)';
NET_NAME
'M_C_DQ<7>'
 '@BASEBOARD_FAB2_LIB.BASEBOARD_FAB2(SCH_1):M_C_DQ'<7>:
 C_SIGNAL='@baseboard_fab2_lib.baseboard_fab2(sch_1):m_c_dq(7)';
NODE_NAME     U5D1 AK75
 '@BASEBOARD_FAB2_LIB.BASEBOARD_FAB2(SCH_1):PAGE25_I172@CHPSET_LIB.SKX_EXT_B(CHIPS)':
 'DDR2_DQ'<7>: CDS_PINID='DDR2_DQ(7)';
NODE_NAME     J4G3 10
 '@BASEBOARD_FAB2_LIB.BASEBOARD_FAB2(SCH_1):PAGE47_I111@MSTR_SCONN.SCONN288_H44441004(CHIPS)':
 'DQ'<6>: CDS_PINID='DQ(6)';
NODE_NAME     J6U2 155
 '@BASEBOARD_FAB2_LIB.BASEBOARD_FAB2(SCH_1):PAGE48_I111@MSTR_SCONN.SCONN288_H44441003(CHIPS)':
 'DQ'<7>: CDS_PINID='DQ(7)';
NET_NAME
'M_C_DQ<8>'
 '@BASEBOARD_FAB2_LIB.BASEBOARD_FAB2(SCH_1):M_C_DQ'<8>:
 C_SIGNAL='@baseboard_fab2_lib.baseboard_fab2(sch_1):m_c_dq(8)';
NODE_NAME     U5D1 AE76
 '@BASEBOARD_FAB2_LIB.BASEBOARD_FAB2(SCH_1):PAGE25_I172@CHPSET_LIB.SKX_EXT_B(CHIPS)':
 'DDR2_DQ'<8>: CDS_PINID='DDR2_DQ(8)';
NODE_NAME     J4G3 161
 '@BASEBOARD_FAB2_LIB.BASEBOARD_FAB2(SCH_1):PAGE47_I111@MSTR_SCONN.SCONN288_H44441004(CHIPS)':
 'DQ'<9>: CDS_PINID='DQ(9)';
NODE_NAME     J6U2 16
 '@BASEBOARD_FAB2_LIB.BASEBOARD_FAB2(SCH_1):PAGE48_I111@MSTR_SCONN.SCONN288_H44441003(CHIPS)':
 'DQ'<8>: CDS_PINID='DQ(8)';
NET_NAME
'M_C_DQ<9>'
 '@BASEBOARD_FAB2_LIB.BASEBOARD_FAB2(SCH_1):M_C_DQ'<9>:
 C_SIGNAL='@baseboard_fab2_lib.baseboard_fab2(sch_1):m_c_dq(9)';
NODE_NAME     U5D1 AC74
 '@BASEBOARD_FAB2_LIB.BASEBOARD_FAB2(SCH_1):PAGE25_I172@CHPSET_LIB.SKX_EXT_B(CHIPS)':
 'DDR2_DQ'<9>: CDS_PINID='DDR2_DQ(9)';
NODE_NAME     J4G3 16
 '@BASEBOARD_FAB2_LIB.BASEBOARD_FAB2(SCH_1):PAGE47_I111@MSTR_SCONN.SCONN288_H44441004(CHIPS)':
 'DQ'<8>: CDS_PINID='DQ(8)';
NODE_NAME     J6U2 161
 '@BASEBOARD_FAB2_LIB.BASEBOARD_FAB2(SCH_1):PAGE48_I111@MSTR_SCONN.SCONN288_H44441003(CHIPS)':
 'DQ'<9>: CDS_PINID='DQ(9)';
NET_NAME
'M_C_DQS_DN<0>'
 '@BASEBOARD_FAB2_LIB.BASEBOARD_FAB2(SCH_1):M_C_DQS_DN'<0>:
 C_SIGNAL='@baseboard_fab2_lib.baseboard_fab2(sch_1):m_c_dqs_dn(0)';
NODE_NAME     U5D1 AL74
 '@BASEBOARD_FAB2_LIB.BASEBOARD_FAB2(SCH_1):PAGE25_I172@CHPSET_LIB.SKX_EXT_B(CHIPS)':
 'DDR2_DQS_DN'<0>: CDS_PINID='DDR2_DQS_DN(0)';
NODE_NAME     J4G3 152
 '@BASEBOARD_FAB2_LIB.BASEBOARD_FAB2(SCH_1):PAGE47_I61@MSTR_SCONN.SCONN288_H44441004(CHIPS)':
 'DQS0N': CDS_PINID='DQS0N';
NODE_NAME     J6U2 152
 '@BASEBOARD_FAB2_LIB.BASEBOARD_FAB2(SCH_1):PAGE48_I61@MSTR_SCONN.SCONN288_H44441003(CHIPS)':
 'DQS0N': CDS_PINID='DQS0N';
NET_NAME
'M_C_DQS_DN<10>'
 '@BASEBOARD_FAB2_LIB.BASEBOARD_FAB2(SCH_1):M_C_DQS_DN'<10>:
 C_SIGNAL='@baseboard_fab2_lib.baseboard_fab2(sch_1):m_c_dqs_dn(10)';
NODE_NAME     U5D1 AD77
 '@BASEBOARD_FAB2_LIB.BASEBOARD_FAB2(SCH_1):PAGE25_I172@CHPSET_LIB.SKX_EXT_B(CHIPS)':
 'DDR2_DQS_DN'<10>: CDS_PINID='DDR2_DQS_DN(10)';
NODE_NAME     J4G3 19
 '@BASEBOARD_FAB2_LIB.BASEBOARD_FAB2(SCH_1):PAGE47_I61@MSTR_SCONN.SCONN288_H44441004(CHIPS)':
 'DQS10N': CDS_PINID='DQS10N';
NODE_NAME     J6U2 19
 '@BASEBOARD_FAB2_LIB.BASEBOARD_FAB2(SCH_1):PAGE48_I61@MSTR_SCONN.SCONN288_H44441003(CHIPS)':
 'DQS10N': CDS_PINID='DQS10N';
NET_NAME
'M_C_DQS_DN<11>'
 '@BASEBOARD_FAB2_LIB.BASEBOARD_FAB2(SCH_1):M_C_DQS_DN'<11>:
 C_SIGNAL='@baseboard_fab2_lib.baseboard_fab2(sch_1):m_c_dqs_dn(11)';
NODE_NAME     U5D1 U72
 '@BASEBOARD_FAB2_LIB.BASEBOARD_FAB2(SCH_1):PAGE25_I172@CHPSET_LIB.SKX_EXT_B(CHIPS)':
 'DDR2_DQS_DN'<11>: CDS_PINID='DDR2_DQS_DN(11)';
NODE_NAME     J4G3 30
 '@BASEBOARD_FAB2_LIB.BASEBOARD_FAB2(SCH_1):PAGE47_I61@MSTR_SCONN.SCONN288_H44441004(CHIPS)':
 'DQS11N': CDS_PINID='DQS11N';
NODE_NAME     J6U2 30
 '@BASEBOARD_FAB2_LIB.BASEBOARD_FAB2(SCH_1):PAGE48_I61@MSTR_SCONN.SCONN288_H44441003(CHIPS)':
 'DQS11N': CDS_PINID='DQS11N';
NET_NAME
'M_C_DQS_DN<12>'
 '@BASEBOARD_FAB2_LIB.BASEBOARD_FAB2(SCH_1):M_C_DQS_DN'<12>:
 C_SIGNAL='@baseboard_fab2_lib.baseboard_fab2(sch_1):m_c_dqs_dn(12)';
NODE_NAME     U5D1 AL66
 '@BASEBOARD_FAB2_LIB.BASEBOARD_FAB2(SCH_1):PAGE25_I172@CHPSET_LIB.SKX_EXT_B(CHIPS)':
 'DDR2_DQS_DN'<12>: CDS_PINID='DDR2_DQS_DN(12)';
NODE_NAME     J4G3 41
 '@BASEBOARD_FAB2_LIB.BASEBOARD_FAB2(SCH_1):PAGE47_I61@MSTR_SCONN.SCONN288_H44441004(CHIPS)':
 'DQS12N': CDS_PINID='DQS12N';
NODE_NAME     J6U2 41
 '@BASEBOARD_FAB2_LIB.BASEBOARD_FAB2(SCH_1):PAGE48_I61@MSTR_SCONN.SCONN288_H44441003(CHIPS)':
 'DQS12N': CDS_PINID='DQS12N';
NET_NAME
'M_C_DQS_DN<13>'
 '@BASEBOARD_FAB2_LIB.BASEBOARD_FAB2(SCH_1):M_C_DQS_DN'<13>:
 C_SIGNAL='@baseboard_fab2_lib.baseboard_fab2(sch_1):m_c_dqs_dn(13)';
NODE_NAME     U5D1 T39
 '@BASEBOARD_FAB2_LIB.BASEBOARD_FAB2(SCH_1):PAGE25_I172@CHPSET_LIB.SKX_EXT_B(CHIPS)':
 'DDR2_DQS_DN'<13>: CDS_PINID='DDR2_DQS_DN(13)';
NODE_NAME     J4G3 100
 '@BASEBOARD_FAB2_LIB.BASEBOARD_FAB2(SCH_1):PAGE47_I61@MSTR_SCONN.SCONN288_H44441004(CHIPS)':
 'DQS13N': CDS_PINID='DQS13N';
NODE_NAME     J6U2 100
 '@BASEBOARD_FAB2_LIB.BASEBOARD_FAB2(SCH_1):PAGE48_I61@MSTR_SCONN.SCONN288_H44441003(CHIPS)':
 'DQS13N': CDS_PINID='DQS13N';
NET_NAME
'M_C_DQS_DN<14>'
 '@BASEBOARD_FAB2_LIB.BASEBOARD_FAB2(SCH_1):M_C_DQS_DN'<14>:
 C_SIGNAL='@baseboard_fab2_lib.baseboard_fab2(sch_1):m_c_dqs_dn(14)';
NODE_NAME     U5D1 T33
 '@BASEBOARD_FAB2_LIB.BASEBOARD_FAB2(SCH_1):PAGE25_I172@CHPSET_LIB.SKX_EXT_B(CHIPS)':
 'DDR2_DQS_DN'<14>: CDS_PINID='DDR2_DQS_DN(14)';
NODE_NAME     J4G3 111
 '@BASEBOARD_FAB2_LIB.BASEBOARD_FAB2(SCH_1):PAGE47_I61@MSTR_SCONN.SCONN288_H44441004(CHIPS)':
 'DQS14N': CDS_PINID='DQS14N';
NODE_NAME     J6U2 111
 '@BASEBOARD_FAB2_LIB.BASEBOARD_FAB2(SCH_1):PAGE48_I61@MSTR_SCONN.SCONN288_H44441003(CHIPS)':
 'DQS14N': CDS_PINID='DQS14N';
NET_NAME
'M_C_DQS_DN<15>'
 '@BASEBOARD_FAB2_LIB.BASEBOARD_FAB2(SCH_1):M_C_DQS_DN'<15>:
 C_SIGNAL='@baseboard_fab2_lib.baseboard_fab2(sch_1):m_c_dqs_dn(15)';
NODE_NAME     U5D1 AC30
 '@BASEBOARD_FAB2_LIB.BASEBOARD_FAB2(SCH_1):PAGE25_I172@CHPSET_LIB.SKX_EXT_B(CHIPS)':
 'DDR2_DQS_DN'<15>: CDS_PINID='DDR2_DQS_DN(15)';
NODE_NAME     J4G3 122
 '@BASEBOARD_FAB2_LIB.BASEBOARD_FAB2(SCH_1):PAGE47_I61@MSTR_SCONN.SCONN288_H44441004(CHIPS)':
 'DQS15N': CDS_PINID='DQS15N';
NODE_NAME     J6U2 122
 '@BASEBOARD_FAB2_LIB.BASEBOARD_FAB2(SCH_1):PAGE48_I61@MSTR_SCONN.SCONN288_H44441003(CHIPS)':
 'DQS15N': CDS_PINID='DQS15N';
NET_NAME
'M_C_DQS_DN<16>'
 '@BASEBOARD_FAB2_LIB.BASEBOARD_FAB2(SCH_1):M_C_DQS_DN'<16>:
 C_SIGNAL='@baseboard_fab2_lib.baseboard_fab2(sch_1):m_c_dqs_dn(16)';
NODE_NAME     U5D1 AC24
 '@BASEBOARD_FAB2_LIB.BASEBOARD_FAB2(SCH_1):PAGE25_I172@CHPSET_LIB.SKX_EXT_B(CHIPS)':
 'DDR2_DQS_DN'<16>: CDS_PINID='DDR2_DQS_DN(16)';
NODE_NAME     J4G3 133
 '@BASEBOARD_FAB2_LIB.BASEBOARD_FAB2(SCH_1):PAGE47_I61@MSTR_SCONN.SCONN288_H44441004(CHIPS)':
 'DQS16N': CDS_PINID='DQS16N';
NODE_NAME     J6U2 133
 '@BASEBOARD_FAB2_LIB.BASEBOARD_FAB2(SCH_1):PAGE48_I61@MSTR_SCONN.SCONN288_H44441003(CHIPS)':
 'DQS16N': CDS_PINID='DQS16N';
NET_NAME
'M_C_DQS_DN<17>'
 '@BASEBOARD_FAB2_LIB.BASEBOARD_FAB2(SCH_1):M_C_DQS_DN'<17>:
 C_SIGNAL='@baseboard_fab2_lib.baseboard_fab2(sch_1):m_c_dqs_dn(17)';
NODE_NAME     U5D1 AT71
 '@BASEBOARD_FAB2_LIB.BASEBOARD_FAB2(SCH_1):PAGE25_I172@CHPSET_LIB.SKX_EXT_B(CHIPS)':
 'DDR2_DQS_DN'<17>: CDS_PINID='DDR2_DQS_DN(17)';
NODE_NAME     J4G3 52
 '@BASEBOARD_FAB2_LIB.BASEBOARD_FAB2(SCH_1):PAGE47_I61@MSTR_SCONN.SCONN288_H44441004(CHIPS)':
 'DQS17N': CDS_PINID='DQS17N';
NODE_NAME     J6U2 52
 '@BASEBOARD_FAB2_LIB.BASEBOARD_FAB2(SCH_1):PAGE48_I61@MSTR_SCONN.SCONN288_H44441003(CHIPS)':
 'DQS17N': CDS_PINID='DQS17N';
NET_NAME
'M_C_DQS_DN<1>'
 '@BASEBOARD_FAB2_LIB.BASEBOARD_FAB2(SCH_1):M_C_DQS_DN'<1>:
 C_SIGNAL='@baseboard_fab2_lib.baseboard_fab2(sch_1):m_c_dqs_dn(1)';
NODE_NAME     U5D1 AA74
 '@BASEBOARD_FAB2_LIB.BASEBOARD_FAB2(SCH_1):PAGE25_I172@CHPSET_LIB.SKX_EXT_B(CHIPS)':
 'DDR2_DQS_DN'<1>: CDS_PINID='DDR2_DQS_DN(1)';
NODE_NAME     J4G3 163
 '@BASEBOARD_FAB2_LIB.BASEBOARD_FAB2(SCH_1):PAGE47_I61@MSTR_SCONN.SCONN288_H44441004(CHIPS)':
 'DQS1N': CDS_PINID='DQS1N';
NODE_NAME     J6U2 163
 '@BASEBOARD_FAB2_LIB.BASEBOARD_FAB2(SCH_1):PAGE48_I61@MSTR_SCONN.SCONN288_H44441003(CHIPS)':
 'DQS1N': CDS_PINID='DQS1N';
NET_NAME
'M_C_DQS_DN<2>'
 '@BASEBOARD_FAB2_LIB.BASEBOARD_FAB2(SCH_1):M_C_DQS_DN'<2>:
 C_SIGNAL='@baseboard_fab2_lib.baseboard_fab2(sch_1):m_c_dqs_dn(2)';
NODE_NAME     U5D1 Y69
 '@BASEBOARD_FAB2_LIB.BASEBOARD_FAB2(SCH_1):PAGE25_I172@CHPSET_LIB.SKX_EXT_B(CHIPS)':
 'DDR2_DQS_DN'<2>: CDS_PINID='DDR2_DQS_DN(2)';
NODE_NAME     J4G3 174
 '@BASEBOARD_FAB2_LIB.BASEBOARD_FAB2(SCH_1):PAGE47_I61@MSTR_SCONN.SCONN288_H44441004(CHIPS)':
 'DQS2N': CDS_PINID='DQS2N';
NODE_NAME     J6U2 174
 '@BASEBOARD_FAB2_LIB.BASEBOARD_FAB2(SCH_1):PAGE48_I61@MSTR_SCONN.SCONN288_H44441003(CHIPS)':
 'DQS2N': CDS_PINID='DQS2N';
NET_NAME
'M_C_DQS_DN<3>'
 '@BASEBOARD_FAB2_LIB.BASEBOARD_FAB2(SCH_1):M_C_DQS_DN'<3>:
 C_SIGNAL='@baseboard_fab2_lib.baseboard_fab2(sch_1):m_c_dqs_dn(3)';
NODE_NAME     U5D1 AU66
 '@BASEBOARD_FAB2_LIB.BASEBOARD_FAB2(SCH_1):PAGE25_I172@CHPSET_LIB.SKX_EXT_B(CHIPS)':
 'DDR2_DQS_DN'<3>: CDS_PINID='DDR2_DQS_DN(3)';
NODE_NAME     J4G3 185
 '@BASEBOARD_FAB2_LIB.BASEBOARD_FAB2(SCH_1):PAGE47_I61@MSTR_SCONN.SCONN288_H44441004(CHIPS)':
 'DQS3N': CDS_PINID='DQS3N';
NODE_NAME     J6U2 185
 '@BASEBOARD_FAB2_LIB.BASEBOARD_FAB2(SCH_1):PAGE48_I61@MSTR_SCONN.SCONN288_H44441003(CHIPS)':
 'DQS3N': CDS_PINID='DQS3N';
NET_NAME
'M_C_DQS_DN<4>'
 '@BASEBOARD_FAB2_LIB.BASEBOARD_FAB2(SCH_1):M_C_DQS_DN'<4>:
 C_SIGNAL='@baseboard_fab2_lib.baseboard_fab2(sch_1):m_c_dqs_dn(4)';
NODE_NAME     U5D1 AB39
 '@BASEBOARD_FAB2_LIB.BASEBOARD_FAB2(SCH_1):PAGE25_I172@CHPSET_LIB.SKX_EXT_B(CHIPS)':
 'DDR2_DQS_DN'<4>: CDS_PINID='DDR2_DQS_DN(4)';
NODE_NAME     J4G3 244
 '@BASEBOARD_FAB2_LIB.BASEBOARD_FAB2(SCH_1):PAGE47_I61@MSTR_SCONN.SCONN288_H44441004(CHIPS)':
 'DQS4N': CDS_PINID='DQS4N';
NODE_NAME     J6U2 244
 '@BASEBOARD_FAB2_LIB.BASEBOARD_FAB2(SCH_1):PAGE48_I61@MSTR_SCONN.SCONN288_H44441003(CHIPS)':
 'DQS4N': CDS_PINID='DQS4N';
NET_NAME
'M_C_DQS_DN<5>'
 '@BASEBOARD_FAB2_LIB.BASEBOARD_FAB2(SCH_1):M_C_DQS_DN'<5>:
 C_SIGNAL='@baseboard_fab2_lib.baseboard_fab2(sch_1):m_c_dqs_dn(5)';
NODE_NAME     U5D1 AB33
 '@BASEBOARD_FAB2_LIB.BASEBOARD_FAB2(SCH_1):PAGE25_I172@CHPSET_LIB.SKX_EXT_B(CHIPS)':
 'DDR2_DQS_DN'<5>: CDS_PINID='DDR2_DQS_DN(5)';
NODE_NAME     J4G3 255
 '@BASEBOARD_FAB2_LIB.BASEBOARD_FAB2(SCH_1):PAGE47_I61@MSTR_SCONN.SCONN288_H44441004(CHIPS)':
 'DQS5N': CDS_PINID='DQS5N';
NODE_NAME     J6U2 255
 '@BASEBOARD_FAB2_LIB.BASEBOARD_FAB2(SCH_1):PAGE48_I61@MSTR_SCONN.SCONN288_H44441003(CHIPS)':
 'DQS5N': CDS_PINID='DQS5N';
NET_NAME
'M_C_DQS_DN<6>'
 '@BASEBOARD_FAB2_LIB.BASEBOARD_FAB2(SCH_1):M_C_DQS_DN'<6>:
 C_SIGNAL='@baseboard_fab2_lib.baseboard_fab2(sch_1):m_c_dqs_dn(6)';
NODE_NAME     U5D1 AJ30
 '@BASEBOARD_FAB2_LIB.BASEBOARD_FAB2(SCH_1):PAGE25_I172@CHPSET_LIB.SKX_EXT_B(CHIPS)':
 'DDR2_DQS_DN'<6>: CDS_PINID='DDR2_DQS_DN(6)';
NODE_NAME     J4G3 266
 '@BASEBOARD_FAB2_LIB.BASEBOARD_FAB2(SCH_1):PAGE47_I61@MSTR_SCONN.SCONN288_H44441004(CHIPS)':
 'DQS6N': CDS_PINID='DQS6N';
NODE_NAME     J6U2 266
 '@BASEBOARD_FAB2_LIB.BASEBOARD_FAB2(SCH_1):PAGE48_I61@MSTR_SCONN.SCONN288_H44441003(CHIPS)':
 'DQS6N': CDS_PINID='DQS6N';
NET_NAME
'M_C_DQS_DN<7>'
 '@BASEBOARD_FAB2_LIB.BASEBOARD_FAB2(SCH_1):M_C_DQS_DN'<7>:
 C_SIGNAL='@baseboard_fab2_lib.baseboard_fab2(sch_1):m_c_dqs_dn(7)';
NODE_NAME     U5D1 AJ24
 '@BASEBOARD_FAB2_LIB.BASEBOARD_FAB2(SCH_1):PAGE25_I172@CHPSET_LIB.SKX_EXT_B(CHIPS)':
 'DDR2_DQS_DN'<7>: CDS_PINID='DDR2_DQS_DN(7)';
NODE_NAME     J4G3 277
 '@BASEBOARD_FAB2_LIB.BASEBOARD_FAB2(SCH_1):PAGE47_I61@MSTR_SCONN.SCONN288_H44441004(CHIPS)':
 'DQS7N': CDS_PINID='DQS7N';
NODE_NAME     J6U2 277
 '@BASEBOARD_FAB2_LIB.BASEBOARD_FAB2(SCH_1):PAGE48_I61@MSTR_SCONN.SCONN288_H44441003(CHIPS)':
 'DQS7N': CDS_PINID='DQS7N';
NET_NAME
'M_C_DQS_DN<8>'
 '@BASEBOARD_FAB2_LIB.BASEBOARD_FAB2(SCH_1):M_C_DQS_DN'<8>:
 C_SIGNAL='@baseboard_fab2_lib.baseboard_fab2(sch_1):m_c_dqs_dn(8)';
NODE_NAME     U5D1 BB71
 '@BASEBOARD_FAB2_LIB.BASEBOARD_FAB2(SCH_1):PAGE25_I172@CHPSET_LIB.SKX_EXT_B(CHIPS)':
 'DDR2_DQS_DN'<8>: CDS_PINID='DDR2_DQS_DN(8)';
NODE_NAME     J4G3 196
 '@BASEBOARD_FAB2_LIB.BASEBOARD_FAB2(SCH_1):PAGE47_I61@MSTR_SCONN.SCONN288_H44441004(CHIPS)':
 'DQS8N': CDS_PINID='DQS8N';
NODE_NAME     J6U2 196
 '@BASEBOARD_FAB2_LIB.BASEBOARD_FAB2(SCH_1):PAGE48_I61@MSTR_SCONN.SCONN288_H44441003(CHIPS)':
 'DQS8N': CDS_PINID='DQS8N';
NET_NAME
'M_C_DQS_DN<9>'
 '@BASEBOARD_FAB2_LIB.BASEBOARD_FAB2(SCH_1):M_C_DQS_DN'<9>:
 C_SIGNAL='@baseboard_fab2_lib.baseboard_fab2(sch_1):m_c_dqs_dn(9)';
NODE_NAME     U5D1 AP77
 '@BASEBOARD_FAB2_LIB.BASEBOARD_FAB2(SCH_1):PAGE25_I172@CHPSET_LIB.SKX_EXT_B(CHIPS)':
 'DDR2_DQS_DN'<9>: CDS_PINID='DDR2_DQS_DN(9)';
NODE_NAME     J4G3 8
 '@BASEBOARD_FAB2_LIB.BASEBOARD_FAB2(SCH_1):PAGE47_I61@MSTR_SCONN.SCONN288_H44441004(CHIPS)':
 'DQS9N': CDS_PINID='DQS9N';
NODE_NAME     J6U2 8
 '@BASEBOARD_FAB2_LIB.BASEBOARD_FAB2(SCH_1):PAGE48_I61@MSTR_SCONN.SCONN288_H44441003(CHIPS)':
 'DQS9N': CDS_PINID='DQS9N';
NET_NAME
'M_C_DQS_DP<0>'
 '@BASEBOARD_FAB2_LIB.BASEBOARD_FAB2(SCH_1):M_C_DQS_DP'<0>:
 C_SIGNAL='@baseboard_fab2_lib.baseboard_fab2(sch_1):m_c_dqs_dp(0)';
NODE_NAME     U5D1 AM75
 '@BASEBOARD_FAB2_LIB.BASEBOARD_FAB2(SCH_1):PAGE25_I172@CHPSET_LIB.SKX_EXT_B(CHIPS)':
 'DDR2_DQS_DP'<0>: CDS_PINID='DDR2_DQS_DP(0)';
NODE_NAME     J4G3 153
 '@BASEBOARD_FAB2_LIB.BASEBOARD_FAB2(SCH_1):PAGE47_I61@MSTR_SCONN.SCONN288_H44441004(CHIPS)':
 'DQS0P': CDS_PINID='DQS0P';
NODE_NAME     J6U2 153
 '@BASEBOARD_FAB2_LIB.BASEBOARD_FAB2(SCH_1):PAGE48_I61@MSTR_SCONN.SCONN288_H44441003(CHIPS)':
 'DQS0P': CDS_PINID='DQS0P';
NET_NAME
'M_C_DQS_DP<10>'
 '@BASEBOARD_FAB2_LIB.BASEBOARD_FAB2(SCH_1):M_C_DQS_DP'<10>:
 C_SIGNAL='@baseboard_fab2_lib.baseboard_fab2(sch_1):m_c_dqs_dp(10)';
NODE_NAME     U5D1 AC76
 '@BASEBOARD_FAB2_LIB.BASEBOARD_FAB2(SCH_1):PAGE25_I172@CHPSET_LIB.SKX_EXT_B(CHIPS)':
 'DDR2_DQS_DP'<10>: CDS_PINID='DDR2_DQS_DP(10)';
NODE_NAME     J4G3 18
 '@BASEBOARD_FAB2_LIB.BASEBOARD_FAB2(SCH_1):PAGE47_I61@MSTR_SCONN.SCONN288_H44441004(CHIPS)':
 'DQS10P': CDS_PINID='DQS10P';
NODE_NAME     J6U2 18
 '@BASEBOARD_FAB2_LIB.BASEBOARD_FAB2(SCH_1):PAGE48_I61@MSTR_SCONN.SCONN288_H44441003(CHIPS)':
 'DQS10P': CDS_PINID='DQS10P';
NET_NAME
'M_C_DQS_DP<11>'
 '@BASEBOARD_FAB2_LIB.BASEBOARD_FAB2(SCH_1):M_C_DQS_DP'<11>:
 C_SIGNAL='@baseboard_fab2_lib.baseboard_fab2(sch_1):m_c_dqs_dp(11)';
NODE_NAME     U5D1 V71
 '@BASEBOARD_FAB2_LIB.BASEBOARD_FAB2(SCH_1):PAGE25_I172@CHPSET_LIB.SKX_EXT_B(CHIPS)':
 'DDR2_DQS_DP'<11>: CDS_PINID='DDR2_DQS_DP(11)';
NODE_NAME     J4G3 29
 '@BASEBOARD_FAB2_LIB.BASEBOARD_FAB2(SCH_1):PAGE47_I61@MSTR_SCONN.SCONN288_H44441004(CHIPS)':
 'DQS11P': CDS_PINID='DQS11P';
NODE_NAME     J6U2 29
 '@BASEBOARD_FAB2_LIB.BASEBOARD_FAB2(SCH_1):PAGE48_I61@MSTR_SCONN.SCONN288_H44441003(CHIPS)':
 'DQS11P': CDS_PINID='DQS11P';
NET_NAME
'M_C_DQS_DP<12>'
 '@BASEBOARD_FAB2_LIB.BASEBOARD_FAB2(SCH_1):M_C_DQS_DP'<12>:
 C_SIGNAL='@baseboard_fab2_lib.baseboard_fab2(sch_1):m_c_dqs_dp(12)';
NODE_NAME     U5D1 AN66
 '@BASEBOARD_FAB2_LIB.BASEBOARD_FAB2(SCH_1):PAGE25_I172@CHPSET_LIB.SKX_EXT_B(CHIPS)':
 'DDR2_DQS_DP'<12>: CDS_PINID='DDR2_DQS_DP(12)';
NODE_NAME     J4G3 40
 '@BASEBOARD_FAB2_LIB.BASEBOARD_FAB2(SCH_1):PAGE47_I61@MSTR_SCONN.SCONN288_H44441004(CHIPS)':
 'DQS12P': CDS_PINID='DQS12P';
NODE_NAME     J6U2 40
 '@BASEBOARD_FAB2_LIB.BASEBOARD_FAB2(SCH_1):PAGE48_I61@MSTR_SCONN.SCONN288_H44441003(CHIPS)':
 'DQS12P': CDS_PINID='DQS12P';
NET_NAME
'M_C_DQS_DP<13>'
 '@BASEBOARD_FAB2_LIB.BASEBOARD_FAB2(SCH_1):M_C_DQS_DP'<13>:
 C_SIGNAL='@baseboard_fab2_lib.baseboard_fab2(sch_1):m_c_dqs_dp(13)';
NODE_NAME     U5D1 V39
 '@BASEBOARD_FAB2_LIB.BASEBOARD_FAB2(SCH_1):PAGE25_I172@CHPSET_LIB.SKX_EXT_B(CHIPS)':
 'DDR2_DQS_DP'<13>: CDS_PINID='DDR2_DQS_DP(13)';
NODE_NAME     J4G3 99
 '@BASEBOARD_FAB2_LIB.BASEBOARD_FAB2(SCH_1):PAGE47_I61@MSTR_SCONN.SCONN288_H44441004(CHIPS)':
 'DQS13P': CDS_PINID='DQS13P';
NODE_NAME     J6U2 99
 '@BASEBOARD_FAB2_LIB.BASEBOARD_FAB2(SCH_1):PAGE48_I61@MSTR_SCONN.SCONN288_H44441003(CHIPS)':
 'DQS13P': CDS_PINID='DQS13P';
NET_NAME
'M_C_DQS_DP<14>'
 '@BASEBOARD_FAB2_LIB.BASEBOARD_FAB2(SCH_1):M_C_DQS_DP'<14>:
 C_SIGNAL='@baseboard_fab2_lib.baseboard_fab2(sch_1):m_c_dqs_dp(14)';
NODE_NAME     U5D1 V33
 '@BASEBOARD_FAB2_LIB.BASEBOARD_FAB2(SCH_1):PAGE25_I172@CHPSET_LIB.SKX_EXT_B(CHIPS)':
 'DDR2_DQS_DP'<14>: CDS_PINID='DDR2_DQS_DP(14)';
NODE_NAME     J4G3 110
 '@BASEBOARD_FAB2_LIB.BASEBOARD_FAB2(SCH_1):PAGE47_I61@MSTR_SCONN.SCONN288_H44441004(CHIPS)':
 'DQS14P': CDS_PINID='DQS14P';
NODE_NAME     J6U2 110
 '@BASEBOARD_FAB2_LIB.BASEBOARD_FAB2(SCH_1):PAGE48_I61@MSTR_SCONN.SCONN288_H44441003(CHIPS)':
 'DQS14P': CDS_PINID='DQS14P';
NET_NAME
'M_C_DQS_DP<15>'
 '@BASEBOARD_FAB2_LIB.BASEBOARD_FAB2(SCH_1):M_C_DQS_DP'<15>:
 C_SIGNAL='@baseboard_fab2_lib.baseboard_fab2(sch_1):m_c_dqs_dp(15)';
NODE_NAME     U5D1 AE30
 '@BASEBOARD_FAB2_LIB.BASEBOARD_FAB2(SCH_1):PAGE25_I172@CHPSET_LIB.SKX_EXT_B(CHIPS)':
 'DDR2_DQS_DP'<15>: CDS_PINID='DDR2_DQS_DP(15)';
NODE_NAME     J4G3 121
 '@BASEBOARD_FAB2_LIB.BASEBOARD_FAB2(SCH_1):PAGE47_I61@MSTR_SCONN.SCONN288_H44441004(CHIPS)':
 'DQS15P': CDS_PINID='DQS15P';
NODE_NAME     J6U2 121
 '@BASEBOARD_FAB2_LIB.BASEBOARD_FAB2(SCH_1):PAGE48_I61@MSTR_SCONN.SCONN288_H44441003(CHIPS)':
 'DQS15P': CDS_PINID='DQS15P';
NET_NAME
'M_C_DQS_DP<16>'
 '@BASEBOARD_FAB2_LIB.BASEBOARD_FAB2(SCH_1):M_C_DQS_DP'<16>:
 C_SIGNAL='@baseboard_fab2_lib.baseboard_fab2(sch_1):m_c_dqs_dp(16)';
NODE_NAME     U5D1 AE24
 '@BASEBOARD_FAB2_LIB.BASEBOARD_FAB2(SCH_1):PAGE25_I172@CHPSET_LIB.SKX_EXT_B(CHIPS)':
 'DDR2_DQS_DP'<16>: CDS_PINID='DDR2_DQS_DP(16)';
NODE_NAME     J4G3 132
 '@BASEBOARD_FAB2_LIB.BASEBOARD_FAB2(SCH_1):PAGE47_I61@MSTR_SCONN.SCONN288_H44441004(CHIPS)':
 'DQS16P': CDS_PINID='DQS16P';
NODE_NAME     J6U2 132
 '@BASEBOARD_FAB2_LIB.BASEBOARD_FAB2(SCH_1):PAGE48_I61@MSTR_SCONN.SCONN288_H44441003(CHIPS)':
 'DQS16P': CDS_PINID='DQS16P';
NET_NAME
'M_C_DQS_DP<17>'
 '@BASEBOARD_FAB2_LIB.BASEBOARD_FAB2(SCH_1):M_C_DQS_DP'<17>:
 C_SIGNAL='@baseboard_fab2_lib.baseboard_fab2(sch_1):m_c_dqs_dp(17)';
NODE_NAME     U5D1 AV71
 '@BASEBOARD_FAB2_LIB.BASEBOARD_FAB2(SCH_1):PAGE25_I172@CHPSET_LIB.SKX_EXT_B(CHIPS)':
 'DDR2_DQS_DP'<17>: CDS_PINID='DDR2_DQS_DP(17)';
NODE_NAME     J4G3 51
 '@BASEBOARD_FAB2_LIB.BASEBOARD_FAB2(SCH_1):PAGE47_I61@MSTR_SCONN.SCONN288_H44441004(CHIPS)':
 'DQS17P': CDS_PINID='DQS17P';
NODE_NAME     J6U2 51
 '@BASEBOARD_FAB2_LIB.BASEBOARD_FAB2(SCH_1):PAGE48_I61@MSTR_SCONN.SCONN288_H44441003(CHIPS)':
 'DQS17P': CDS_PINID='DQS17P';
NET_NAME
'M_C_DQS_DP<1>'
 '@BASEBOARD_FAB2_LIB.BASEBOARD_FAB2(SCH_1):M_C_DQS_DP'<1>:
 C_SIGNAL='@baseboard_fab2_lib.baseboard_fab2(sch_1):m_c_dqs_dp(1)';
NODE_NAME     U5D1 AB75
 '@BASEBOARD_FAB2_LIB.BASEBOARD_FAB2(SCH_1):PAGE25_I172@CHPSET_LIB.SKX_EXT_B(CHIPS)':
 'DDR2_DQS_DP'<1>: CDS_PINID='DDR2_DQS_DP(1)';
NODE_NAME     J4G3 164
 '@BASEBOARD_FAB2_LIB.BASEBOARD_FAB2(SCH_1):PAGE47_I61@MSTR_SCONN.SCONN288_H44441004(CHIPS)':
 'DQS1P': CDS_PINID='DQS1P';
NODE_NAME     J6U2 164
 '@BASEBOARD_FAB2_LIB.BASEBOARD_FAB2(SCH_1):PAGE48_I61@MSTR_SCONN.SCONN288_H44441003(CHIPS)':
 'DQS1P': CDS_PINID='DQS1P';
NET_NAME
'M_C_DQS_DP<2>'
 '@BASEBOARD_FAB2_LIB.BASEBOARD_FAB2(SCH_1):M_C_DQS_DP'<2>:
 C_SIGNAL='@baseboard_fab2_lib.baseboard_fab2(sch_1):m_c_dqs_dp(2)';
NODE_NAME     U5D1 W70
 '@BASEBOARD_FAB2_LIB.BASEBOARD_FAB2(SCH_1):PAGE25_I172@CHPSET_LIB.SKX_EXT_B(CHIPS)':
 'DDR2_DQS_DP'<2>: CDS_PINID='DDR2_DQS_DP(2)';
NODE_NAME     J4G3 175
 '@BASEBOARD_FAB2_LIB.BASEBOARD_FAB2(SCH_1):PAGE47_I61@MSTR_SCONN.SCONN288_H44441004(CHIPS)':
 'DQS2P': CDS_PINID='DQS2P';
NODE_NAME     J6U2 175
 '@BASEBOARD_FAB2_LIB.BASEBOARD_FAB2(SCH_1):PAGE48_I61@MSTR_SCONN.SCONN288_H44441003(CHIPS)':
 'DQS2P': CDS_PINID='DQS2P';
NET_NAME
'M_C_DQS_DP<3>'
 '@BASEBOARD_FAB2_LIB.BASEBOARD_FAB2(SCH_1):M_C_DQS_DP'<3>:
 C_SIGNAL='@baseboard_fab2_lib.baseboard_fab2(sch_1):m_c_dqs_dp(3)';
NODE_NAME     U5D1 AR66
 '@BASEBOARD_FAB2_LIB.BASEBOARD_FAB2(SCH_1):PAGE25_I172@CHPSET_LIB.SKX_EXT_B(CHIPS)':
 'DDR2_DQS_DP'<3>: CDS_PINID='DDR2_DQS_DP(3)';
NODE_NAME     J4G3 186
 '@BASEBOARD_FAB2_LIB.BASEBOARD_FAB2(SCH_1):PAGE47_I61@MSTR_SCONN.SCONN288_H44441004(CHIPS)':
 'DQS3P': CDS_PINID='DQS3P';
NODE_NAME     J6U2 186
 '@BASEBOARD_FAB2_LIB.BASEBOARD_FAB2(SCH_1):PAGE48_I61@MSTR_SCONN.SCONN288_H44441003(CHIPS)':
 'DQS3P': CDS_PINID='DQS3P';
NET_NAME
'M_C_DQS_DP<4>'
 '@BASEBOARD_FAB2_LIB.BASEBOARD_FAB2(SCH_1):M_C_DQS_DP'<4>:
 C_SIGNAL='@baseboard_fab2_lib.baseboard_fab2(sch_1):m_c_dqs_dp(4)';
NODE_NAME     U5D1 Y39
 '@BASEBOARD_FAB2_LIB.BASEBOARD_FAB2(SCH_1):PAGE25_I172@CHPSET_LIB.SKX_EXT_B(CHIPS)':
 'DDR2_DQS_DP'<4>: CDS_PINID='DDR2_DQS_DP(4)';
NODE_NAME     J4G3 245
 '@BASEBOARD_FAB2_LIB.BASEBOARD_FAB2(SCH_1):PAGE47_I61@MSTR_SCONN.SCONN288_H44441004(CHIPS)':
 'DQS4P': CDS_PINID='DQS4P';
NODE_NAME     J6U2 245
 '@BASEBOARD_FAB2_LIB.BASEBOARD_FAB2(SCH_1):PAGE48_I61@MSTR_SCONN.SCONN288_H44441003(CHIPS)':
 'DQS4P': CDS_PINID='DQS4P';
NET_NAME
'M_C_DQS_DP<5>'
 '@BASEBOARD_FAB2_LIB.BASEBOARD_FAB2(SCH_1):M_C_DQS_DP'<5>:
 C_SIGNAL='@baseboard_fab2_lib.baseboard_fab2(sch_1):m_c_dqs_dp(5)';
NODE_NAME     U5D1 Y33
 '@BASEBOARD_FAB2_LIB.BASEBOARD_FAB2(SCH_1):PAGE25_I172@CHPSET_LIB.SKX_EXT_B(CHIPS)':
 'DDR2_DQS_DP'<5>: CDS_PINID='DDR2_DQS_DP(5)';
NODE_NAME     J4G3 256
 '@BASEBOARD_FAB2_LIB.BASEBOARD_FAB2(SCH_1):PAGE47_I61@MSTR_SCONN.SCONN288_H44441004(CHIPS)':
 'DQS5P': CDS_PINID='DQS5P';
NODE_NAME     J6U2 256
 '@BASEBOARD_FAB2_LIB.BASEBOARD_FAB2(SCH_1):PAGE48_I61@MSTR_SCONN.SCONN288_H44441003(CHIPS)':
 'DQS5P': CDS_PINID='DQS5P';
NET_NAME
'M_C_DQS_DP<6>'
 '@BASEBOARD_FAB2_LIB.BASEBOARD_FAB2(SCH_1):M_C_DQS_DP'<6>:
 C_SIGNAL='@baseboard_fab2_lib.baseboard_fab2(sch_1):m_c_dqs_dp(6)';
NODE_NAME     U5D1 AG30
 '@BASEBOARD_FAB2_LIB.BASEBOARD_FAB2(SCH_1):PAGE25_I172@CHPSET_LIB.SKX_EXT_B(CHIPS)':
 'DDR2_DQS_DP'<6>: CDS_PINID='DDR2_DQS_DP(6)';
NODE_NAME     J4G3 267
 '@BASEBOARD_FAB2_LIB.BASEBOARD_FAB2(SCH_1):PAGE47_I61@MSTR_SCONN.SCONN288_H44441004(CHIPS)':
 'DQS6P': CDS_PINID='DQS6P';
NODE_NAME     J6U2 267
 '@BASEBOARD_FAB2_LIB.BASEBOARD_FAB2(SCH_1):PAGE48_I61@MSTR_SCONN.SCONN288_H44441003(CHIPS)':
 'DQS6P': CDS_PINID='DQS6P';
NET_NAME
'M_C_DQS_DP<7>'
 '@BASEBOARD_FAB2_LIB.BASEBOARD_FAB2(SCH_1):M_C_DQS_DP'<7>:
 C_SIGNAL='@baseboard_fab2_lib.baseboard_fab2(sch_1):m_c_dqs_dp(7)';
NODE_NAME     U5D1 AG24
 '@BASEBOARD_FAB2_LIB.BASEBOARD_FAB2(SCH_1):PAGE25_I172@CHPSET_LIB.SKX_EXT_B(CHIPS)':
 'DDR2_DQS_DP'<7>: CDS_PINID='DDR2_DQS_DP(7)';
NODE_NAME     J4G3 278
 '@BASEBOARD_FAB2_LIB.BASEBOARD_FAB2(SCH_1):PAGE47_I61@MSTR_SCONN.SCONN288_H44441004(CHIPS)':
 'DQS7P': CDS_PINID='DQS7P';
NODE_NAME     J6U2 278
 '@BASEBOARD_FAB2_LIB.BASEBOARD_FAB2(SCH_1):PAGE48_I61@MSTR_SCONN.SCONN288_H44441003(CHIPS)':
 'DQS7P': CDS_PINID='DQS7P';
NET_NAME
'M_C_DQS_DP<8>'
 '@BASEBOARD_FAB2_LIB.BASEBOARD_FAB2(SCH_1):M_C_DQS_DP'<8>:
 C_SIGNAL='@baseboard_fab2_lib.baseboard_fab2(sch_1):m_c_dqs_dp(8)';
NODE_NAME     U5D1 AY71
 '@BASEBOARD_FAB2_LIB.BASEBOARD_FAB2(SCH_1):PAGE25_I172@CHPSET_LIB.SKX_EXT_B(CHIPS)':
 'DDR2_DQS_DP'<8>: CDS_PINID='DDR2_DQS_DP(8)';
NODE_NAME     J4G3 197
 '@BASEBOARD_FAB2_LIB.BASEBOARD_FAB2(SCH_1):PAGE47_I61@MSTR_SCONN.SCONN288_H44441004(CHIPS)':
 'DQS8P': CDS_PINID='DQS8P';
NODE_NAME     J6U2 197
 '@BASEBOARD_FAB2_LIB.BASEBOARD_FAB2(SCH_1):PAGE48_I61@MSTR_SCONN.SCONN288_H44441003(CHIPS)':
 'DQS8P': CDS_PINID='DQS8P';
NET_NAME
'M_C_DQS_DP<9>'
 '@BASEBOARD_FAB2_LIB.BASEBOARD_FAB2(SCH_1):M_C_DQS_DP'<9>:
 C_SIGNAL='@baseboard_fab2_lib.baseboard_fab2(sch_1):m_c_dqs_dp(9)';
NODE_NAME     U5D1 AN76
 '@BASEBOARD_FAB2_LIB.BASEBOARD_FAB2(SCH_1):PAGE25_I172@CHPSET_LIB.SKX_EXT_B(CHIPS)':
 'DDR2_DQS_DP'<9>: CDS_PINID='DDR2_DQS_DP(9)';
NODE_NAME     J4G3 7
 '@BASEBOARD_FAB2_LIB.BASEBOARD_FAB2(SCH_1):PAGE47_I61@MSTR_SCONN.SCONN288_H44441004(CHIPS)':
 'DQS9P': CDS_PINID='DQS9P';
NODE_NAME     J6U2 7
 '@BASEBOARD_FAB2_LIB.BASEBOARD_FAB2(SCH_1):PAGE48_I61@MSTR_SCONN.SCONN288_H44441003(CHIPS)':
 'DQS9P': CDS_PINID='DQS9P';
NET_NAME
'M_C_ECC<0>'
 '@BASEBOARD_FAB2_LIB.BASEBOARD_FAB2(SCH_1):M_C_ECC'<0>:
 C_SIGNAL='@baseboard_fab2_lib.baseboard_fab2(sch_1):m_c_ecc(0)';
NODE_NAME     U5D1 AU72
 '@BASEBOARD_FAB2_LIB.BASEBOARD_FAB2(SCH_1):PAGE25_I172@CHPSET_LIB.SKX_EXT_B(CHIPS)':
 'DDR2_ECC'<0>: CDS_PINID='DDR2_ECC(0)';
NODE_NAME     J4G3 194
 '@BASEBOARD_FAB2_LIB.BASEBOARD_FAB2(SCH_1):PAGE47_I111@MSTR_SCONN.SCONN288_H44441004(CHIPS)':
 'CB'<1>: CDS_PINID='CB(1)';
NODE_NAME     J6U2 49
 '@BASEBOARD_FAB2_LIB.BASEBOARD_FAB2(SCH_1):PAGE48_I111@MSTR_SCONN.SCONN288_H44441003(CHIPS)':
 'CB'<0>: CDS_PINID='CB(0)';
NET_NAME
'M_C_ECC<1>'
 '@BASEBOARD_FAB2_LIB.BASEBOARD_FAB2(SCH_1):M_C_ECC'<1>:
 C_SIGNAL='@baseboard_fab2_lib.baseboard_fab2(sch_1):m_c_ecc(1)';
NODE_NAME     U5D1 BA72
 '@BASEBOARD_FAB2_LIB.BASEBOARD_FAB2(SCH_1):PAGE25_I172@CHPSET_LIB.SKX_EXT_B(CHIPS)':
 'DDR2_ECC'<1>: CDS_PINID='DDR2_ECC(1)';
NODE_NAME     J4G3 49
 '@BASEBOARD_FAB2_LIB.BASEBOARD_FAB2(SCH_1):PAGE47_I111@MSTR_SCONN.SCONN288_H44441004(CHIPS)':
 'CB'<0>: CDS_PINID='CB(0)';
NODE_NAME     J6U2 194
 '@BASEBOARD_FAB2_LIB.BASEBOARD_FAB2(SCH_1):PAGE48_I111@MSTR_SCONN.SCONN288_H44441003(CHIPS)':
 'CB'<1>: CDS_PINID='CB(1)';
NET_NAME
'M_C_ECC<2>'
 '@BASEBOARD_FAB2_LIB.BASEBOARD_FAB2(SCH_1):M_C_ECC'<2>:
 C_SIGNAL='@baseboard_fab2_lib.baseboard_fab2(sch_1):m_c_ecc(2)';
NODE_NAME     U5D1 AV69
 '@BASEBOARD_FAB2_LIB.BASEBOARD_FAB2(SCH_1):PAGE25_I172@CHPSET_LIB.SKX_EXT_B(CHIPS)':
 'DDR2_ECC'<2>: CDS_PINID='DDR2_ECC(2)';
NODE_NAME     J4G3 201
 '@BASEBOARD_FAB2_LIB.BASEBOARD_FAB2(SCH_1):PAGE47_I111@MSTR_SCONN.SCONN288_H44441004(CHIPS)':
 'CB'<3>: CDS_PINID='CB(3)';
NODE_NAME     J6U2 56
 '@BASEBOARD_FAB2_LIB.BASEBOARD_FAB2(SCH_1):PAGE48_I111@MSTR_SCONN.SCONN288_H44441003(CHIPS)':
 'CB'<2>: CDS_PINID='CB(2)';
NET_NAME
'M_C_ECC<3>'
 '@BASEBOARD_FAB2_LIB.BASEBOARD_FAB2(SCH_1):M_C_ECC'<3>:
 C_SIGNAL='@baseboard_fab2_lib.baseboard_fab2(sch_1):m_c_ecc(3)';
NODE_NAME     U5D1 AY69
 '@BASEBOARD_FAB2_LIB.BASEBOARD_FAB2(SCH_1):PAGE25_I172@CHPSET_LIB.SKX_EXT_B(CHIPS)':
 'DDR2_ECC'<3>: CDS_PINID='DDR2_ECC(3)';
NODE_NAME     J4G3 56
 '@BASEBOARD_FAB2_LIB.BASEBOARD_FAB2(SCH_1):PAGE47_I111@MSTR_SCONN.SCONN288_H44441004(CHIPS)':
 'CB'<2>: CDS_PINID='CB(2)';
NODE_NAME     J6U2 201
 '@BASEBOARD_FAB2_LIB.BASEBOARD_FAB2(SCH_1):PAGE48_I111@MSTR_SCONN.SCONN288_H44441003(CHIPS)':
 'CB'<3>: CDS_PINID='CB(3)';
NET_NAME
'M_C_ECC<4>'
 '@BASEBOARD_FAB2_LIB.BASEBOARD_FAB2(SCH_1):M_C_ECC'<4>:
 C_SIGNAL='@baseboard_fab2_lib.baseboard_fab2(sch_1):m_c_ecc(4)';
NODE_NAME     U5D1 AV73
 '@BASEBOARD_FAB2_LIB.BASEBOARD_FAB2(SCH_1):PAGE25_I172@CHPSET_LIB.SKX_EXT_B(CHIPS)':
 'DDR2_ECC'<4>: CDS_PINID='DDR2_ECC(4)';
NODE_NAME     J4G3 192
 '@BASEBOARD_FAB2_LIB.BASEBOARD_FAB2(SCH_1):PAGE47_I111@MSTR_SCONN.SCONN288_H44441004(CHIPS)':
 'CB'<5>: CDS_PINID='CB(5)';
NODE_NAME     J6U2 47
 '@BASEBOARD_FAB2_LIB.BASEBOARD_FAB2(SCH_1):PAGE48_I111@MSTR_SCONN.SCONN288_H44441003(CHIPS)':
 'CB'<4>: CDS_PINID='CB(4)';
NET_NAME
'M_C_ECC<5>'
 '@BASEBOARD_FAB2_LIB.BASEBOARD_FAB2(SCH_1):M_C_ECC'<5>:
 C_SIGNAL='@baseboard_fab2_lib.baseboard_fab2(sch_1):m_c_ecc(5)';
NODE_NAME     U5D1 AY73
 '@BASEBOARD_FAB2_LIB.BASEBOARD_FAB2(SCH_1):PAGE25_I172@CHPSET_LIB.SKX_EXT_B(CHIPS)':
 'DDR2_ECC'<5>: CDS_PINID='DDR2_ECC(5)';
NODE_NAME     J4G3 47
 '@BASEBOARD_FAB2_LIB.BASEBOARD_FAB2(SCH_1):PAGE47_I111@MSTR_SCONN.SCONN288_H44441004(CHIPS)':
 'CB'<4>: CDS_PINID='CB(4)';
NODE_NAME     J6U2 192
 '@BASEBOARD_FAB2_LIB.BASEBOARD_FAB2(SCH_1):PAGE48_I111@MSTR_SCONN.SCONN288_H44441003(CHIPS)':
 'CB'<5>: CDS_PINID='CB(5)';
NET_NAME
'M_C_ECC<6>'
 '@BASEBOARD_FAB2_LIB.BASEBOARD_FAB2(SCH_1):M_C_ECC'<6>:
 C_SIGNAL='@baseboard_fab2_lib.baseboard_fab2(sch_1):m_c_ecc(6)';
NODE_NAME     U5D1 AU70
 '@BASEBOARD_FAB2_LIB.BASEBOARD_FAB2(SCH_1):PAGE25_I172@CHPSET_LIB.SKX_EXT_B(CHIPS)':
 'DDR2_ECC'<6>: CDS_PINID='DDR2_ECC(6)';
NODE_NAME     J4G3 199
 '@BASEBOARD_FAB2_LIB.BASEBOARD_FAB2(SCH_1):PAGE47_I111@MSTR_SCONN.SCONN288_H44441004(CHIPS)':
 'CB'<7>: CDS_PINID='CB(7)';
NODE_NAME     J6U2 54
 '@BASEBOARD_FAB2_LIB.BASEBOARD_FAB2(SCH_1):PAGE48_I111@MSTR_SCONN.SCONN288_H44441003(CHIPS)':
 'CB'<6>: CDS_PINID='CB(6)';
NET_NAME
'M_C_ECC<7>'
 '@BASEBOARD_FAB2_LIB.BASEBOARD_FAB2(SCH_1):M_C_ECC'<7>:
 C_SIGNAL='@baseboard_fab2_lib.baseboard_fab2(sch_1):m_c_ecc(7)';
NODE_NAME     U5D1 BA70
 '@BASEBOARD_FAB2_LIB.BASEBOARD_FAB2(SCH_1):PAGE25_I172@CHPSET_LIB.SKX_EXT_B(CHIPS)':
 'DDR2_ECC'<7>: CDS_PINID='DDR2_ECC(7)';
NODE_NAME     J4G3 54
 '@BASEBOARD_FAB2_LIB.BASEBOARD_FAB2(SCH_1):PAGE47_I111@MSTR_SCONN.SCONN288_H44441004(CHIPS)':
 'CB'<6>: CDS_PINID='CB(6)';
NODE_NAME     J6U2 199
 '@BASEBOARD_FAB2_LIB.BASEBOARD_FAB2(SCH_1):PAGE48_I111@MSTR_SCONN.SCONN288_H44441003(CHIPS)':
 'CB'<7>: CDS_PINID='CB(7)';
NET_NAME
'M_C_MA<0>'
 '@BASEBOARD_FAB2_LIB.BASEBOARD_FAB2(SCH_1):M_C_MA'<0>:
 C_SIGNAL='@baseboard_fab2_lib.baseboard_fab2(sch_1):m_c_ma(0)';
NODE_NAME     U5D1 AB53
 '@BASEBOARD_FAB2_LIB.BASEBOARD_FAB2(SCH_1):PAGE25_I172@CHPSET_LIB.SKX_EXT_B(CHIPS)':
 'DDR2_MA'<0>: CDS_PINID='DDR2_MA(0)';
NODE_NAME     J4G3 79
 '@BASEBOARD_FAB2_LIB.BASEBOARD_FAB2(SCH_1):PAGE47_I111@MSTR_SCONN.SCONN288_H44441004(CHIPS)':
 'A0': CDS_PINID='A0';
NODE_NAME     J6U2 79
 '@BASEBOARD_FAB2_LIB.BASEBOARD_FAB2(SCH_1):PAGE48_I111@MSTR_SCONN.SCONN288_H44441003(CHIPS)':
 'A0': CDS_PINID='A0';
NET_NAME
'M_C_MA<10>'
 '@BASEBOARD_FAB2_LIB.BASEBOARD_FAB2(SCH_1):M_C_MA'<10>:
 C_SIGNAL='@baseboard_fab2_lib.baseboard_fab2(sch_1):m_c_ma(10)';
NODE_NAME     U5D1 AD55
 '@BASEBOARD_FAB2_LIB.BASEBOARD_FAB2(SCH_1):PAGE25_I172@CHPSET_LIB.SKX_EXT_B(CHIPS)':
 'DDR2_MA'<10>: CDS_PINID='DDR2_MA(10)';
NODE_NAME     J4G3 225
 '@BASEBOARD_FAB2_LIB.BASEBOARD_FAB2(SCH_1):PAGE47_I111@MSTR_SCONN.SCONN288_H44441004(CHIPS)':
 'A10': CDS_PINID='A10';
NODE_NAME     J6U2 225
 '@BASEBOARD_FAB2_LIB.BASEBOARD_FAB2(SCH_1):PAGE48_I111@MSTR_SCONN.SCONN288_H44441003(CHIPS)':
 'A10': CDS_PINID='A10';
NET_NAME
'M_C_MA<11>'
 '@BASEBOARD_FAB2_LIB.BASEBOARD_FAB2(SCH_1):M_C_MA'<11>:
 C_SIGNAL='@baseboard_fab2_lib.baseboard_fab2(sch_1):m_c_ma(11)';
NODE_NAME     U5D1 AG60
 '@BASEBOARD_FAB2_LIB.BASEBOARD_FAB2(SCH_1):PAGE25_I172@CHPSET_LIB.SKX_EXT_B(CHIPS)':
 'DDR2_MA'<11>: CDS_PINID='DDR2_MA(11)';
NODE_NAME     J4G3 210
 '@BASEBOARD_FAB2_LIB.BASEBOARD_FAB2(SCH_1):PAGE47_I111@MSTR_SCONN.SCONN288_H44441004(CHIPS)':
 'A11': CDS_PINID='A11';
NODE_NAME     J6U2 210
 '@BASEBOARD_FAB2_LIB.BASEBOARD_FAB2(SCH_1):PAGE48_I111@MSTR_SCONN.SCONN288_H44441003(CHIPS)':
 'A11': CDS_PINID='A11';
NET_NAME
'M_C_MA<12>'
 '@BASEBOARD_FAB2_LIB.BASEBOARD_FAB2(SCH_1):M_C_MA'<12>:
 C_SIGNAL='@baseboard_fab2_lib.baseboard_fab2(sch_1):m_c_ma(12)';
NODE_NAME     U5D1 AG62
 '@BASEBOARD_FAB2_LIB.BASEBOARD_FAB2(SCH_1):PAGE25_I172@CHPSET_LIB.SKX_EXT_B(CHIPS)':
 'DDR2_MA'<12>: CDS_PINID='DDR2_MA(12)';
NODE_NAME     J4G3 65
 '@BASEBOARD_FAB2_LIB.BASEBOARD_FAB2(SCH_1):PAGE47_I111@MSTR_SCONN.SCONN288_H44441004(CHIPS)':
 'A12': CDS_PINID='A12';
NODE_NAME     J6U2 65
 '@BASEBOARD_FAB2_LIB.BASEBOARD_FAB2(SCH_1):PAGE48_I111@MSTR_SCONN.SCONN288_H44441003(CHIPS)':
 'A12': CDS_PINID='A12';
NET_NAME
'M_C_MA<13>'
 '@BASEBOARD_FAB2_LIB.BASEBOARD_FAB2(SCH_1):M_C_MA'<13>:
 C_SIGNAL='@baseboard_fab2_lib.baseboard_fab2(sch_1):m_c_ma(13)';
NODE_NAME     U5D1 AD53
 '@BASEBOARD_FAB2_LIB.BASEBOARD_FAB2(SCH_1):PAGE25_I172@CHPSET_LIB.SKX_EXT_B(CHIPS)':
 'DDR2_MA'<13>: CDS_PINID='DDR2_MA(13)';
NODE_NAME     J4G3 232
 '@BASEBOARD_FAB2_LIB.BASEBOARD_FAB2(SCH_1):PAGE47_I111@MSTR_SCONN.SCONN288_H44441004(CHIPS)':
 'A13': CDS_PINID='A13';
NODE_NAME     J6U2 232
 '@BASEBOARD_FAB2_LIB.BASEBOARD_FAB2(SCH_1):PAGE48_I111@MSTR_SCONN.SCONN288_H44441003(CHIPS)':
 'A13': CDS_PINID='A13';
NET_NAME
'M_C_MA<14>'
 '@BASEBOARD_FAB2_LIB.BASEBOARD_FAB2(SCH_1):M_C_MA'<14>:
 C_SIGNAL='@baseboard_fab2_lib.baseboard_fab2(sch_1):m_c_ma(14)';
NODE_NAME     U5D1 W50
 '@BASEBOARD_FAB2_LIB.BASEBOARD_FAB2(SCH_1):PAGE25_I172@CHPSET_LIB.SKX_EXT_B(CHIPS)':
 'DDR2_MA'<14>: CDS_PINID='DDR2_MA(14)';
NODE_NAME     J4G3 228
 '@BASEBOARD_FAB2_LIB.BASEBOARD_FAB2(SCH_1):PAGE47_I111@MSTR_SCONN.SCONN288_H44441004(CHIPS)':
 'A14_WE_N': CDS_PINID='A14_WE_N';
NODE_NAME     J6U2 228
 '@BASEBOARD_FAB2_LIB.BASEBOARD_FAB2(SCH_1):PAGE48_I111@MSTR_SCONN.SCONN288_H44441003(CHIPS)':
 'A14_WE_N': CDS_PINID='A14_WE_N';
NET_NAME
'M_C_MA<15>'
 '@BASEBOARD_FAB2_LIB.BASEBOARD_FAB2(SCH_1):M_C_MA'<15>:
 C_SIGNAL='@baseboard_fab2_lib.baseboard_fab2(sch_1):m_c_ma(15)';
NODE_NAME     U5D1 AE54
 '@BASEBOARD_FAB2_LIB.BASEBOARD_FAB2(SCH_1):PAGE25_I172@CHPSET_LIB.SKX_EXT_B(CHIPS)':
 'DDR2_MA'<15>: CDS_PINID='DDR2_MA(15)';
NODE_NAME     J4G3 86
 '@BASEBOARD_FAB2_LIB.BASEBOARD_FAB2(SCH_1):PAGE47_I111@MSTR_SCONN.SCONN288_H44441004(CHIPS)':
 'A15_CAS_N': CDS_PINID='A15_CAS_N';
NODE_NAME     J6U2 86
 '@BASEBOARD_FAB2_LIB.BASEBOARD_FAB2(SCH_1):PAGE48_I111@MSTR_SCONN.SCONN288_H44441003(CHIPS)':
 'A15_CAS_N': CDS_PINID='A15_CAS_N';
NET_NAME
'M_C_MA<16>'
 '@BASEBOARD_FAB2_LIB.BASEBOARD_FAB2(SCH_1):M_C_MA'<16>:
 C_SIGNAL='@baseboard_fab2_lib.baseboard_fab2(sch_1):m_c_ma(16)';
NODE_NAME     U5D1 AA52
 '@BASEBOARD_FAB2_LIB.BASEBOARD_FAB2(SCH_1):PAGE25_I172@CHPSET_LIB.SKX_EXT_B(CHIPS)':
 'DDR2_MA'<16>: CDS_PINID='DDR2_MA(16)';
NODE_NAME     J4G3 82
 '@BASEBOARD_FAB2_LIB.BASEBOARD_FAB2(SCH_1):PAGE47_I111@MSTR_SCONN.SCONN288_H44441004(CHIPS)':
 'A16_RAS_N': CDS_PINID='A16_RAS_N';
NODE_NAME     J6U2 82
 '@BASEBOARD_FAB2_LIB.BASEBOARD_FAB2(SCH_1):PAGE48_I111@MSTR_SCONN.SCONN288_H44441003(CHIPS)':
 'A16_RAS_N': CDS_PINID='A16_RAS_N';
NET_NAME
'M_C_MA<17>'
 '@BASEBOARD_FAB2_LIB.BASEBOARD_FAB2(SCH_1):M_C_MA'<17>:
 C_SIGNAL='@baseboard_fab2_lib.baseboard_fab2(sch_1):m_c_ma(17)';
NODE_NAME     U5D1 AC46
 '@BASEBOARD_FAB2_LIB.BASEBOARD_FAB2(SCH_1):PAGE25_I172@CHPSET_LIB.SKX_EXT_B(CHIPS)':
 'DDR2_MA'<17>: CDS_PINID='DDR2_MA(17)';
NODE_NAME     J4G3 234
 '@BASEBOARD_FAB2_LIB.BASEBOARD_FAB2(SCH_1):PAGE47_I111@MSTR_SCONN.SCONN288_H44441004(CHIPS)':
 'A17': CDS_PINID='A17';
NODE_NAME     J6U2 234
 '@BASEBOARD_FAB2_LIB.BASEBOARD_FAB2(SCH_1):PAGE48_I111@MSTR_SCONN.SCONN288_H44441003(CHIPS)':
 'A17': CDS_PINID='A17';
NET_NAME
'M_C_MA<1>'
 '@BASEBOARD_FAB2_LIB.BASEBOARD_FAB2(SCH_1):M_C_MA'<1>:
 C_SIGNAL='@baseboard_fab2_lib.baseboard_fab2(sch_1):m_c_ma(1)';
NODE_NAME     U5D1 AE58
 '@BASEBOARD_FAB2_LIB.BASEBOARD_FAB2(SCH_1):PAGE25_I172@CHPSET_LIB.SKX_EXT_B(CHIPS)':
 'DDR2_MA'<1>: CDS_PINID='DDR2_MA(1)';
NODE_NAME     J4G3 72
 '@BASEBOARD_FAB2_LIB.BASEBOARD_FAB2(SCH_1):PAGE47_I111@MSTR_SCONN.SCONN288_H44441004(CHIPS)':
 'A1': CDS_PINID='A1';
NODE_NAME     J6U2 72
 '@BASEBOARD_FAB2_LIB.BASEBOARD_FAB2(SCH_1):PAGE48_I111@MSTR_SCONN.SCONN288_H44441003(CHIPS)':
 'A1': CDS_PINID='A1';
NET_NAME
'M_C_MA<2>'
 '@BASEBOARD_FAB2_LIB.BASEBOARD_FAB2(SCH_1):M_C_MA'<2>:
 C_SIGNAL='@baseboard_fab2_lib.baseboard_fab2(sch_1):m_c_ma(2)';
NODE_NAME     U5D1 AD57
 '@BASEBOARD_FAB2_LIB.BASEBOARD_FAB2(SCH_1):PAGE25_I172@CHPSET_LIB.SKX_EXT_B(CHIPS)':
 'DDR2_MA'<2>: CDS_PINID='DDR2_MA(2)';
NODE_NAME     J4G3 216
 '@BASEBOARD_FAB2_LIB.BASEBOARD_FAB2(SCH_1):PAGE47_I111@MSTR_SCONN.SCONN288_H44441004(CHIPS)':
 'A2': CDS_PINID='A2';
NODE_NAME     J6U2 216
 '@BASEBOARD_FAB2_LIB.BASEBOARD_FAB2(SCH_1):PAGE48_I111@MSTR_SCONN.SCONN288_H44441003(CHIPS)':
 'A2': CDS_PINID='A2';
NET_NAME
'M_C_MA<3>'
 '@BASEBOARD_FAB2_LIB.BASEBOARD_FAB2(SCH_1):M_C_MA'<3>:
 C_SIGNAL='@baseboard_fab2_lib.baseboard_fab2(sch_1):m_c_ma(3)';
NODE_NAME     U5D1 W58
 '@BASEBOARD_FAB2_LIB.BASEBOARD_FAB2(SCH_1):PAGE25_I172@CHPSET_LIB.SKX_EXT_B(CHIPS)':
 'DDR2_MA'<3>: CDS_PINID='DDR2_MA(3)';
NODE_NAME     J4G3 71
 '@BASEBOARD_FAB2_LIB.BASEBOARD_FAB2(SCH_1):PAGE47_I111@MSTR_SCONN.SCONN288_H44441004(CHIPS)':
 'A3': CDS_PINID='A3';
NODE_NAME     J6U2 71
 '@BASEBOARD_FAB2_LIB.BASEBOARD_FAB2(SCH_1):PAGE48_I111@MSTR_SCONN.SCONN288_H44441003(CHIPS)':
 'A3': CDS_PINID='A3';
NET_NAME
'M_C_MA<4>'
 '@BASEBOARD_FAB2_LIB.BASEBOARD_FAB2(SCH_1):M_C_MA'<4>:
 C_SIGNAL='@baseboard_fab2_lib.baseboard_fab2(sch_1):m_c_ma(4)';
NODE_NAME     U5D1 AA58
 '@BASEBOARD_FAB2_LIB.BASEBOARD_FAB2(SCH_1):PAGE25_I172@CHPSET_LIB.SKX_EXT_B(CHIPS)':
 'DDR2_MA'<4>: CDS_PINID='DDR2_MA(4)';
NODE_NAME     J4G3 214
 '@BASEBOARD_FAB2_LIB.BASEBOARD_FAB2(SCH_1):PAGE47_I111@MSTR_SCONN.SCONN288_H44441004(CHIPS)':
 'A4': CDS_PINID='A4';
NODE_NAME     J6U2 214
 '@BASEBOARD_FAB2_LIB.BASEBOARD_FAB2(SCH_1):PAGE48_I111@MSTR_SCONN.SCONN288_H44441003(CHIPS)':
 'A4': CDS_PINID='A4';
NET_NAME
'M_C_MA<5>'
 '@BASEBOARD_FAB2_LIB.BASEBOARD_FAB2(SCH_1):M_C_MA'<5>:
 C_SIGNAL='@baseboard_fab2_lib.baseboard_fab2(sch_1):m_c_ma(5)';
NODE_NAME     U5D1 V59
 '@BASEBOARD_FAB2_LIB.BASEBOARD_FAB2(SCH_1):PAGE25_I172@CHPSET_LIB.SKX_EXT_B(CHIPS)':
 'DDR2_MA'<5>: CDS_PINID='DDR2_MA(5)';
NODE_NAME     J4G3 213
 '@BASEBOARD_FAB2_LIB.BASEBOARD_FAB2(SCH_1):PAGE47_I111@MSTR_SCONN.SCONN288_H44441004(CHIPS)':
 'A5': CDS_PINID='A5';
NODE_NAME     J6U2 213
 '@BASEBOARD_FAB2_LIB.BASEBOARD_FAB2(SCH_1):PAGE48_I111@MSTR_SCONN.SCONN288_H44441003(CHIPS)':
 'A5': CDS_PINID='A5';
NET_NAME
'M_C_MA<6>'
 '@BASEBOARD_FAB2_LIB.BASEBOARD_FAB2(SCH_1):M_C_MA'<6>:
 C_SIGNAL='@baseboard_fab2_lib.baseboard_fab2(sch_1):m_c_ma(6)';
NODE_NAME     U5D1 AB59
 '@BASEBOARD_FAB2_LIB.BASEBOARD_FAB2(SCH_1):PAGE25_I172@CHPSET_LIB.SKX_EXT_B(CHIPS)':
 'DDR2_MA'<6>: CDS_PINID='DDR2_MA(6)';
NODE_NAME     J4G3 69
 '@BASEBOARD_FAB2_LIB.BASEBOARD_FAB2(SCH_1):PAGE47_I111@MSTR_SCONN.SCONN288_H44441004(CHIPS)':
 'A6': CDS_PINID='A6';
NODE_NAME     J6U2 69
 '@BASEBOARD_FAB2_LIB.BASEBOARD_FAB2(SCH_1):PAGE48_I111@MSTR_SCONN.SCONN288_H44441003(CHIPS)':
 'A6': CDS_PINID='A6';
NET_NAME
'M_C_MA<7>'
 '@BASEBOARD_FAB2_LIB.BASEBOARD_FAB2(SCH_1):M_C_MA'<7>:
 C_SIGNAL='@baseboard_fab2_lib.baseboard_fab2(sch_1):m_c_ma(7)';
NODE_NAME     U5D1 AE60
 '@BASEBOARD_FAB2_LIB.BASEBOARD_FAB2(SCH_1):PAGE25_I172@CHPSET_LIB.SKX_EXT_B(CHIPS)':
 'DDR2_MA'<7>: CDS_PINID='DDR2_MA(7)';
NODE_NAME     J4G3 211
 '@BASEBOARD_FAB2_LIB.BASEBOARD_FAB2(SCH_1):PAGE47_I111@MSTR_SCONN.SCONN288_H44441004(CHIPS)':
 'A7': CDS_PINID='A7';
NODE_NAME     J6U2 211
 '@BASEBOARD_FAB2_LIB.BASEBOARD_FAB2(SCH_1):PAGE48_I111@MSTR_SCONN.SCONN288_H44441003(CHIPS)':
 'A7': CDS_PINID='A7';
NET_NAME
'M_C_MA<8>'
 '@BASEBOARD_FAB2_LIB.BASEBOARD_FAB2(SCH_1):M_C_MA'<8>:
 C_SIGNAL='@baseboard_fab2_lib.baseboard_fab2(sch_1):m_c_ma(8)';
NODE_NAME     U5D1 AD59
 '@BASEBOARD_FAB2_LIB.BASEBOARD_FAB2(SCH_1):PAGE25_I172@CHPSET_LIB.SKX_EXT_B(CHIPS)':
 'DDR2_MA'<8>: CDS_PINID='DDR2_MA(8)';
NODE_NAME     J4G3 68
 '@BASEBOARD_FAB2_LIB.BASEBOARD_FAB2(SCH_1):PAGE47_I111@MSTR_SCONN.SCONN288_H44441004(CHIPS)':
 'A8': CDS_PINID='A8';
NODE_NAME     J6U2 68
 '@BASEBOARD_FAB2_LIB.BASEBOARD_FAB2(SCH_1):PAGE48_I111@MSTR_SCONN.SCONN288_H44441003(CHIPS)':
 'A8': CDS_PINID='A8';
NET_NAME
'M_C_MA<9>'
 '@BASEBOARD_FAB2_LIB.BASEBOARD_FAB2(SCH_1):M_C_MA'<9>:
 C_SIGNAL='@baseboard_fab2_lib.baseboard_fab2(sch_1):m_c_ma(9)';
NODE_NAME     U5D1 AG58
 '@BASEBOARD_FAB2_LIB.BASEBOARD_FAB2(SCH_1):PAGE25_I172@CHPSET_LIB.SKX_EXT_B(CHIPS)':
 'DDR2_MA'<9>: CDS_PINID='DDR2_MA(9)';
NODE_NAME     J4G3 66
 '@BASEBOARD_FAB2_LIB.BASEBOARD_FAB2(SCH_1):PAGE47_I111@MSTR_SCONN.SCONN288_H44441004(CHIPS)':
 'A9': CDS_PINID='A9';
NODE_NAME     J6U2 66
 '@BASEBOARD_FAB2_LIB.BASEBOARD_FAB2(SCH_1):PAGE48_I111@MSTR_SCONN.SCONN288_H44441003(CHIPS)':
 'A9': CDS_PINID='A9';
NET_NAME
'M_C_ODT<0>'
 '@BASEBOARD_FAB2_LIB.BASEBOARD_FAB2(SCH_1):M_C_ODT'<0>:
 C_SIGNAL='@baseboard_fab2_lib.baseboard_fab2(sch_1):m_c_odt(0)';
NODE_NAME     U5D1 AA50
 '@BASEBOARD_FAB2_LIB.BASEBOARD_FAB2(SCH_1):PAGE25_I172@CHPSET_LIB.SKX_EXT_B(CHIPS)':
 'DDR2_ODT'<0>: CDS_PINID='DDR2_ODT(0)';
NODE_NAME     J4G3 87
 '@BASEBOARD_FAB2_LIB.BASEBOARD_FAB2(SCH_1):PAGE47_I111@MSTR_SCONN.SCONN288_H44441004(CHIPS)':
 'ODT'<0>: CDS_PINID='ODT(0)';
NET_NAME
'M_C_ODT<1>'
 '@BASEBOARD_FAB2_LIB.BASEBOARD_FAB2(SCH_1):M_C_ODT'<1>:
 C_SIGNAL='@baseboard_fab2_lib.baseboard_fab2(sch_1):m_c_odt(1)';
NODE_NAME     U5D1 AA48
 '@BASEBOARD_FAB2_LIB.BASEBOARD_FAB2(SCH_1):PAGE25_I172@CHPSET_LIB.SKX_EXT_B(CHIPS)':
 'DDR2_ODT'<1>: CDS_PINID='DDR2_ODT(1)';
NODE_NAME     J4G3 91
 '@BASEBOARD_FAB2_LIB.BASEBOARD_FAB2(SCH_1):PAGE47_I111@MSTR_SCONN.SCONN288_H44441004(CHIPS)':
 'ODT'<1>: CDS_PINID='ODT(1)';
NET_NAME
'M_C_ODT<2>'
 '@BASEBOARD_FAB2_LIB.BASEBOARD_FAB2(SCH_1):M_C_ODT'<2>:
 C_SIGNAL='@baseboard_fab2_lib.baseboard_fab2(sch_1):m_c_odt(2)';
NODE_NAME     U5D1 V49
 '@BASEBOARD_FAB2_LIB.BASEBOARD_FAB2(SCH_1):PAGE25_I172@CHPSET_LIB.SKX_EXT_B(CHIPS)':
 'DDR2_ODT'<2>: CDS_PINID='DDR2_ODT(2)';
NODE_NAME     J6U2 87
 '@BASEBOARD_FAB2_LIB.BASEBOARD_FAB2(SCH_1):PAGE48_I111@MSTR_SCONN.SCONN288_H44441003(CHIPS)':
 'ODT'<0>: CDS_PINID='ODT(0)';
NET_NAME
'M_C_ODT<3>'
 '@BASEBOARD_FAB2_LIB.BASEBOARD_FAB2(SCH_1):M_C_ODT'<3>:
 C_SIGNAL='@baseboard_fab2_lib.baseboard_fab2(sch_1):m_c_odt(3)';
NODE_NAME     U5D1 AB47
 '@BASEBOARD_FAB2_LIB.BASEBOARD_FAB2(SCH_1):PAGE25_I172@CHPSET_LIB.SKX_EXT_B(CHIPS)':
 'DDR2_ODT'<3>: CDS_PINID='DDR2_ODT(3)';
NODE_NAME     J6U2 91
 '@BASEBOARD_FAB2_LIB.BASEBOARD_FAB2(SCH_1):PAGE48_I111@MSTR_SCONN.SCONN288_H44441003(CHIPS)':
 'ODT'<1>: CDS_PINID='ODT(1)';
NET_NAME
'M_C_PAR'
 '@BASEBOARD_FAB2_LIB.BASEBOARD_FAB2(SCH_1):M_C_PAR':
 C_SIGNAL='@baseboard_fab2_lib.baseboard_fab2(sch_1):m_c_par';
NODE_NAME     U5D1 V53
 '@BASEBOARD_FAB2_LIB.BASEBOARD_FAB2(SCH_1):PAGE25_I172@CHPSET_LIB.SKX_EXT_B(CHIPS)':
 'DDR2_PAR': CDS_PINID='DDR2_PAR';
NODE_NAME     J4G3 222
 '@BASEBOARD_FAB2_LIB.BASEBOARD_FAB2(SCH_1):PAGE47_I111@MSTR_SCONN.SCONN288_H44441004(CHIPS)':
 'PAR': CDS_PINID='PAR';
NODE_NAME     J6U2 222
 '@BASEBOARD_FAB2_LIB.BASEBOARD_FAB2(SCH_1):PAGE48_I111@MSTR_SCONN.SCONN288_H44441003(CHIPS)':
 'PAR': CDS_PINID='PAR';
NET_NAME
'M_C_VREF'
 '@BASEBOARD_FAB2_LIB.BASEBOARD_FAB2(SCH_1):M_C_VREF':
 C_SIGNAL='@baseboard_fab2_lib.baseboard_fab2(sch_1):m_c_vref';
NODE_NAME     J4G3 146
 '@BASEBOARD_FAB2_LIB.BASEBOARD_FAB2(SCH_1):PAGE47_I111@MSTR_SCONN.SCONN288_H44441004(CHIPS)':
 'VREFCA': CDS_PINID='VREFCA';
NODE_NAME     C4G19 1
 '@BASEBOARD_FAB2_LIB.BASEBOARD_FAB2(SCH_1):PAGE47_I188@DEV_DISCRETE.CAP_A(CHIPS)':
 'A': CDS_PINID='A';
NODE_NAME     J6U2 146
 '@BASEBOARD_FAB2_LIB.BASEBOARD_FAB2(SCH_1):PAGE48_I111@MSTR_SCONN.SCONN288_H44441003(CHIPS)':
 'VREFCA': CDS_PINID='VREFCA';
NODE_NAME     C6U17 1
 '@BASEBOARD_FAB2_LIB.BASEBOARD_FAB2(SCH_1):PAGE48_I176@DEV_DISCRETE.CAP_A(CHIPS)':
 'A': CDS_PINID='A';
NODE_NAME     R4G21 2
 '@BASEBOARD_FAB2_LIB.BASEBOARD_FAB2(SCH_1):PAGE98_I46@MSTR_DISCRETE.RES(CHIPS)':
 'B': CDS_PINID='B';
NODE_NAME     R4G22 1
 '@BASEBOARD_FAB2_LIB.BASEBOARD_FAB2(SCH_1):PAGE98_I48@MSTR_DISCRETE.RES(CHIPS)':
 'A': CDS_PINID='A';
NODE_NAME     R4G20 2
 '@BASEBOARD_FAB2_LIB.BASEBOARD_FAB2(SCH_1):PAGE98_I50@MSTR_DISCRETE.RES(CHIPS)':
 'B': CDS_PINID='B';
NET_NAME
'M_DEF_RST_N'
 '@BASEBOARD_FAB2_LIB.BASEBOARD_FAB2(SCH_1):M_DEF_RST_N':
 C_SIGNAL='@baseboard_fab2_lib.baseboard_fab2(sch_1):m_def_rst_n';
NODE_NAME     U5D1 DV63
 '@BASEBOARD_FAB2_LIB.BASEBOARD_FAB2(SCH_1):PAGE21_I259@CHPSET_LIB.SKX_EXT_B(CHIPS)':
 'DDR345_RESET_N': CDS_PINID='DDR345_RESET_N';
NODE_NAME     J4B1 58
 '@BASEBOARD_FAB2_LIB.BASEBOARD_FAB2(SCH_1):PAGE49_I111@MSTR_SCONN.SCONN288_H44441004(CHIPS)':
 'RESET_N': CDS_PINID='RESET_N';
NODE_NAME     J6M1 58
 '@BASEBOARD_FAB2_LIB.BASEBOARD_FAB2(SCH_1):PAGE50_I158@MSTR_SCONN.SCONN288_H44441003(CHIPS)':
 'RESET_N': CDS_PINID='RESET_N';
NODE_NAME     J4A2 58
 '@BASEBOARD_FAB2_LIB.BASEBOARD_FAB2(SCH_1):PAGE51_I111@MSTR_SCONN.SCONN288_H44441004(CHIPS)':
 'RESET_N': CDS_PINID='RESET_N';
NODE_NAME     J6L2 58
 '@BASEBOARD_FAB2_LIB.BASEBOARD_FAB2(SCH_1):PAGE52_I12@MSTR_SCONN.SCONN288_H44441003(CHIPS)':
 'RESET_N': CDS_PINID='RESET_N';
NODE_NAME     J4A1 58
 '@BASEBOARD_FAB2_LIB.BASEBOARD_FAB2(SCH_1):PAGE53_I111@MSTR_SCONN.SCONN288_H44441004(CHIPS)':
 'RESET_N': CDS_PINID='RESET_N';
NODE_NAME     J6L1 58
 '@BASEBOARD_FAB2_LIB.BASEBOARD_FAB2(SCH_1):PAGE54_I111@MSTR_SCONN.SCONN288_H44441003(CHIPS)':
 'RESET_N': CDS_PINID='RESET_N';
NET_NAME
'M_D_ACT_N'
 '@BASEBOARD_FAB2_LIB.BASEBOARD_FAB2(SCH_1):M_D_ACT_N':
 C_SIGNAL='@baseboard_fab2_lib.baseboard_fab2(sch_1):m_d_act_n';
NODE_NAME     U5D1 DW60
 '@BASEBOARD_FAB2_LIB.BASEBOARD_FAB2(SCH_1):PAGE26_I172@CHPSET_LIB.SKX_EXT_B(CHIPS)':
 'DDR3_ACT_N': CDS_PINID='DDR3_ACT_N';
NODE_NAME     J4B1 62
 '@BASEBOARD_FAB2_LIB.BASEBOARD_FAB2(SCH_1):PAGE49_I111@MSTR_SCONN.SCONN288_H44441004(CHIPS)':
 'ACT_N': CDS_PINID='ACT_N';
NODE_NAME     J6M1 62
 '@BASEBOARD_FAB2_LIB.BASEBOARD_FAB2(SCH_1):PAGE50_I158@MSTR_SCONN.SCONN288_H44441003(CHIPS)':
 'ACT_N': CDS_PINID='ACT_N';
NET_NAME
'M_D_ALERT_N'
 '@BASEBOARD_FAB2_LIB.BASEBOARD_FAB2(SCH_1):M_D_ALERT_N':
 C_SIGNAL='@baseboard_fab2_lib.baseboard_fab2(sch_1):m_d_alert_n';
NODE_NAME     U5D1 ED63
 '@BASEBOARD_FAB2_LIB.BASEBOARD_FAB2(SCH_1):PAGE26_I172@CHPSET_LIB.SKX_EXT_B(CHIPS)':
 'DDR3_ALERT_N': CDS_PINID='DDR3_ALERT_N';
NODE_NAME     J4B1 208
 '@BASEBOARD_FAB2_LIB.BASEBOARD_FAB2(SCH_1):PAGE49_I111@MSTR_SCONN.SCONN288_H44441004(CHIPS)':
 'ALERT_N': CDS_PINID='ALERT_N';
NODE_NAME     J6M1 208
 '@BASEBOARD_FAB2_LIB.BASEBOARD_FAB2(SCH_1):PAGE50_I158@MSTR_SCONN.SCONN288_H44441003(CHIPS)':
 'ALERT_N': CDS_PINID='ALERT_N';
NET_NAME
'M_D_BA<0>'
 '@BASEBOARD_FAB2_LIB.BASEBOARD_FAB2(SCH_1):M_D_BA'<0>:
 C_SIGNAL='@baseboard_fab2_lib.baseboard_fab2(sch_1):m_d_ba(0)';
NODE_NAME     U5D1 EE52
 '@BASEBOARD_FAB2_LIB.BASEBOARD_FAB2(SCH_1):PAGE26_I172@CHPSET_LIB.SKX_EXT_B(CHIPS)':
 'DDR3_BA'<0>: CDS_PINID='DDR3_BA(0)';
NODE_NAME     J4B1 81
 '@BASEBOARD_FAB2_LIB.BASEBOARD_FAB2(SCH_1):PAGE49_I111@MSTR_SCONN.SCONN288_H44441004(CHIPS)':
 'BA'<0>: CDS_PINID='BA(0)';
NODE_NAME     J6M1 81
 '@BASEBOARD_FAB2_LIB.BASEBOARD_FAB2(SCH_1):PAGE50_I158@MSTR_SCONN.SCONN288_H44441003(CHIPS)':
 'BA'<0>: CDS_PINID='BA(0)';
NET_NAME
'M_D_BA<1>'
 '@BASEBOARD_FAB2_LIB.BASEBOARD_FAB2(SCH_1):M_D_BA'<1>:
 C_SIGNAL='@baseboard_fab2_lib.baseboard_fab2(sch_1):m_d_ba(1)';
NODE_NAME     U5D1 EA54
 '@BASEBOARD_FAB2_LIB.BASEBOARD_FAB2(SCH_1):PAGE26_I172@CHPSET_LIB.SKX_EXT_B(CHIPS)':
 'DDR3_BA'<1>: CDS_PINID='DDR3_BA(1)';
NODE_NAME     J4B1 224
 '@BASEBOARD_FAB2_LIB.BASEBOARD_FAB2(SCH_1):PAGE49_I111@MSTR_SCONN.SCONN288_H44441004(CHIPS)':
 'BA'<1>: CDS_PINID='BA(1)';
NODE_NAME     J6M1 224
 '@BASEBOARD_FAB2_LIB.BASEBOARD_FAB2(SCH_1):PAGE50_I158@MSTR_SCONN.SCONN288_H44441003(CHIPS)':
 'BA'<1>: CDS_PINID='BA(1)';
NET_NAME
'M_D_BG<0>'
 '@BASEBOARD_FAB2_LIB.BASEBOARD_FAB2(SCH_1):M_D_BG'<0>:
 C_SIGNAL='@baseboard_fab2_lib.baseboard_fab2(sch_1):m_d_bg(0)';
NODE_NAME     U5D1 ED61
 '@BASEBOARD_FAB2_LIB.BASEBOARD_FAB2(SCH_1):PAGE26_I172@CHPSET_LIB.SKX_EXT_B(CHIPS)':
 'DDR3_BG'<0>: CDS_PINID='DDR3_BG(0)';
NODE_NAME     J4B1 63
 '@BASEBOARD_FAB2_LIB.BASEBOARD_FAB2(SCH_1):PAGE49_I111@MSTR_SCONN.SCONN288_H44441004(CHIPS)':
 'BG'<0>: CDS_PINID='BG(0)';
NODE_NAME     J6M1 63
 '@BASEBOARD_FAB2_LIB.BASEBOARD_FAB2(SCH_1):PAGE50_I158@MSTR_SCONN.SCONN288_H44441003(CHIPS)':
 'BG'<0>: CDS_PINID='BG(0)';
NET_NAME
'M_D_BG<1>'
 '@BASEBOARD_FAB2_LIB.BASEBOARD_FAB2(SCH_1):M_D_BG'<1>:
 C_SIGNAL='@baseboard_fab2_lib.baseboard_fab2(sch_1):m_d_bg(1)';
NODE_NAME     U5D1 DW62
 '@BASEBOARD_FAB2_LIB.BASEBOARD_FAB2(SCH_1):PAGE26_I172@CHPSET_LIB.SKX_EXT_B(CHIPS)':
 'DDR3_BG'<1>: CDS_PINID='DDR3_BG(1)';
NODE_NAME     J4B1 207
 '@BASEBOARD_FAB2_LIB.BASEBOARD_FAB2(SCH_1):PAGE49_I111@MSTR_SCONN.SCONN288_H44441004(CHIPS)':
 'BG'<1>: CDS_PINID='BG(1)';
NODE_NAME     J6M1 207
 '@BASEBOARD_FAB2_LIB.BASEBOARD_FAB2(SCH_1):PAGE50_I158@MSTR_SCONN.SCONN288_H44441003(CHIPS)':
 'BG'<1>: CDS_PINID='BG(1)';
NET_NAME
'M_D_C<2>'
 '@BASEBOARD_FAB2_LIB.BASEBOARD_FAB2(SCH_1):M_D_C'<2>:
 C_SIGNAL='@baseboard_fab2_lib.baseboard_fab2(sch_1):m_d_c(2)';
NODE_NAME     U5D1 DV47
 '@BASEBOARD_FAB2_LIB.BASEBOARD_FAB2(SCH_1):PAGE26_I172@CHPSET_LIB.SKX_EXT_B(CHIPS)':
 'DDR3_CID'<2>: CDS_PINID='DDR3_CID(2)';
NODE_NAME     J4B1 235
 '@BASEBOARD_FAB2_LIB.BASEBOARD_FAB2(SCH_1):PAGE49_I111@MSTR_SCONN.SCONN288_H44441004(CHIPS)':
 'C'<2>: CDS_PINID='C(2)';
NODE_NAME     J6M1 235
 '@BASEBOARD_FAB2_LIB.BASEBOARD_FAB2(SCH_1):PAGE50_I158@MSTR_SCONN.SCONN288_H44441003(CHIPS)':
 'C'<2>: CDS_PINID='C(2)';
NET_NAME
'M_D_CKE<0>'
 '@BASEBOARD_FAB2_LIB.BASEBOARD_FAB2(SCH_1):M_D_CKE'<0>:
 C_SIGNAL='@baseboard_fab2_lib.baseboard_fab2(sch_1):m_d_cke(0)';
NODE_NAME     U5D1 EE62
 '@BASEBOARD_FAB2_LIB.BASEBOARD_FAB2(SCH_1):PAGE26_I172@CHPSET_LIB.SKX_EXT_B(CHIPS)':
 'DDR3_CKE'<0>: CDS_PINID='DDR3_CKE(0)';
NODE_NAME     J4B1 60
 '@BASEBOARD_FAB2_LIB.BASEBOARD_FAB2(SCH_1):PAGE49_I111@MSTR_SCONN.SCONN288_H44441004(CHIPS)':
 'CKE'<0>: CDS_PINID='CKE(0)';
NET_NAME
'M_D_CKE<1>'
 '@BASEBOARD_FAB2_LIB.BASEBOARD_FAB2(SCH_1):M_D_CKE'<1>:
 C_SIGNAL='@baseboard_fab2_lib.baseboard_fab2(sch_1):m_d_cke(1)';
NODE_NAME     U5D1 EF63
 '@BASEBOARD_FAB2_LIB.BASEBOARD_FAB2(SCH_1):PAGE26_I172@CHPSET_LIB.SKX_EXT_B(CHIPS)':
 'DDR3_CKE'<1>: CDS_PINID='DDR3_CKE(1)';
NODE_NAME     J4B1 203
 '@BASEBOARD_FAB2_LIB.BASEBOARD_FAB2(SCH_1):PAGE49_I111@MSTR_SCONN.SCONN288_H44441004(CHIPS)':
 'CKE'<1>: CDS_PINID='CKE(1)';
NET_NAME
'M_D_CKE<2>'
 '@BASEBOARD_FAB2_LIB.BASEBOARD_FAB2(SCH_1):M_D_CKE'<2>:
 C_SIGNAL='@baseboard_fab2_lib.baseboard_fab2(sch_1):m_d_cke(2)';
NODE_NAME     U5D1 EA62
 '@BASEBOARD_FAB2_LIB.BASEBOARD_FAB2(SCH_1):PAGE26_I172@CHPSET_LIB.SKX_EXT_B(CHIPS)':
 'DDR3_CKE'<2>: CDS_PINID='DDR3_CKE(2)';
NODE_NAME     J6M1 60
 '@BASEBOARD_FAB2_LIB.BASEBOARD_FAB2(SCH_1):PAGE50_I158@MSTR_SCONN.SCONN288_H44441003(CHIPS)':
 'CKE'<0>: CDS_PINID='CKE(0)';
NET_NAME
'M_D_CKE<3>'
 '@BASEBOARD_FAB2_LIB.BASEBOARD_FAB2(SCH_1):M_D_CKE'<3>:
 C_SIGNAL='@baseboard_fab2_lib.baseboard_fab2(sch_1):m_d_cke(3)';
NODE_NAME     U5D1 EB63
 '@BASEBOARD_FAB2_LIB.BASEBOARD_FAB2(SCH_1):PAGE26_I172@CHPSET_LIB.SKX_EXT_B(CHIPS)':
 'DDR3_CKE'<3>: CDS_PINID='DDR3_CKE(3)';
NODE_NAME     J6M1 203
 '@BASEBOARD_FAB2_LIB.BASEBOARD_FAB2(SCH_1):PAGE50_I158@MSTR_SCONN.SCONN288_H44441003(CHIPS)':
 'CKE'<1>: CDS_PINID='CKE(1)';
NET_NAME
'M_D_CLK_DN<0>'
 '@BASEBOARD_FAB2_LIB.BASEBOARD_FAB2(SCH_1):M_D_CLK_DN'<0>:
 C_SIGNAL='@baseboard_fab2_lib.baseboard_fab2(sch_1):m_d_clk_dn(0)';
NODE_NAME     U5D1 ED55
 '@BASEBOARD_FAB2_LIB.BASEBOARD_FAB2(SCH_1):PAGE26_I172@CHPSET_LIB.SKX_EXT_B(CHIPS)':
 'DDR3_CLK_DN'<0>: CDS_PINID='DDR3_CLK_DN(0)';
NODE_NAME     J4B1 75
 '@BASEBOARD_FAB2_LIB.BASEBOARD_FAB2(SCH_1):PAGE49_I111@MSTR_SCONN.SCONN288_H44441004(CHIPS)':
 'CK0N': CDS_PINID='CK0N';
NET_NAME
'M_D_CLK_DN<1>'
 '@BASEBOARD_FAB2_LIB.BASEBOARD_FAB2(SCH_1):M_D_CLK_DN'<1>:
 C_SIGNAL='@baseboard_fab2_lib.baseboard_fab2(sch_1):m_d_clk_dn(1)';
NODE_NAME     U5D1 EF55
 '@BASEBOARD_FAB2_LIB.BASEBOARD_FAB2(SCH_1):PAGE26_I172@CHPSET_LIB.SKX_EXT_B(CHIPS)':
 'DDR3_CLK_DN'<1>: CDS_PINID='DDR3_CLK_DN(1)';
NODE_NAME     J4B1 219
 '@BASEBOARD_FAB2_LIB.BASEBOARD_FAB2(SCH_1):PAGE49_I111@MSTR_SCONN.SCONN288_H44441004(CHIPS)':
 'CK1N': CDS_PINID='CK1N';
NET_NAME
'M_D_CLK_DN<2>'
 '@BASEBOARD_FAB2_LIB.BASEBOARD_FAB2(SCH_1):M_D_CLK_DN'<2>:
 C_SIGNAL='@baseboard_fab2_lib.baseboard_fab2(sch_1):m_d_clk_dn(2)';
NODE_NAME     U5D1 DW56
 '@BASEBOARD_FAB2_LIB.BASEBOARD_FAB2(SCH_1):PAGE26_I172@CHPSET_LIB.SKX_EXT_B(CHIPS)':
 'DDR3_CLK_DN'<2>: CDS_PINID='DDR3_CLK_DN(2)';
NODE_NAME     J6M1 75
 '@BASEBOARD_FAB2_LIB.BASEBOARD_FAB2(SCH_1):PAGE50_I158@MSTR_SCONN.SCONN288_H44441003(CHIPS)':
 'CK0N': CDS_PINID='CK0N';
NET_NAME
'M_D_CLK_DN<3>'
 '@BASEBOARD_FAB2_LIB.BASEBOARD_FAB2(SCH_1):M_D_CLK_DN'<3>:
 C_SIGNAL='@baseboard_fab2_lib.baseboard_fab2(sch_1):m_d_clk_dn(3)';
NODE_NAME     U5D1 EF57
 '@BASEBOARD_FAB2_LIB.BASEBOARD_FAB2(SCH_1):PAGE26_I172@CHPSET_LIB.SKX_EXT_B(CHIPS)':
 'DDR3_CLK_DN'<3>: CDS_PINID='DDR3_CLK_DN(3)';
NODE_NAME     J6M1 219
 '@BASEBOARD_FAB2_LIB.BASEBOARD_FAB2(SCH_1):PAGE50_I158@MSTR_SCONN.SCONN288_H44441003(CHIPS)':
 'CK1N': CDS_PINID='CK1N';
NET_NAME
'M_D_CLK_DP<0>'
 '@BASEBOARD_FAB2_LIB.BASEBOARD_FAB2(SCH_1):M_D_CLK_DP'<0>:
 C_SIGNAL='@baseboard_fab2_lib.baseboard_fab2(sch_1):m_d_clk_dp(0)';
NODE_NAME     U5D1 EB55
 '@BASEBOARD_FAB2_LIB.BASEBOARD_FAB2(SCH_1):PAGE26_I172@CHPSET_LIB.SKX_EXT_B(CHIPS)':
 'DDR3_CLK_DP'<0>: CDS_PINID='DDR3_CLK_DP(0)';
NODE_NAME     J4B1 74
 '@BASEBOARD_FAB2_LIB.BASEBOARD_FAB2(SCH_1):PAGE49_I111@MSTR_SCONN.SCONN288_H44441004(CHIPS)':
 'CK0P': CDS_PINID='CK0P';
NET_NAME
'M_D_CLK_DP<1>'
 '@BASEBOARD_FAB2_LIB.BASEBOARD_FAB2(SCH_1):M_D_CLK_DP'<1>:
 C_SIGNAL='@baseboard_fab2_lib.baseboard_fab2(sch_1):m_d_clk_dp(1)';
NODE_NAME     U5D1 EE54
 '@BASEBOARD_FAB2_LIB.BASEBOARD_FAB2(SCH_1):PAGE26_I172@CHPSET_LIB.SKX_EXT_B(CHIPS)':
 'DDR3_CLK_DP'<1>: CDS_PINID='DDR3_CLK_DP(1)';
NODE_NAME     J4B1 218
 '@BASEBOARD_FAB2_LIB.BASEBOARD_FAB2(SCH_1):PAGE49_I111@MSTR_SCONN.SCONN288_H44441004(CHIPS)':
 'CK1P': CDS_PINID='CK1P';
NET_NAME
'M_D_CLK_DP<2>'
 '@BASEBOARD_FAB2_LIB.BASEBOARD_FAB2(SCH_1):M_D_CLK_DP'<2>:
 C_SIGNAL='@baseboard_fab2_lib.baseboard_fab2(sch_1):m_d_clk_dp(2)';
NODE_NAME     U5D1 EA56
 '@BASEBOARD_FAB2_LIB.BASEBOARD_FAB2(SCH_1):PAGE26_I172@CHPSET_LIB.SKX_EXT_B(CHIPS)':
 'DDR3_CLK_DP'<2>: CDS_PINID='DDR3_CLK_DP(2)';
NODE_NAME     J6M1 74
 '@BASEBOARD_FAB2_LIB.BASEBOARD_FAB2(SCH_1):PAGE50_I158@MSTR_SCONN.SCONN288_H44441003(CHIPS)':
 'CK0P': CDS_PINID='CK0P';
NET_NAME
'M_D_CLK_DP<3>'
 '@BASEBOARD_FAB2_LIB.BASEBOARD_FAB2(SCH_1):M_D_CLK_DP'<3>:
 C_SIGNAL='@baseboard_fab2_lib.baseboard_fab2(sch_1):m_d_clk_dp(3)';
NODE_NAME     U5D1 EE56
 '@BASEBOARD_FAB2_LIB.BASEBOARD_FAB2(SCH_1):PAGE26_I172@CHPSET_LIB.SKX_EXT_B(CHIPS)':
 'DDR3_CLK_DP'<3>: CDS_PINID='DDR3_CLK_DP(3)';
NODE_NAME     J6M1 218
 '@BASEBOARD_FAB2_LIB.BASEBOARD_FAB2(SCH_1):PAGE50_I158@MSTR_SCONN.SCONN288_H44441003(CHIPS)':
 'CK1P': CDS_PINID='CK1P';
NET_NAME
'M_D_CPU_VREF'
 '@BASEBOARD_FAB2_LIB.BASEBOARD_FAB2(SCH_1):M_D_CPU_VREF':
 C_SIGNAL='@baseboard_fab2_lib.baseboard_fab2(sch_1):m_d_cpu_vref';
NODE_NAME     U5D1 CP61
 '@BASEBOARD_FAB2_LIB.BASEBOARD_FAB2(SCH_1):PAGE21_I259@CHPSET_LIB.SKX_EXT_B(CHIPS)':
 'DDR3_CAVREF': CDS_PINID='DDR3_CAVREF';
NODE_NAME     R6M2 1
 '@BASEBOARD_FAB2_LIB.BASEBOARD_FAB2(SCH_1):PAGE98_I14@MSTR_DISCRETE.RES(CHIPS)':
 'A': CDS_PINID='A';
NODE_NAME     C6M2 1
 '@BASEBOARD_FAB2_LIB.BASEBOARD_FAB2(SCH_1):PAGE98_I33@DEV_DISCRETE.CAP_A(CHIPS)':
 'A': CDS_PINID='A';
NET_NAME
'M_D_CS_N<0>'
 '@BASEBOARD_FAB2_LIB.BASEBOARD_FAB2(SCH_1):M_D_CS_N'<0>:
 C_SIGNAL='@baseboard_fab2_lib.baseboard_fab2(sch_1):m_d_cs_n(0)';
NODE_NAME     U5D1 EF51
 '@BASEBOARD_FAB2_LIB.BASEBOARD_FAB2(SCH_1):PAGE26_I172@CHPSET_LIB.SKX_EXT_B(CHIPS)':
 'DDR3_CS_N'<0>: CDS_PINID='DDR3_CS_N(0)';
NODE_NAME     J4B1 84
 '@BASEBOARD_FAB2_LIB.BASEBOARD_FAB2(SCH_1):PAGE49_I111@MSTR_SCONN.SCONN288_H44441004(CHIPS)':
 'S0_N': CDS_PINID='S0_N';
NET_NAME
'M_D_CS_N<1>'
 '@BASEBOARD_FAB2_LIB.BASEBOARD_FAB2(SCH_1):M_D_CS_N'<1>:
 C_SIGNAL='@baseboard_fab2_lib.baseboard_fab2(sch_1):m_d_cs_n(1)';
NODE_NAME     U5D1 ED49
 '@BASEBOARD_FAB2_LIB.BASEBOARD_FAB2(SCH_1):PAGE26_I172@CHPSET_LIB.SKX_EXT_B(CHIPS)':
 'DDR3_CS_N'<1>: CDS_PINID='DDR3_CS_N(1)';
NODE_NAME     J4B1 89
 '@BASEBOARD_FAB2_LIB.BASEBOARD_FAB2(SCH_1):PAGE49_I111@MSTR_SCONN.SCONN288_H44441004(CHIPS)':
 'S1_N': CDS_PINID='S1_N';
NET_NAME
'M_D_CS_N<2>'
 '@BASEBOARD_FAB2_LIB.BASEBOARD_FAB2(SCH_1):M_D_CS_N'<2>:
 C_SIGNAL='@baseboard_fab2_lib.baseboard_fab2(sch_1):m_d_cs_n(2)';
NODE_NAME     U5D1 ED47
 '@BASEBOARD_FAB2_LIB.BASEBOARD_FAB2(SCH_1):PAGE26_I172@CHPSET_LIB.SKX_EXT_B(CHIPS)':
 'DDR3_CS_N'<2>: CDS_PINID='DDR3_CS_N(2)';
NODE_NAME     J4B1 93
 '@BASEBOARD_FAB2_LIB.BASEBOARD_FAB2(SCH_1):PAGE49_I111@MSTR_SCONN.SCONN288_H44441004(CHIPS)':
 'S2_N_C'<0>: CDS_PINID='S2_N_C(0)';
NET_NAME
'M_D_CS_N<3>'
 '@BASEBOARD_FAB2_LIB.BASEBOARD_FAB2(SCH_1):M_D_CS_N'<3>:
 C_SIGNAL='@baseboard_fab2_lib.baseboard_fab2(sch_1):m_d_cs_n(3)';
NODE_NAME     U5D1 EB47
 '@BASEBOARD_FAB2_LIB.BASEBOARD_FAB2(SCH_1):PAGE26_I172@CHPSET_LIB.SKX_EXT_B(CHIPS)':
 'DDR3_CS_N'<3>: CDS_PINID='DDR3_CS_N(3)';
NODE_NAME     J4B1 237
 '@BASEBOARD_FAB2_LIB.BASEBOARD_FAB2(SCH_1):PAGE49_I111@MSTR_SCONN.SCONN288_H44441004(CHIPS)':
 'S3_N_C'<1>: CDS_PINID='S3_N_C(1)';
NET_NAME
'M_D_CS_N<4>'
 '@BASEBOARD_FAB2_LIB.BASEBOARD_FAB2(SCH_1):M_D_CS_N'<4>:
 C_SIGNAL='@baseboard_fab2_lib.baseboard_fab2(sch_1):m_d_cs_n(4)';
NODE_NAME     U5D1 EB51
 '@BASEBOARD_FAB2_LIB.BASEBOARD_FAB2(SCH_1):PAGE26_I172@CHPSET_LIB.SKX_EXT_B(CHIPS)':
 'DDR3_CS_N'<4>: CDS_PINID='DDR3_CS_N(4)';
NODE_NAME     J6M1 84
 '@BASEBOARD_FAB2_LIB.BASEBOARD_FAB2(SCH_1):PAGE50_I158@MSTR_SCONN.SCONN288_H44441003(CHIPS)':
 'S0_N': CDS_PINID='S0_N';
NET_NAME
'M_D_CS_N<5>'
 '@BASEBOARD_FAB2_LIB.BASEBOARD_FAB2(SCH_1):M_D_CS_N'<5>:
 C_SIGNAL='@baseboard_fab2_lib.baseboard_fab2(sch_1):m_d_cs_n(5)';
NODE_NAME     U5D1 EB49
 '@BASEBOARD_FAB2_LIB.BASEBOARD_FAB2(SCH_1):PAGE26_I172@CHPSET_LIB.SKX_EXT_B(CHIPS)':
 'DDR3_CS_N'<5>: CDS_PINID='DDR3_CS_N(5)';
NODE_NAME     J6M1 89
 '@BASEBOARD_FAB2_LIB.BASEBOARD_FAB2(SCH_1):PAGE50_I158@MSTR_SCONN.SCONN288_H44441003(CHIPS)':
 'S1_N': CDS_PINID='S1_N';
NET_NAME
'M_D_CS_N<6>'
 '@BASEBOARD_FAB2_LIB.BASEBOARD_FAB2(SCH_1):M_D_CS_N'<6>:
 C_SIGNAL='@baseboard_fab2_lib.baseboard_fab2(sch_1):m_d_cs_n(6)';
NODE_NAME     U5D1 DV45
 '@BASEBOARD_FAB2_LIB.BASEBOARD_FAB2(SCH_1):PAGE26_I172@CHPSET_LIB.SKX_EXT_B(CHIPS)':
 'DDR3_CS_N'<6>: CDS_PINID='DDR3_CS_N(6)';
NODE_NAME     J6M1 93
 '@BASEBOARD_FAB2_LIB.BASEBOARD_FAB2(SCH_1):PAGE50_I158@MSTR_SCONN.SCONN288_H44441003(CHIPS)':
 'S2_N_C'<0>: CDS_PINID='S2_N_C(0)';
NET_NAME
'M_D_CS_N<7>'
 '@BASEBOARD_FAB2_LIB.BASEBOARD_FAB2(SCH_1):M_D_CS_N'<7>:
 C_SIGNAL='@baseboard_fab2_lib.baseboard_fab2(sch_1):m_d_cs_n(7)';
NODE_NAME     U5D1 EB45
 '@BASEBOARD_FAB2_LIB.BASEBOARD_FAB2(SCH_1):PAGE26_I172@CHPSET_LIB.SKX_EXT_B(CHIPS)':
 'DDR3_CS_N'<7>: CDS_PINID='DDR3_CS_N(7)';
NODE_NAME     J6M1 237
 '@BASEBOARD_FAB2_LIB.BASEBOARD_FAB2(SCH_1):PAGE50_I158@MSTR_SCONN.SCONN288_H44441003(CHIPS)':
 'S3_N_C'<1>: CDS_PINID='S3_N_C(1)';
NET_NAME
'M_D_DQ<0>'
 '@BASEBOARD_FAB2_LIB.BASEBOARD_FAB2(SCH_1):M_D_DQ'<0>:
 C_SIGNAL='@baseboard_fab2_lib.baseboard_fab2(sch_1):m_d_dq(0)';
NODE_NAME     U5D1 CN84
 '@BASEBOARD_FAB2_LIB.BASEBOARD_FAB2(SCH_1):PAGE26_I172@CHPSET_LIB.SKX_EXT_B(CHIPS)':
 'DDR3_DQ'<0>: CDS_PINID='DDR3_DQ(0)';
NODE_NAME     J4B1 150
 '@BASEBOARD_FAB2_LIB.BASEBOARD_FAB2(SCH_1):PAGE49_I111@MSTR_SCONN.SCONN288_H44441004(CHIPS)':
 'DQ'<1>: CDS_PINID='DQ(1)';
NODE_NAME     J6M1 5
 '@BASEBOARD_FAB2_LIB.BASEBOARD_FAB2(SCH_1):PAGE50_I158@MSTR_SCONN.SCONN288_H44441003(CHIPS)':
 'DQ'<0>: CDS_PINID='DQ(0)';
NET_NAME
'M_D_DQ<10>'
 '@BASEBOARD_FAB2_LIB.BASEBOARD_FAB2(SCH_1):M_D_DQ'<10>:
 C_SIGNAL='@baseboard_fab2_lib.baseboard_fab2(sch_1):m_d_dq(10)';
NODE_NAME     U5D1 DV83
 '@BASEBOARD_FAB2_LIB.BASEBOARD_FAB2(SCH_1):PAGE26_I172@CHPSET_LIB.SKX_EXT_B(CHIPS)':
 'DDR3_DQ'<10>: CDS_PINID='DDR3_DQ(10)';
NODE_NAME     J4B1 168
 '@BASEBOARD_FAB2_LIB.BASEBOARD_FAB2(SCH_1):PAGE49_I111@MSTR_SCONN.SCONN288_H44441004(CHIPS)':
 'DQ'<11>: CDS_PINID='DQ(11)';
NODE_NAME     J6M1 23
 '@BASEBOARD_FAB2_LIB.BASEBOARD_FAB2(SCH_1):PAGE50_I158@MSTR_SCONN.SCONN288_H44441003(CHIPS)':
 'DQ'<10>: CDS_PINID='DQ(10)';
NET_NAME
'M_D_DQ<11>'
 '@BASEBOARD_FAB2_LIB.BASEBOARD_FAB2(SCH_1):M_D_DQ'<11>:
 C_SIGNAL='@baseboard_fab2_lib.baseboard_fab2(sch_1):m_d_dq(11)';
NODE_NAME     U5D1 DY83
 '@BASEBOARD_FAB2_LIB.BASEBOARD_FAB2(SCH_1):PAGE26_I172@CHPSET_LIB.SKX_EXT_B(CHIPS)':
 'DDR3_DQ'<11>: CDS_PINID='DDR3_DQ(11)';
NODE_NAME     J4B1 23
 '@BASEBOARD_FAB2_LIB.BASEBOARD_FAB2(SCH_1):PAGE49_I111@MSTR_SCONN.SCONN288_H44441004(CHIPS)':
 'DQ'<10>: CDS_PINID='DQ(10)';
NODE_NAME     J6M1 168
 '@BASEBOARD_FAB2_LIB.BASEBOARD_FAB2(SCH_1):PAGE50_I158@MSTR_SCONN.SCONN288_H44441003(CHIPS)':
 'DQ'<11>: CDS_PINID='DQ(11)';
NET_NAME
'M_D_DQ<12>'
 '@BASEBOARD_FAB2_LIB.BASEBOARD_FAB2(SCH_1):M_D_DQ'<12>:
 C_SIGNAL='@baseboard_fab2_lib.baseboard_fab2(sch_1):m_d_dq(12)';
NODE_NAME     U5D1 DD85
 '@BASEBOARD_FAB2_LIB.BASEBOARD_FAB2(SCH_1):PAGE26_I172@CHPSET_LIB.SKX_EXT_B(CHIPS)':
 'DDR3_DQ'<12>: CDS_PINID='DDR3_DQ(12)';
NODE_NAME     J4B1 159
 '@BASEBOARD_FAB2_LIB.BASEBOARD_FAB2(SCH_1):PAGE49_I111@MSTR_SCONN.SCONN288_H44441004(CHIPS)':
 'DQ'<13>: CDS_PINID='DQ(13)';
NODE_NAME     J6M1 14
 '@BASEBOARD_FAB2_LIB.BASEBOARD_FAB2(SCH_1):PAGE50_I158@MSTR_SCONN.SCONN288_H44441003(CHIPS)':
 'DQ'<12>: CDS_PINID='DQ(12)';
NET_NAME
'M_D_DQ<13>'
 '@BASEBOARD_FAB2_LIB.BASEBOARD_FAB2(SCH_1):M_D_DQ'<13>:
 C_SIGNAL='@baseboard_fab2_lib.baseboard_fab2(sch_1):m_d_dq(13)';
NODE_NAME     U5D1 DE84
 '@BASEBOARD_FAB2_LIB.BASEBOARD_FAB2(SCH_1):PAGE26_I172@CHPSET_LIB.SKX_EXT_B(CHIPS)':
 'DDR3_DQ'<13>: CDS_PINID='DDR3_DQ(13)';
NODE_NAME     J4B1 14
 '@BASEBOARD_FAB2_LIB.BASEBOARD_FAB2(SCH_1):PAGE49_I111@MSTR_SCONN.SCONN288_H44441004(CHIPS)':
 'DQ'<12>: CDS_PINID='DQ(12)';
NODE_NAME     J6M1 159
 '@BASEBOARD_FAB2_LIB.BASEBOARD_FAB2(SCH_1):PAGE50_I158@MSTR_SCONN.SCONN288_H44441003(CHIPS)':
 'DQ'<13>: CDS_PINID='DQ(13)';
NET_NAME
'M_D_DQ<14>'
 '@BASEBOARD_FAB2_LIB.BASEBOARD_FAB2(SCH_1):M_D_DQ'<14>:
 C_SIGNAL='@baseboard_fab2_lib.baseboard_fab2(sch_1):m_d_dq(14)';
NODE_NAME     U5D1 DR84
 '@BASEBOARD_FAB2_LIB.BASEBOARD_FAB2(SCH_1):PAGE26_I172@CHPSET_LIB.SKX_EXT_B(CHIPS)':
 'DDR3_DQ'<14>: CDS_PINID='DDR3_DQ(14)';
NODE_NAME     J4B1 166
 '@BASEBOARD_FAB2_LIB.BASEBOARD_FAB2(SCH_1):PAGE49_I111@MSTR_SCONN.SCONN288_H44441004(CHIPS)':
 'DQ'<15>: CDS_PINID='DQ(15)';
NODE_NAME     J6M1 21
 '@BASEBOARD_FAB2_LIB.BASEBOARD_FAB2(SCH_1):PAGE50_I158@MSTR_SCONN.SCONN288_H44441003(CHIPS)':
 'DQ'<14>: CDS_PINID='DQ(14)';
NET_NAME
'M_D_DQ<15>'
 '@BASEBOARD_FAB2_LIB.BASEBOARD_FAB2(SCH_1):M_D_DQ'<15>:
 C_SIGNAL='@baseboard_fab2_lib.baseboard_fab2(sch_1):m_d_dq(15)';
NODE_NAME     U5D1 DV85
 '@BASEBOARD_FAB2_LIB.BASEBOARD_FAB2(SCH_1):PAGE26_I172@CHPSET_LIB.SKX_EXT_B(CHIPS)':
 'DDR3_DQ'<15>: CDS_PINID='DDR3_DQ(15)';
NODE_NAME     J4B1 21
 '@BASEBOARD_FAB2_LIB.BASEBOARD_FAB2(SCH_1):PAGE49_I111@MSTR_SCONN.SCONN288_H44441004(CHIPS)':
 'DQ'<14>: CDS_PINID='DQ(14)';
NODE_NAME     J6M1 166
 '@BASEBOARD_FAB2_LIB.BASEBOARD_FAB2(SCH_1):PAGE50_I158@MSTR_SCONN.SCONN288_H44441003(CHIPS)':
 'DQ'<15>: CDS_PINID='DQ(15)';
NET_NAME
'M_D_DQ<16>'
 '@BASEBOARD_FAB2_LIB.BASEBOARD_FAB2(SCH_1):M_D_DQ'<16>:
 C_SIGNAL='@baseboard_fab2_lib.baseboard_fab2(sch_1):m_d_dq(16)';
NODE_NAME     U5D1 DM79
 '@BASEBOARD_FAB2_LIB.BASEBOARD_FAB2(SCH_1):PAGE26_I172@CHPSET_LIB.SKX_EXT_B(CHIPS)':
 'DDR3_DQ'<16>: CDS_PINID='DDR3_DQ(16)';
NODE_NAME     J4B1 172
 '@BASEBOARD_FAB2_LIB.BASEBOARD_FAB2(SCH_1):PAGE49_I111@MSTR_SCONN.SCONN288_H44441004(CHIPS)':
 'DQ'<17>: CDS_PINID='DQ(17)';
NODE_NAME     J6M1 27
 '@BASEBOARD_FAB2_LIB.BASEBOARD_FAB2(SCH_1):PAGE50_I158@MSTR_SCONN.SCONN288_H44441003(CHIPS)':
 'DQ'<16>: CDS_PINID='DQ(16)';
NET_NAME
'M_D_DQ<17>'
 '@BASEBOARD_FAB2_LIB.BASEBOARD_FAB2(SCH_1):M_D_DQ'<17>:
 C_SIGNAL='@baseboard_fab2_lib.baseboard_fab2(sch_1):m_d_dq(17)';
NODE_NAME     U5D1 DK81
 '@BASEBOARD_FAB2_LIB.BASEBOARD_FAB2(SCH_1):PAGE26_I172@CHPSET_LIB.SKX_EXT_B(CHIPS)':
 'DDR3_DQ'<17>: CDS_PINID='DDR3_DQ(17)';
NODE_NAME     J4B1 27
 '@BASEBOARD_FAB2_LIB.BASEBOARD_FAB2(SCH_1):PAGE49_I111@MSTR_SCONN.SCONN288_H44441004(CHIPS)':
 'DQ'<16>: CDS_PINID='DQ(16)';
NODE_NAME     J6M1 172
 '@BASEBOARD_FAB2_LIB.BASEBOARD_FAB2(SCH_1):PAGE50_I158@MSTR_SCONN.SCONN288_H44441003(CHIPS)':
 'DQ'<17>: CDS_PINID='DQ(17)';
NET_NAME
'M_D_DQ<18>'
 '@BASEBOARD_FAB2_LIB.BASEBOARD_FAB2(SCH_1):M_D_DQ'<18>:
 C_SIGNAL='@baseboard_fab2_lib.baseboard_fab2(sch_1):m_d_dq(18)';
NODE_NAME     U5D1 DT81
 '@BASEBOARD_FAB2_LIB.BASEBOARD_FAB2(SCH_1):PAGE26_I172@CHPSET_LIB.SKX_EXT_B(CHIPS)':
 'DDR3_DQ'<18>: CDS_PINID='DDR3_DQ(18)';
NODE_NAME     J4B1 179
 '@BASEBOARD_FAB2_LIB.BASEBOARD_FAB2(SCH_1):PAGE49_I111@MSTR_SCONN.SCONN288_H44441004(CHIPS)':
 'DQ'<19>: CDS_PINID='DQ(19)';
NODE_NAME     J6M1 34
 '@BASEBOARD_FAB2_LIB.BASEBOARD_FAB2(SCH_1):PAGE50_I158@MSTR_SCONN.SCONN288_H44441003(CHIPS)':
 'DQ'<18>: CDS_PINID='DQ(18)';
NET_NAME
'M_D_DQ<19>'
 '@BASEBOARD_FAB2_LIB.BASEBOARD_FAB2(SCH_1):M_D_DQ'<19>:
 C_SIGNAL='@baseboard_fab2_lib.baseboard_fab2(sch_1):m_d_dq(19)';
NODE_NAME     U5D1 DR82
 '@BASEBOARD_FAB2_LIB.BASEBOARD_FAB2(SCH_1):PAGE26_I172@CHPSET_LIB.SKX_EXT_B(CHIPS)':
 'DDR3_DQ'<19>: CDS_PINID='DDR3_DQ(19)';
NODE_NAME     J4B1 34
 '@BASEBOARD_FAB2_LIB.BASEBOARD_FAB2(SCH_1):PAGE49_I111@MSTR_SCONN.SCONN288_H44441004(CHIPS)':
 'DQ'<18>: CDS_PINID='DQ(18)';
NODE_NAME     J6M1 179
 '@BASEBOARD_FAB2_LIB.BASEBOARD_FAB2(SCH_1):PAGE50_I158@MSTR_SCONN.SCONN288_H44441003(CHIPS)':
 'DQ'<19>: CDS_PINID='DQ(19)';
NET_NAME
'M_D_DQ<1>'
 '@BASEBOARD_FAB2_LIB.BASEBOARD_FAB2(SCH_1):M_D_DQ'<1>:
 C_SIGNAL='@baseboard_fab2_lib.baseboard_fab2(sch_1):m_d_dq(1)';
NODE_NAME     U5D1 CN86
 '@BASEBOARD_FAB2_LIB.BASEBOARD_FAB2(SCH_1):PAGE26_I172@CHPSET_LIB.SKX_EXT_B(CHIPS)':
 'DDR3_DQ'<1>: CDS_PINID='DDR3_DQ(1)';
NODE_NAME     J4B1 5
 '@BASEBOARD_FAB2_LIB.BASEBOARD_FAB2(SCH_1):PAGE49_I111@MSTR_SCONN.SCONN288_H44441004(CHIPS)':
 'DQ'<0>: CDS_PINID='DQ(0)';
NODE_NAME     J6M1 150
 '@BASEBOARD_FAB2_LIB.BASEBOARD_FAB2(SCH_1):PAGE50_I158@MSTR_SCONN.SCONN288_H44441003(CHIPS)':
 'DQ'<1>: CDS_PINID='DQ(1)';
NET_NAME
'M_D_DQ<20>'
 '@BASEBOARD_FAB2_LIB.BASEBOARD_FAB2(SCH_1):M_D_DQ'<20>:
 C_SIGNAL='@baseboard_fab2_lib.baseboard_fab2(sch_1):m_d_dq(20)';
NODE_NAME     U5D1 DK79
 '@BASEBOARD_FAB2_LIB.BASEBOARD_FAB2(SCH_1):PAGE26_I172@CHPSET_LIB.SKX_EXT_B(CHIPS)':
 'DDR3_DQ'<20>: CDS_PINID='DDR3_DQ(20)';
NODE_NAME     J4B1 170
 '@BASEBOARD_FAB2_LIB.BASEBOARD_FAB2(SCH_1):PAGE49_I111@MSTR_SCONN.SCONN288_H44441004(CHIPS)':
 'DQ'<21>: CDS_PINID='DQ(21)';
NODE_NAME     J6M1 25
 '@BASEBOARD_FAB2_LIB.BASEBOARD_FAB2(SCH_1):PAGE50_I158@MSTR_SCONN.SCONN288_H44441003(CHIPS)':
 'DQ'<20>: CDS_PINID='DQ(20)';
NET_NAME
'M_D_DQ<21>'
 '@BASEBOARD_FAB2_LIB.BASEBOARD_FAB2(SCH_1):M_D_DQ'<21>:
 C_SIGNAL='@baseboard_fab2_lib.baseboard_fab2(sch_1):m_d_dq(21)';
NODE_NAME     U5D1 DJ80
 '@BASEBOARD_FAB2_LIB.BASEBOARD_FAB2(SCH_1):PAGE26_I172@CHPSET_LIB.SKX_EXT_B(CHIPS)':
 'DDR3_DQ'<21>: CDS_PINID='DDR3_DQ(21)';
NODE_NAME     J4B1 25
 '@BASEBOARD_FAB2_LIB.BASEBOARD_FAB2(SCH_1):PAGE49_I111@MSTR_SCONN.SCONN288_H44441004(CHIPS)':
 'DQ'<20>: CDS_PINID='DQ(20)';
NODE_NAME     J6M1 170
 '@BASEBOARD_FAB2_LIB.BASEBOARD_FAB2(SCH_1):PAGE50_I158@MSTR_SCONN.SCONN288_H44441003(CHIPS)':
 'DQ'<21>: CDS_PINID='DQ(21)';
NET_NAME
'M_D_DQ<22>'
 '@BASEBOARD_FAB2_LIB.BASEBOARD_FAB2(SCH_1):M_D_DQ'<22>:
 C_SIGNAL='@baseboard_fab2_lib.baseboard_fab2(sch_1):m_d_dq(22)';
NODE_NAME     U5D1 DR80
 '@BASEBOARD_FAB2_LIB.BASEBOARD_FAB2(SCH_1):PAGE26_I172@CHPSET_LIB.SKX_EXT_B(CHIPS)':
 'DDR3_DQ'<22>: CDS_PINID='DDR3_DQ(22)';
NODE_NAME     J4B1 177
 '@BASEBOARD_FAB2_LIB.BASEBOARD_FAB2(SCH_1):PAGE49_I111@MSTR_SCONN.SCONN288_H44441004(CHIPS)':
 'DQ'<23>: CDS_PINID='DQ(23)';
NODE_NAME     J6M1 32
 '@BASEBOARD_FAB2_LIB.BASEBOARD_FAB2(SCH_1):PAGE50_I158@MSTR_SCONN.SCONN288_H44441003(CHIPS)':
 'DQ'<22>: CDS_PINID='DQ(22)';
NET_NAME
'M_D_DQ<23>'
 '@BASEBOARD_FAB2_LIB.BASEBOARD_FAB2(SCH_1):M_D_DQ'<23>:
 C_SIGNAL='@baseboard_fab2_lib.baseboard_fab2(sch_1):m_d_dq(23)';
NODE_NAME     U5D1 DN82
 '@BASEBOARD_FAB2_LIB.BASEBOARD_FAB2(SCH_1):PAGE26_I172@CHPSET_LIB.SKX_EXT_B(CHIPS)':
 'DDR3_DQ'<23>: CDS_PINID='DDR3_DQ(23)';
NODE_NAME     J4B1 32
 '@BASEBOARD_FAB2_LIB.BASEBOARD_FAB2(SCH_1):PAGE49_I111@MSTR_SCONN.SCONN288_H44441004(CHIPS)':
 'DQ'<22>: CDS_PINID='DQ(22)';
NODE_NAME     J6M1 177
 '@BASEBOARD_FAB2_LIB.BASEBOARD_FAB2(SCH_1):PAGE50_I158@MSTR_SCONN.SCONN288_H44441003(CHIPS)':
 'DQ'<23>: CDS_PINID='DQ(23)';
NET_NAME
'M_D_DQ<24>'
 '@BASEBOARD_FAB2_LIB.BASEBOARD_FAB2(SCH_1):M_D_DQ'<24>:
 C_SIGNAL='@baseboard_fab2_lib.baseboard_fab2(sch_1):m_d_dq(24)';
NODE_NAME     U5D1 DN76
 '@BASEBOARD_FAB2_LIB.BASEBOARD_FAB2(SCH_1):PAGE26_I172@CHPSET_LIB.SKX_EXT_B(CHIPS)':
 'DDR3_DQ'<24>: CDS_PINID='DDR3_DQ(24)';
NODE_NAME     J4B1 183
 '@BASEBOARD_FAB2_LIB.BASEBOARD_FAB2(SCH_1):PAGE49_I111@MSTR_SCONN.SCONN288_H44441004(CHIPS)':
 'DQ'<25>: CDS_PINID='DQ(25)';
NODE_NAME     J6M1 38
 '@BASEBOARD_FAB2_LIB.BASEBOARD_FAB2(SCH_1):PAGE50_I158@MSTR_SCONN.SCONN288_H44441003(CHIPS)':
 'DQ'<24>: CDS_PINID='DQ(24)';
NET_NAME
'M_D_DQ<25>'
 '@BASEBOARD_FAB2_LIB.BASEBOARD_FAB2(SCH_1):M_D_DQ'<25>:
 C_SIGNAL='@baseboard_fab2_lib.baseboard_fab2(sch_1):m_d_dq(25)';
NODE_NAME     U5D1 DU76
 '@BASEBOARD_FAB2_LIB.BASEBOARD_FAB2(SCH_1):PAGE26_I172@CHPSET_LIB.SKX_EXT_B(CHIPS)':
 'DDR3_DQ'<25>: CDS_PINID='DDR3_DQ(25)';
NODE_NAME     J4B1 38
 '@BASEBOARD_FAB2_LIB.BASEBOARD_FAB2(SCH_1):PAGE49_I111@MSTR_SCONN.SCONN288_H44441004(CHIPS)':
 'DQ'<24>: CDS_PINID='DQ(24)';
NODE_NAME     J6M1 183
 '@BASEBOARD_FAB2_LIB.BASEBOARD_FAB2(SCH_1):PAGE50_I158@MSTR_SCONN.SCONN288_H44441003(CHIPS)':
 'DQ'<25>: CDS_PINID='DQ(25)';
NET_NAME
'M_D_DQ<26>'
 '@BASEBOARD_FAB2_LIB.BASEBOARD_FAB2(SCH_1):M_D_DQ'<26>:
 C_SIGNAL='@baseboard_fab2_lib.baseboard_fab2(sch_1):m_d_dq(26)';
NODE_NAME     U5D1 DP73
 '@BASEBOARD_FAB2_LIB.BASEBOARD_FAB2(SCH_1):PAGE26_I172@CHPSET_LIB.SKX_EXT_B(CHIPS)':
 'DDR3_DQ'<26>: CDS_PINID='DDR3_DQ(26)';
NODE_NAME     J4B1 190
 '@BASEBOARD_FAB2_LIB.BASEBOARD_FAB2(SCH_1):PAGE49_I111@MSTR_SCONN.SCONN288_H44441004(CHIPS)':
 'DQ'<27>: CDS_PINID='DQ(27)';
NODE_NAME     J6M1 45
 '@BASEBOARD_FAB2_LIB.BASEBOARD_FAB2(SCH_1):PAGE50_I158@MSTR_SCONN.SCONN288_H44441003(CHIPS)':
 'DQ'<26>: CDS_PINID='DQ(26)';
NET_NAME
'M_D_DQ<27>'
 '@BASEBOARD_FAB2_LIB.BASEBOARD_FAB2(SCH_1):M_D_DQ'<27>:
 C_SIGNAL='@baseboard_fab2_lib.baseboard_fab2(sch_1):m_d_dq(27)';
NODE_NAME     U5D1 DT73
 '@BASEBOARD_FAB2_LIB.BASEBOARD_FAB2(SCH_1):PAGE26_I172@CHPSET_LIB.SKX_EXT_B(CHIPS)':
 'DDR3_DQ'<27>: CDS_PINID='DDR3_DQ(27)';
NODE_NAME     J4B1 45
 '@BASEBOARD_FAB2_LIB.BASEBOARD_FAB2(SCH_1):PAGE49_I111@MSTR_SCONN.SCONN288_H44441004(CHIPS)':
 'DQ'<26>: CDS_PINID='DQ(26)';
NODE_NAME     J6M1 190
 '@BASEBOARD_FAB2_LIB.BASEBOARD_FAB2(SCH_1):PAGE50_I158@MSTR_SCONN.SCONN288_H44441003(CHIPS)':
 'DQ'<27>: CDS_PINID='DQ(27)';
NET_NAME
'M_D_DQ<28>'
 '@BASEBOARD_FAB2_LIB.BASEBOARD_FAB2(SCH_1):M_D_DQ'<28>:
 C_SIGNAL='@baseboard_fab2_lib.baseboard_fab2(sch_1):m_d_dq(28)';
NODE_NAME     U5D1 DP77
 '@BASEBOARD_FAB2_LIB.BASEBOARD_FAB2(SCH_1):PAGE26_I172@CHPSET_LIB.SKX_EXT_B(CHIPS)':
 'DDR3_DQ'<28>: CDS_PINID='DDR3_DQ(28)';
NODE_NAME     J4B1 181
 '@BASEBOARD_FAB2_LIB.BASEBOARD_FAB2(SCH_1):PAGE49_I111@MSTR_SCONN.SCONN288_H44441004(CHIPS)':
 'DQ'<29>: CDS_PINID='DQ(29)';
NODE_NAME     J6M1 36
 '@BASEBOARD_FAB2_LIB.BASEBOARD_FAB2(SCH_1):PAGE50_I158@MSTR_SCONN.SCONN288_H44441003(CHIPS)':
 'DQ'<28>: CDS_PINID='DQ(28)';
NET_NAME
'M_D_DQ<29>'
 '@BASEBOARD_FAB2_LIB.BASEBOARD_FAB2(SCH_1):M_D_DQ'<29>:
 C_SIGNAL='@baseboard_fab2_lib.baseboard_fab2(sch_1):m_d_dq(29)';
NODE_NAME     U5D1 DT77
 '@BASEBOARD_FAB2_LIB.BASEBOARD_FAB2(SCH_1):PAGE26_I172@CHPSET_LIB.SKX_EXT_B(CHIPS)':
 'DDR3_DQ'<29>: CDS_PINID='DDR3_DQ(29)';
NODE_NAME     J4B1 36
 '@BASEBOARD_FAB2_LIB.BASEBOARD_FAB2(SCH_1):PAGE49_I111@MSTR_SCONN.SCONN288_H44441004(CHIPS)':
 'DQ'<28>: CDS_PINID='DQ(28)';
NODE_NAME     J6M1 181
 '@BASEBOARD_FAB2_LIB.BASEBOARD_FAB2(SCH_1):PAGE50_I158@MSTR_SCONN.SCONN288_H44441003(CHIPS)':
 'DQ'<29>: CDS_PINID='DQ(29)';
NET_NAME
'M_D_DQ<2>'
 '@BASEBOARD_FAB2_LIB.BASEBOARD_FAB2(SCH_1):M_D_DQ'<2>:
 C_SIGNAL='@baseboard_fab2_lib.baseboard_fab2(sch_1):m_d_dq(2)';
NODE_NAME     U5D1 DA86
 '@BASEBOARD_FAB2_LIB.BASEBOARD_FAB2(SCH_1):PAGE26_I172@CHPSET_LIB.SKX_EXT_B(CHIPS)':
 'DDR3_DQ'<2>: CDS_PINID='DDR3_DQ(2)';
NODE_NAME     J4B1 157
 '@BASEBOARD_FAB2_LIB.BASEBOARD_FAB2(SCH_1):PAGE49_I111@MSTR_SCONN.SCONN288_H44441004(CHIPS)':
 'DQ'<3>: CDS_PINID='DQ(3)';
NODE_NAME     J6M1 12
 '@BASEBOARD_FAB2_LIB.BASEBOARD_FAB2(SCH_1):PAGE50_I158@MSTR_SCONN.SCONN288_H44441003(CHIPS)':
 'DQ'<2>: CDS_PINID='DQ(2)';
NET_NAME
'M_D_DQ<30>'
 '@BASEBOARD_FAB2_LIB.BASEBOARD_FAB2(SCH_1):M_D_DQ'<30>:
 C_SIGNAL='@baseboard_fab2_lib.baseboard_fab2(sch_1):m_d_dq(30)';
NODE_NAME     U5D1 DN74
 '@BASEBOARD_FAB2_LIB.BASEBOARD_FAB2(SCH_1):PAGE26_I172@CHPSET_LIB.SKX_EXT_B(CHIPS)':
 'DDR3_DQ'<30>: CDS_PINID='DDR3_DQ(30)';
NODE_NAME     J4B1 188
 '@BASEBOARD_FAB2_LIB.BASEBOARD_FAB2(SCH_1):PAGE49_I111@MSTR_SCONN.SCONN288_H44441004(CHIPS)':
 'DQ'<31>: CDS_PINID='DQ(31)';
NODE_NAME     J6M1 43
 '@BASEBOARD_FAB2_LIB.BASEBOARD_FAB2(SCH_1):PAGE50_I158@MSTR_SCONN.SCONN288_H44441003(CHIPS)':
 'DQ'<30>: CDS_PINID='DQ(30)';
NET_NAME
'M_D_DQ<31>'
 '@BASEBOARD_FAB2_LIB.BASEBOARD_FAB2(SCH_1):M_D_DQ'<31>:
 C_SIGNAL='@baseboard_fab2_lib.baseboard_fab2(sch_1):m_d_dq(31)';
NODE_NAME     U5D1 DU74
 '@BASEBOARD_FAB2_LIB.BASEBOARD_FAB2(SCH_1):PAGE26_I172@CHPSET_LIB.SKX_EXT_B(CHIPS)':
 'DDR3_DQ'<31>: CDS_PINID='DDR3_DQ(31)';
NODE_NAME     J4B1 43
 '@BASEBOARD_FAB2_LIB.BASEBOARD_FAB2(SCH_1):PAGE49_I111@MSTR_SCONN.SCONN288_H44441004(CHIPS)':
 'DQ'<30>: CDS_PINID='DQ(30)';
NODE_NAME     J6M1 188
 '@BASEBOARD_FAB2_LIB.BASEBOARD_FAB2(SCH_1):PAGE50_I158@MSTR_SCONN.SCONN288_H44441003(CHIPS)':
 'DQ'<31>: CDS_PINID='DQ(31)';
NET_NAME
'M_D_DQ<32>'
 '@BASEBOARD_FAB2_LIB.BASEBOARD_FAB2(SCH_1):M_D_DQ'<32>:
 C_SIGNAL='@baseboard_fab2_lib.baseboard_fab2(sch_1):m_d_dq(32)';
NODE_NAME     U5D1 EC40
 '@BASEBOARD_FAB2_LIB.BASEBOARD_FAB2(SCH_1):PAGE26_I172@CHPSET_LIB.SKX_EXT_B(CHIPS)':
 'DDR3_DQ'<32>: CDS_PINID='DDR3_DQ(32)';
NODE_NAME     J4B1 242
 '@BASEBOARD_FAB2_LIB.BASEBOARD_FAB2(SCH_1):PAGE49_I111@MSTR_SCONN.SCONN288_H44441004(CHIPS)':
 'DQ'<33>: CDS_PINID='DQ(33)';
NODE_NAME     J6M1 97
 '@BASEBOARD_FAB2_LIB.BASEBOARD_FAB2(SCH_1):PAGE50_I158@MSTR_SCONN.SCONN288_H44441003(CHIPS)':
 'DQ'<32>: CDS_PINID='DQ(32)';
NET_NAME
'M_D_DQ<33>'
 '@BASEBOARD_FAB2_LIB.BASEBOARD_FAB2(SCH_1):M_D_DQ'<33>:
 C_SIGNAL='@baseboard_fab2_lib.baseboard_fab2(sch_1):m_d_dq(33)';
NODE_NAME     U5D1 ED39
 '@BASEBOARD_FAB2_LIB.BASEBOARD_FAB2(SCH_1):PAGE26_I172@CHPSET_LIB.SKX_EXT_B(CHIPS)':
 'DDR3_DQ'<33>: CDS_PINID='DDR3_DQ(33)';
NODE_NAME     J4B1 97
 '@BASEBOARD_FAB2_LIB.BASEBOARD_FAB2(SCH_1):PAGE49_I111@MSTR_SCONN.SCONN288_H44441004(CHIPS)':
 'DQ'<32>: CDS_PINID='DQ(32)';
NODE_NAME     J6M1 242
 '@BASEBOARD_FAB2_LIB.BASEBOARD_FAB2(SCH_1):PAGE50_I158@MSTR_SCONN.SCONN288_H44441003(CHIPS)':
 'DQ'<33>: CDS_PINID='DQ(33)';
NET_NAME
'M_D_DQ<34>'
 '@BASEBOARD_FAB2_LIB.BASEBOARD_FAB2(SCH_1):M_D_DQ'<34>:
 C_SIGNAL='@baseboard_fab2_lib.baseboard_fab2(sch_1):m_d_dq(34)';
NODE_NAME     U5D1 EA36
 '@BASEBOARD_FAB2_LIB.BASEBOARD_FAB2(SCH_1):PAGE26_I172@CHPSET_LIB.SKX_EXT_B(CHIPS)':
 'DDR3_DQ'<34>: CDS_PINID='DDR3_DQ(34)';
NODE_NAME     J4B1 249
 '@BASEBOARD_FAB2_LIB.BASEBOARD_FAB2(SCH_1):PAGE49_I111@MSTR_SCONN.SCONN288_H44441004(CHIPS)':
 'DQ'<35>: CDS_PINID='DQ(35)';
NODE_NAME     J6M1 104
 '@BASEBOARD_FAB2_LIB.BASEBOARD_FAB2(SCH_1):PAGE50_I158@MSTR_SCONN.SCONN288_H44441003(CHIPS)':
 'DQ'<34>: CDS_PINID='DQ(34)';
NET_NAME
'M_D_DQ<35>'
 '@BASEBOARD_FAB2_LIB.BASEBOARD_FAB2(SCH_1):M_D_DQ'<35>:
 C_SIGNAL='@baseboard_fab2_lib.baseboard_fab2(sch_1):m_d_dq(35)';
NODE_NAME     U5D1 EC36
 '@BASEBOARD_FAB2_LIB.BASEBOARD_FAB2(SCH_1):PAGE26_I172@CHPSET_LIB.SKX_EXT_B(CHIPS)':
 'DDR3_DQ'<35>: CDS_PINID='DDR3_DQ(35)';
NODE_NAME     J4B1 104
 '@BASEBOARD_FAB2_LIB.BASEBOARD_FAB2(SCH_1):PAGE49_I111@MSTR_SCONN.SCONN288_H44441004(CHIPS)':
 'DQ'<34>: CDS_PINID='DQ(34)';
NODE_NAME     J6M1 249
 '@BASEBOARD_FAB2_LIB.BASEBOARD_FAB2(SCH_1):PAGE50_I158@MSTR_SCONN.SCONN288_H44441003(CHIPS)':
 'DQ'<35>: CDS_PINID='DQ(35)';
NET_NAME
'M_D_DQ<36>'
 '@BASEBOARD_FAB2_LIB.BASEBOARD_FAB2(SCH_1):M_D_DQ'<36>:
 C_SIGNAL='@baseboard_fab2_lib.baseboard_fab2(sch_1):m_d_dq(36)';
NODE_NAME     U5D1 DY39
 '@BASEBOARD_FAB2_LIB.BASEBOARD_FAB2(SCH_1):PAGE26_I172@CHPSET_LIB.SKX_EXT_B(CHIPS)':
 'DDR3_DQ'<36>: CDS_PINID='DDR3_DQ(36)';
NODE_NAME     J4B1 240
 '@BASEBOARD_FAB2_LIB.BASEBOARD_FAB2(SCH_1):PAGE49_I111@MSTR_SCONN.SCONN288_H44441004(CHIPS)':
 'DQ'<37>: CDS_PINID='DQ(37)';
NODE_NAME     J6M1 95
 '@BASEBOARD_FAB2_LIB.BASEBOARD_FAB2(SCH_1):PAGE50_I158@MSTR_SCONN.SCONN288_H44441003(CHIPS)':
 'DQ'<36>: CDS_PINID='DQ(36)';
NET_NAME
'M_D_DQ<37>'
 '@BASEBOARD_FAB2_LIB.BASEBOARD_FAB2(SCH_1):M_D_DQ'<37>:
 C_SIGNAL='@baseboard_fab2_lib.baseboard_fab2(sch_1):m_d_dq(37)';
NODE_NAME     U5D1 EA40
 '@BASEBOARD_FAB2_LIB.BASEBOARD_FAB2(SCH_1):PAGE26_I172@CHPSET_LIB.SKX_EXT_B(CHIPS)':
 'DDR3_DQ'<37>: CDS_PINID='DDR3_DQ(37)';
NODE_NAME     J4B1 95
 '@BASEBOARD_FAB2_LIB.BASEBOARD_FAB2(SCH_1):PAGE49_I111@MSTR_SCONN.SCONN288_H44441004(CHIPS)':
 'DQ'<36>: CDS_PINID='DQ(36)';
NODE_NAME     J6M1 240
 '@BASEBOARD_FAB2_LIB.BASEBOARD_FAB2(SCH_1):PAGE50_I158@MSTR_SCONN.SCONN288_H44441003(CHIPS)':
 'DQ'<37>: CDS_PINID='DQ(37)';
NET_NAME
'M_D_DQ<38>'
 '@BASEBOARD_FAB2_LIB.BASEBOARD_FAB2(SCH_1):M_D_DQ'<38>:
 C_SIGNAL='@baseboard_fab2_lib.baseboard_fab2(sch_1):m_d_dq(38)';
NODE_NAME     U5D1 DY37
 '@BASEBOARD_FAB2_LIB.BASEBOARD_FAB2(SCH_1):PAGE26_I172@CHPSET_LIB.SKX_EXT_B(CHIPS)':
 'DDR3_DQ'<38>: CDS_PINID='DDR3_DQ(38)';
NODE_NAME     J4B1 247
 '@BASEBOARD_FAB2_LIB.BASEBOARD_FAB2(SCH_1):PAGE49_I111@MSTR_SCONN.SCONN288_H44441004(CHIPS)':
 'DQ'<39>: CDS_PINID='DQ(39)';
NODE_NAME     J6M1 102
 '@BASEBOARD_FAB2_LIB.BASEBOARD_FAB2(SCH_1):PAGE50_I158@MSTR_SCONN.SCONN288_H44441003(CHIPS)':
 'DQ'<38>: CDS_PINID='DQ(38)';
NET_NAME
'M_D_DQ<39>'
 '@BASEBOARD_FAB2_LIB.BASEBOARD_FAB2(SCH_1):M_D_DQ'<39>:
 C_SIGNAL='@baseboard_fab2_lib.baseboard_fab2(sch_1):m_d_dq(39)';
NODE_NAME     U5D1 ED37
 '@BASEBOARD_FAB2_LIB.BASEBOARD_FAB2(SCH_1):PAGE26_I172@CHPSET_LIB.SKX_EXT_B(CHIPS)':
 'DDR3_DQ'<39>: CDS_PINID='DDR3_DQ(39)';
NODE_NAME     J4B1 102
 '@BASEBOARD_FAB2_LIB.BASEBOARD_FAB2(SCH_1):PAGE49_I111@MSTR_SCONN.SCONN288_H44441004(CHIPS)':
 'DQ'<38>: CDS_PINID='DQ(38)';
NODE_NAME     J6M1 247
 '@BASEBOARD_FAB2_LIB.BASEBOARD_FAB2(SCH_1):PAGE50_I158@MSTR_SCONN.SCONN288_H44441003(CHIPS)':
 'DQ'<39>: CDS_PINID='DQ(39)';
NET_NAME
'M_D_DQ<3>'
 '@BASEBOARD_FAB2_LIB.BASEBOARD_FAB2(SCH_1):M_D_DQ'<3>:
 C_SIGNAL='@baseboard_fab2_lib.baseboard_fab2(sch_1):m_d_dq(3)';
NODE_NAME     U5D1 DA84
 '@BASEBOARD_FAB2_LIB.BASEBOARD_FAB2(SCH_1):PAGE26_I172@CHPSET_LIB.SKX_EXT_B(CHIPS)':
 'DDR3_DQ'<3>: CDS_PINID='DDR3_DQ(3)';
NODE_NAME     J4B1 12
 '@BASEBOARD_FAB2_LIB.BASEBOARD_FAB2(SCH_1):PAGE49_I111@MSTR_SCONN.SCONN288_H44441004(CHIPS)':
 'DQ'<2>: CDS_PINID='DQ(2)';
NODE_NAME     J6M1 157
 '@BASEBOARD_FAB2_LIB.BASEBOARD_FAB2(SCH_1):PAGE50_I158@MSTR_SCONN.SCONN288_H44441003(CHIPS)':
 'DQ'<3>: CDS_PINID='DQ(3)';
NET_NAME
'M_D_DQ<40>'
 '@BASEBOARD_FAB2_LIB.BASEBOARD_FAB2(SCH_1):M_D_DQ'<40>:
 C_SIGNAL='@baseboard_fab2_lib.baseboard_fab2(sch_1):m_d_dq(40)';
NODE_NAME     U5D1 DN36
 '@BASEBOARD_FAB2_LIB.BASEBOARD_FAB2(SCH_1):PAGE26_I172@CHPSET_LIB.SKX_EXT_B(CHIPS)':
 'DDR3_DQ'<40>: CDS_PINID='DDR3_DQ(40)';
NODE_NAME     J4B1 253
 '@BASEBOARD_FAB2_LIB.BASEBOARD_FAB2(SCH_1):PAGE49_I111@MSTR_SCONN.SCONN288_H44441004(CHIPS)':
 'DQ'<41>: CDS_PINID='DQ(41)';
NODE_NAME     J6M1 108
 '@BASEBOARD_FAB2_LIB.BASEBOARD_FAB2(SCH_1):PAGE50_I158@MSTR_SCONN.SCONN288_H44441003(CHIPS)':
 'DQ'<40>: CDS_PINID='DQ(40)';
NET_NAME
'M_D_DQ<41>'
 '@BASEBOARD_FAB2_LIB.BASEBOARD_FAB2(SCH_1):M_D_DQ'<41>:
 C_SIGNAL='@baseboard_fab2_lib.baseboard_fab2(sch_1):m_d_dq(41)';
NODE_NAME     U5D1 DU36
 '@BASEBOARD_FAB2_LIB.BASEBOARD_FAB2(SCH_1):PAGE26_I172@CHPSET_LIB.SKX_EXT_B(CHIPS)':
 'DDR3_DQ'<41>: CDS_PINID='DDR3_DQ(41)';
NODE_NAME     J4B1 108
 '@BASEBOARD_FAB2_LIB.BASEBOARD_FAB2(SCH_1):PAGE49_I111@MSTR_SCONN.SCONN288_H44441004(CHIPS)':
 'DQ'<40>: CDS_PINID='DQ(40)';
NODE_NAME     J6M1 253
 '@BASEBOARD_FAB2_LIB.BASEBOARD_FAB2(SCH_1):PAGE50_I158@MSTR_SCONN.SCONN288_H44441003(CHIPS)':
 'DQ'<41>: CDS_PINID='DQ(41)';
NET_NAME
'M_D_DQ<42>'
 '@BASEBOARD_FAB2_LIB.BASEBOARD_FAB2(SCH_1):M_D_DQ'<42>:
 C_SIGNAL='@baseboard_fab2_lib.baseboard_fab2(sch_1):m_d_dq(42)';
NODE_NAME     U5D1 DP33
 '@BASEBOARD_FAB2_LIB.BASEBOARD_FAB2(SCH_1):PAGE26_I172@CHPSET_LIB.SKX_EXT_B(CHIPS)':
 'DDR3_DQ'<42>: CDS_PINID='DDR3_DQ(42)';
NODE_NAME     J4B1 260
 '@BASEBOARD_FAB2_LIB.BASEBOARD_FAB2(SCH_1):PAGE49_I111@MSTR_SCONN.SCONN288_H44441004(CHIPS)':
 'DQ'<43>: CDS_PINID='DQ(43)';
NODE_NAME     J6M1 115
 '@BASEBOARD_FAB2_LIB.BASEBOARD_FAB2(SCH_1):PAGE50_I158@MSTR_SCONN.SCONN288_H44441003(CHIPS)':
 'DQ'<42>: CDS_PINID='DQ(42)';
NET_NAME
'M_D_DQ<43>'
 '@BASEBOARD_FAB2_LIB.BASEBOARD_FAB2(SCH_1):M_D_DQ'<43>:
 C_SIGNAL='@baseboard_fab2_lib.baseboard_fab2(sch_1):m_d_dq(43)';
NODE_NAME     U5D1 DT33
 '@BASEBOARD_FAB2_LIB.BASEBOARD_FAB2(SCH_1):PAGE26_I172@CHPSET_LIB.SKX_EXT_B(CHIPS)':
 'DDR3_DQ'<43>: CDS_PINID='DDR3_DQ(43)';
NODE_NAME     J4B1 115
 '@BASEBOARD_FAB2_LIB.BASEBOARD_FAB2(SCH_1):PAGE49_I111@MSTR_SCONN.SCONN288_H44441004(CHIPS)':
 'DQ'<42>: CDS_PINID='DQ(42)';
NODE_NAME     J6M1 260
 '@BASEBOARD_FAB2_LIB.BASEBOARD_FAB2(SCH_1):PAGE50_I158@MSTR_SCONN.SCONN288_H44441003(CHIPS)':
 'DQ'<43>: CDS_PINID='DQ(43)';
NET_NAME
'M_D_DQ<44>'
 '@BASEBOARD_FAB2_LIB.BASEBOARD_FAB2(SCH_1):M_D_DQ'<44>:
 C_SIGNAL='@baseboard_fab2_lib.baseboard_fab2(sch_1):m_d_dq(44)';
NODE_NAME     U5D1 DP37
 '@BASEBOARD_FAB2_LIB.BASEBOARD_FAB2(SCH_1):PAGE26_I172@CHPSET_LIB.SKX_EXT_B(CHIPS)':
 'DDR3_DQ'<44>: CDS_PINID='DDR3_DQ(44)';
NODE_NAME     J4B1 251
 '@BASEBOARD_FAB2_LIB.BASEBOARD_FAB2(SCH_1):PAGE49_I111@MSTR_SCONN.SCONN288_H44441004(CHIPS)':
 'DQ'<45>: CDS_PINID='DQ(45)';
NODE_NAME     J6M1 106
 '@BASEBOARD_FAB2_LIB.BASEBOARD_FAB2(SCH_1):PAGE50_I158@MSTR_SCONN.SCONN288_H44441003(CHIPS)':
 'DQ'<44>: CDS_PINID='DQ(44)';
NET_NAME
'M_D_DQ<45>'
 '@BASEBOARD_FAB2_LIB.BASEBOARD_FAB2(SCH_1):M_D_DQ'<45>:
 C_SIGNAL='@baseboard_fab2_lib.baseboard_fab2(sch_1):m_d_dq(45)';
NODE_NAME     U5D1 DT37
 '@BASEBOARD_FAB2_LIB.BASEBOARD_FAB2(SCH_1):PAGE26_I172@CHPSET_LIB.SKX_EXT_B(CHIPS)':
 'DDR3_DQ'<45>: CDS_PINID='DDR3_DQ(45)';
NODE_NAME     J4B1 106
 '@BASEBOARD_FAB2_LIB.BASEBOARD_FAB2(SCH_1):PAGE49_I111@MSTR_SCONN.SCONN288_H44441004(CHIPS)':
 'DQ'<44>: CDS_PINID='DQ(44)';
NODE_NAME     J6M1 251
 '@BASEBOARD_FAB2_LIB.BASEBOARD_FAB2(SCH_1):PAGE50_I158@MSTR_SCONN.SCONN288_H44441003(CHIPS)':
 'DQ'<45>: CDS_PINID='DQ(45)';
NET_NAME
'M_D_DQ<46>'
 '@BASEBOARD_FAB2_LIB.BASEBOARD_FAB2(SCH_1):M_D_DQ'<46>:
 C_SIGNAL='@baseboard_fab2_lib.baseboard_fab2(sch_1):m_d_dq(46)';
NODE_NAME     U5D1 DN34
 '@BASEBOARD_FAB2_LIB.BASEBOARD_FAB2(SCH_1):PAGE26_I172@CHPSET_LIB.SKX_EXT_B(CHIPS)':
 'DDR3_DQ'<46>: CDS_PINID='DDR3_DQ(46)';
NODE_NAME     J4B1 258
 '@BASEBOARD_FAB2_LIB.BASEBOARD_FAB2(SCH_1):PAGE49_I111@MSTR_SCONN.SCONN288_H44441004(CHIPS)':
 'DQ'<47>: CDS_PINID='DQ(47)';
NODE_NAME     J6M1 113
 '@BASEBOARD_FAB2_LIB.BASEBOARD_FAB2(SCH_1):PAGE50_I158@MSTR_SCONN.SCONN288_H44441003(CHIPS)':
 'DQ'<46>: CDS_PINID='DQ(46)';
NET_NAME
'M_D_DQ<47>'
 '@BASEBOARD_FAB2_LIB.BASEBOARD_FAB2(SCH_1):M_D_DQ'<47>:
 C_SIGNAL='@baseboard_fab2_lib.baseboard_fab2(sch_1):m_d_dq(47)';
NODE_NAME     U5D1 DU34
 '@BASEBOARD_FAB2_LIB.BASEBOARD_FAB2(SCH_1):PAGE26_I172@CHPSET_LIB.SKX_EXT_B(CHIPS)':
 'DDR3_DQ'<47>: CDS_PINID='DDR3_DQ(47)';
NODE_NAME     J4B1 113
 '@BASEBOARD_FAB2_LIB.BASEBOARD_FAB2(SCH_1):PAGE49_I111@MSTR_SCONN.SCONN288_H44441004(CHIPS)':
 'DQ'<46>: CDS_PINID='DQ(46)';
NODE_NAME     J6M1 258
 '@BASEBOARD_FAB2_LIB.BASEBOARD_FAB2(SCH_1):PAGE50_I158@MSTR_SCONN.SCONN288_H44441003(CHIPS)':
 'DQ'<47>: CDS_PINID='DQ(47)';
NET_NAME
'M_D_DQ<48>'
 '@BASEBOARD_FAB2_LIB.BASEBOARD_FAB2(SCH_1):M_D_DQ'<48>:
 C_SIGNAL='@baseboard_fab2_lib.baseboard_fab2(sch_1):m_d_dq(48)';
NODE_NAME     U5D1 DN30
 '@BASEBOARD_FAB2_LIB.BASEBOARD_FAB2(SCH_1):PAGE26_I172@CHPSET_LIB.SKX_EXT_B(CHIPS)':
 'DDR3_DQ'<48>: CDS_PINID='DDR3_DQ(48)';
NODE_NAME     J4B1 264
 '@BASEBOARD_FAB2_LIB.BASEBOARD_FAB2(SCH_1):PAGE49_I111@MSTR_SCONN.SCONN288_H44441004(CHIPS)':
 'DQ'<49>: CDS_PINID='DQ(49)';
NODE_NAME     J6M1 119
 '@BASEBOARD_FAB2_LIB.BASEBOARD_FAB2(SCH_1):PAGE50_I158@MSTR_SCONN.SCONN288_H44441003(CHIPS)':
 'DQ'<48>: CDS_PINID='DQ(48)';
NET_NAME
'M_D_DQ<49>'
 '@BASEBOARD_FAB2_LIB.BASEBOARD_FAB2(SCH_1):M_D_DQ'<49>:
 C_SIGNAL='@baseboard_fab2_lib.baseboard_fab2(sch_1):m_d_dq(49)';
NODE_NAME     U5D1 DU30
 '@BASEBOARD_FAB2_LIB.BASEBOARD_FAB2(SCH_1):PAGE26_I172@CHPSET_LIB.SKX_EXT_B(CHIPS)':
 'DDR3_DQ'<49>: CDS_PINID='DDR3_DQ(49)';
NODE_NAME     J4B1 119
 '@BASEBOARD_FAB2_LIB.BASEBOARD_FAB2(SCH_1):PAGE49_I111@MSTR_SCONN.SCONN288_H44441004(CHIPS)':
 'DQ'<48>: CDS_PINID='DQ(48)';
NODE_NAME     J6M1 264
 '@BASEBOARD_FAB2_LIB.BASEBOARD_FAB2(SCH_1):PAGE50_I158@MSTR_SCONN.SCONN288_H44441003(CHIPS)':
 'DQ'<49>: CDS_PINID='DQ(49)';
NET_NAME
'M_D_DQ<4>'
 '@BASEBOARD_FAB2_LIB.BASEBOARD_FAB2(SCH_1):M_D_DQ'<4>:
 C_SIGNAL='@baseboard_fab2_lib.baseboard_fab2(sch_1):m_d_dq(4)';
NODE_NAME     U5D1 CL84
 '@BASEBOARD_FAB2_LIB.BASEBOARD_FAB2(SCH_1):PAGE26_I172@CHPSET_LIB.SKX_EXT_B(CHIPS)':
 'DDR3_DQ'<4>: CDS_PINID='DDR3_DQ(4)';
NODE_NAME     J4B1 148
 '@BASEBOARD_FAB2_LIB.BASEBOARD_FAB2(SCH_1):PAGE49_I111@MSTR_SCONN.SCONN288_H44441004(CHIPS)':
 'DQ'<5>: CDS_PINID='DQ(5)';
NODE_NAME     J6M1 3
 '@BASEBOARD_FAB2_LIB.BASEBOARD_FAB2(SCH_1):PAGE50_I158@MSTR_SCONN.SCONN288_H44441003(CHIPS)':
 'DQ'<4>: CDS_PINID='DQ(4)';
NET_NAME
'M_D_DQ<50>'
 '@BASEBOARD_FAB2_LIB.BASEBOARD_FAB2(SCH_1):M_D_DQ'<50>:
 C_SIGNAL='@baseboard_fab2_lib.baseboard_fab2(sch_1):m_d_dq(50)';
NODE_NAME     U5D1 DP27
 '@BASEBOARD_FAB2_LIB.BASEBOARD_FAB2(SCH_1):PAGE26_I172@CHPSET_LIB.SKX_EXT_B(CHIPS)':
 'DDR3_DQ'<50>: CDS_PINID='DDR3_DQ(50)';
NODE_NAME     J4B1 271
 '@BASEBOARD_FAB2_LIB.BASEBOARD_FAB2(SCH_1):PAGE49_I111@MSTR_SCONN.SCONN288_H44441004(CHIPS)':
 'DQ'<51>: CDS_PINID='DQ(51)';
NODE_NAME     J6M1 126
 '@BASEBOARD_FAB2_LIB.BASEBOARD_FAB2(SCH_1):PAGE50_I158@MSTR_SCONN.SCONN288_H44441003(CHIPS)':
 'DQ'<50>: CDS_PINID='DQ(50)';
NET_NAME
'M_D_DQ<51>'
 '@BASEBOARD_FAB2_LIB.BASEBOARD_FAB2(SCH_1):M_D_DQ'<51>:
 C_SIGNAL='@baseboard_fab2_lib.baseboard_fab2(sch_1):m_d_dq(51)';
NODE_NAME     U5D1 DT27
 '@BASEBOARD_FAB2_LIB.BASEBOARD_FAB2(SCH_1):PAGE26_I172@CHPSET_LIB.SKX_EXT_B(CHIPS)':
 'DDR3_DQ'<51>: CDS_PINID='DDR3_DQ(51)';
NODE_NAME     J4B1 126
 '@BASEBOARD_FAB2_LIB.BASEBOARD_FAB2(SCH_1):PAGE49_I111@MSTR_SCONN.SCONN288_H44441004(CHIPS)':
 'DQ'<50>: CDS_PINID='DQ(50)';
NODE_NAME     J6M1 271
 '@BASEBOARD_FAB2_LIB.BASEBOARD_FAB2(SCH_1):PAGE50_I158@MSTR_SCONN.SCONN288_H44441003(CHIPS)':
 'DQ'<51>: CDS_PINID='DQ(51)';
NET_NAME
'M_D_DQ<52>'
 '@BASEBOARD_FAB2_LIB.BASEBOARD_FAB2(SCH_1):M_D_DQ'<52>:
 C_SIGNAL='@baseboard_fab2_lib.baseboard_fab2(sch_1):m_d_dq(52)';
NODE_NAME     U5D1 DP31
 '@BASEBOARD_FAB2_LIB.BASEBOARD_FAB2(SCH_1):PAGE26_I172@CHPSET_LIB.SKX_EXT_B(CHIPS)':
 'DDR3_DQ'<52>: CDS_PINID='DDR3_DQ(52)';
NODE_NAME     J4B1 262
 '@BASEBOARD_FAB2_LIB.BASEBOARD_FAB2(SCH_1):PAGE49_I111@MSTR_SCONN.SCONN288_H44441004(CHIPS)':
 'DQ'<53>: CDS_PINID='DQ(53)';
NODE_NAME     J6M1 117
 '@BASEBOARD_FAB2_LIB.BASEBOARD_FAB2(SCH_1):PAGE50_I158@MSTR_SCONN.SCONN288_H44441003(CHIPS)':
 'DQ'<52>: CDS_PINID='DQ(52)';
NET_NAME
'M_D_DQ<53>'
 '@BASEBOARD_FAB2_LIB.BASEBOARD_FAB2(SCH_1):M_D_DQ'<53>:
 C_SIGNAL='@baseboard_fab2_lib.baseboard_fab2(sch_1):m_d_dq(53)';
NODE_NAME     U5D1 DT31
 '@BASEBOARD_FAB2_LIB.BASEBOARD_FAB2(SCH_1):PAGE26_I172@CHPSET_LIB.SKX_EXT_B(CHIPS)':
 'DDR3_DQ'<53>: CDS_PINID='DDR3_DQ(53)';
NODE_NAME     J4B1 117
 '@BASEBOARD_FAB2_LIB.BASEBOARD_FAB2(SCH_1):PAGE49_I111@MSTR_SCONN.SCONN288_H44441004(CHIPS)':
 'DQ'<52>: CDS_PINID='DQ(52)';
NODE_NAME     J6M1 262
 '@BASEBOARD_FAB2_LIB.BASEBOARD_FAB2(SCH_1):PAGE50_I158@MSTR_SCONN.SCONN288_H44441003(CHIPS)':
 'DQ'<53>: CDS_PINID='DQ(53)';
NET_NAME
'M_D_DQ<54>'
 '@BASEBOARD_FAB2_LIB.BASEBOARD_FAB2(SCH_1):M_D_DQ'<54>:
 C_SIGNAL='@baseboard_fab2_lib.baseboard_fab2(sch_1):m_d_dq(54)';
NODE_NAME     U5D1 DN28
 '@BASEBOARD_FAB2_LIB.BASEBOARD_FAB2(SCH_1):PAGE26_I172@CHPSET_LIB.SKX_EXT_B(CHIPS)':
 'DDR3_DQ'<54>: CDS_PINID='DDR3_DQ(54)';
NODE_NAME     J4B1 269
 '@BASEBOARD_FAB2_LIB.BASEBOARD_FAB2(SCH_1):PAGE49_I111@MSTR_SCONN.SCONN288_H44441004(CHIPS)':
 'DQ'<55>: CDS_PINID='DQ(55)';
NODE_NAME     J6M1 124
 '@BASEBOARD_FAB2_LIB.BASEBOARD_FAB2(SCH_1):PAGE50_I158@MSTR_SCONN.SCONN288_H44441003(CHIPS)':
 'DQ'<54>: CDS_PINID='DQ(54)';
NET_NAME
'M_D_DQ<55>'
 '@BASEBOARD_FAB2_LIB.BASEBOARD_FAB2(SCH_1):M_D_DQ'<55>:
 C_SIGNAL='@baseboard_fab2_lib.baseboard_fab2(sch_1):m_d_dq(55)';
NODE_NAME     U5D1 DU28
 '@BASEBOARD_FAB2_LIB.BASEBOARD_FAB2(SCH_1):PAGE26_I172@CHPSET_LIB.SKX_EXT_B(CHIPS)':
 'DDR3_DQ'<55>: CDS_PINID='DDR3_DQ(55)';
NODE_NAME     J4B1 124
 '@BASEBOARD_FAB2_LIB.BASEBOARD_FAB2(SCH_1):PAGE49_I111@MSTR_SCONN.SCONN288_H44441004(CHIPS)':
 'DQ'<54>: CDS_PINID='DQ(54)';
NODE_NAME     J6M1 269
 '@BASEBOARD_FAB2_LIB.BASEBOARD_FAB2(SCH_1):PAGE50_I158@MSTR_SCONN.SCONN288_H44441003(CHIPS)':
 'DQ'<55>: CDS_PINID='DQ(55)';
NET_NAME
'M_D_DQ<56>'
 '@BASEBOARD_FAB2_LIB.BASEBOARD_FAB2(SCH_1):M_D_DQ'<56>:
 C_SIGNAL='@baseboard_fab2_lib.baseboard_fab2(sch_1):m_d_dq(56)';
NODE_NAME     U5D1 DN24
 '@BASEBOARD_FAB2_LIB.BASEBOARD_FAB2(SCH_1):PAGE26_I172@CHPSET_LIB.SKX_EXT_B(CHIPS)':
 'DDR3_DQ'<56>: CDS_PINID='DDR3_DQ(56)';
NODE_NAME     J4B1 275
 '@BASEBOARD_FAB2_LIB.BASEBOARD_FAB2(SCH_1):PAGE49_I111@MSTR_SCONN.SCONN288_H44441004(CHIPS)':
 'DQ'<57>: CDS_PINID='DQ(57)';
NODE_NAME     J6M1 130
 '@BASEBOARD_FAB2_LIB.BASEBOARD_FAB2(SCH_1):PAGE50_I158@MSTR_SCONN.SCONN288_H44441003(CHIPS)':
 'DQ'<56>: CDS_PINID='DQ(56)';
NET_NAME
'M_D_DQ<57>'
 '@BASEBOARD_FAB2_LIB.BASEBOARD_FAB2(SCH_1):M_D_DQ'<57>:
 C_SIGNAL='@baseboard_fab2_lib.baseboard_fab2(sch_1):m_d_dq(57)';
NODE_NAME     U5D1 DU24
 '@BASEBOARD_FAB2_LIB.BASEBOARD_FAB2(SCH_1):PAGE26_I172@CHPSET_LIB.SKX_EXT_B(CHIPS)':
 'DDR3_DQ'<57>: CDS_PINID='DDR3_DQ(57)';
NODE_NAME     J4B1 130
 '@BASEBOARD_FAB2_LIB.BASEBOARD_FAB2(SCH_1):PAGE49_I111@MSTR_SCONN.SCONN288_H44441004(CHIPS)':
 'DQ'<56>: CDS_PINID='DQ(56)';
NODE_NAME     J6M1 275
 '@BASEBOARD_FAB2_LIB.BASEBOARD_FAB2(SCH_1):PAGE50_I158@MSTR_SCONN.SCONN288_H44441003(CHIPS)':
 'DQ'<57>: CDS_PINID='DQ(57)';
NET_NAME
'M_D_DQ<58>'
 '@BASEBOARD_FAB2_LIB.BASEBOARD_FAB2(SCH_1):M_D_DQ'<58>:
 C_SIGNAL='@baseboard_fab2_lib.baseboard_fab2(sch_1):m_d_dq(58)';
NODE_NAME     U5D1 DY21
 '@BASEBOARD_FAB2_LIB.BASEBOARD_FAB2(SCH_1):PAGE26_I172@CHPSET_LIB.SKX_EXT_B(CHIPS)':
 'DDR3_DQ'<58>: CDS_PINID='DDR3_DQ(58)';
NODE_NAME     J4B1 282
 '@BASEBOARD_FAB2_LIB.BASEBOARD_FAB2(SCH_1):PAGE49_I111@MSTR_SCONN.SCONN288_H44441004(CHIPS)':
 'DQ'<59>: CDS_PINID='DQ(59)';
NODE_NAME     J6M1 137
 '@BASEBOARD_FAB2_LIB.BASEBOARD_FAB2(SCH_1):PAGE50_I158@MSTR_SCONN.SCONN288_H44441003(CHIPS)':
 'DQ'<58>: CDS_PINID='DQ(58)';
NET_NAME
'M_D_DQ<59>'
 '@BASEBOARD_FAB2_LIB.BASEBOARD_FAB2(SCH_1):M_D_DQ'<59>:
 C_SIGNAL='@baseboard_fab2_lib.baseboard_fab2(sch_1):m_d_dq(59)';
NODE_NAME     U5D1 EB21
 '@BASEBOARD_FAB2_LIB.BASEBOARD_FAB2(SCH_1):PAGE26_I172@CHPSET_LIB.SKX_EXT_B(CHIPS)':
 'DDR3_DQ'<59>: CDS_PINID='DDR3_DQ(59)';
NODE_NAME     J4B1 137
 '@BASEBOARD_FAB2_LIB.BASEBOARD_FAB2(SCH_1):PAGE49_I111@MSTR_SCONN.SCONN288_H44441004(CHIPS)':
 'DQ'<58>: CDS_PINID='DQ(58)';
NODE_NAME     J6M1 282
 '@BASEBOARD_FAB2_LIB.BASEBOARD_FAB2(SCH_1):PAGE50_I158@MSTR_SCONN.SCONN288_H44441003(CHIPS)':
 'DQ'<59>: CDS_PINID='DQ(59)';
NET_NAME
'M_D_DQ<5>'
 '@BASEBOARD_FAB2_LIB.BASEBOARD_FAB2(SCH_1):M_D_DQ'<5>:
 C_SIGNAL='@baseboard_fab2_lib.baseboard_fab2(sch_1):m_d_dq(5)';
NODE_NAME     U5D1 CL86
 '@BASEBOARD_FAB2_LIB.BASEBOARD_FAB2(SCH_1):PAGE26_I172@CHPSET_LIB.SKX_EXT_B(CHIPS)':
 'DDR3_DQ'<5>: CDS_PINID='DDR3_DQ(5)';
NODE_NAME     J4B1 3
 '@BASEBOARD_FAB2_LIB.BASEBOARD_FAB2(SCH_1):PAGE49_I111@MSTR_SCONN.SCONN288_H44441004(CHIPS)':
 'DQ'<4>: CDS_PINID='DQ(4)';
NODE_NAME     J6M1 148
 '@BASEBOARD_FAB2_LIB.BASEBOARD_FAB2(SCH_1):PAGE50_I158@MSTR_SCONN.SCONN288_H44441003(CHIPS)':
 'DQ'<5>: CDS_PINID='DQ(5)';
NET_NAME
'M_D_DQ<60>'
 '@BASEBOARD_FAB2_LIB.BASEBOARD_FAB2(SCH_1):M_D_DQ'<60>:
 C_SIGNAL='@baseboard_fab2_lib.baseboard_fab2(sch_1):m_d_dq(60)';
NODE_NAME     U5D1 DP25
 '@BASEBOARD_FAB2_LIB.BASEBOARD_FAB2(SCH_1):PAGE26_I172@CHPSET_LIB.SKX_EXT_B(CHIPS)':
 'DDR3_DQ'<60>: CDS_PINID='DDR3_DQ(60)';
NODE_NAME     J4B1 273
 '@BASEBOARD_FAB2_LIB.BASEBOARD_FAB2(SCH_1):PAGE49_I111@MSTR_SCONN.SCONN288_H44441004(CHIPS)':
 'DQ'<61>: CDS_PINID='DQ(61)';
NODE_NAME     J6M1 128
 '@BASEBOARD_FAB2_LIB.BASEBOARD_FAB2(SCH_1):PAGE50_I158@MSTR_SCONN.SCONN288_H44441003(CHIPS)':
 'DQ'<60>: CDS_PINID='DQ(60)';
NET_NAME
'M_D_DQ<61>'
 '@BASEBOARD_FAB2_LIB.BASEBOARD_FAB2(SCH_1):M_D_DQ'<61>:
 C_SIGNAL='@baseboard_fab2_lib.baseboard_fab2(sch_1):m_d_dq(61)';
NODE_NAME     U5D1 DT25
 '@BASEBOARD_FAB2_LIB.BASEBOARD_FAB2(SCH_1):PAGE26_I172@CHPSET_LIB.SKX_EXT_B(CHIPS)':
 'DDR3_DQ'<61>: CDS_PINID='DDR3_DQ(61)';
NODE_NAME     J4B1 128
 '@BASEBOARD_FAB2_LIB.BASEBOARD_FAB2(SCH_1):PAGE49_I111@MSTR_SCONN.SCONN288_H44441004(CHIPS)':
 'DQ'<60>: CDS_PINID='DQ(60)';
NODE_NAME     J6M1 273
 '@BASEBOARD_FAB2_LIB.BASEBOARD_FAB2(SCH_1):PAGE50_I158@MSTR_SCONN.SCONN288_H44441003(CHIPS)':
 'DQ'<61>: CDS_PINID='DQ(61)';
NET_NAME
'M_D_DQ<62>'
 '@BASEBOARD_FAB2_LIB.BASEBOARD_FAB2(SCH_1):M_D_DQ'<62>:
 C_SIGNAL='@baseboard_fab2_lib.baseboard_fab2(sch_1):m_d_dq(62)';
NODE_NAME     U5D1 EC22
 '@BASEBOARD_FAB2_LIB.BASEBOARD_FAB2(SCH_1):PAGE26_I172@CHPSET_LIB.SKX_EXT_B(CHIPS)':
 'DDR3_DQ'<62>: CDS_PINID='DDR3_DQ(62)';
NODE_NAME     J4B1 280
 '@BASEBOARD_FAB2_LIB.BASEBOARD_FAB2(SCH_1):PAGE49_I111@MSTR_SCONN.SCONN288_H44441004(CHIPS)':
 'DQ'<63>: CDS_PINID='DQ(63)';
NODE_NAME     J6M1 135
 '@BASEBOARD_FAB2_LIB.BASEBOARD_FAB2(SCH_1):PAGE50_I158@MSTR_SCONN.SCONN288_H44441003(CHIPS)':
 'DQ'<62>: CDS_PINID='DQ(62)';
NET_NAME
'M_D_DQ<63>'
 '@BASEBOARD_FAB2_LIB.BASEBOARD_FAB2(SCH_1):M_D_DQ'<63>:
 C_SIGNAL='@baseboard_fab2_lib.baseboard_fab2(sch_1):m_d_dq(63)';
NODE_NAME     U5D1 DW22
 '@BASEBOARD_FAB2_LIB.BASEBOARD_FAB2(SCH_1):PAGE26_I172@CHPSET_LIB.SKX_EXT_B(CHIPS)':
 'DDR3_DQ'<63>: CDS_PINID='DDR3_DQ(63)';
NODE_NAME     J4B1 135
 '@BASEBOARD_FAB2_LIB.BASEBOARD_FAB2(SCH_1):PAGE49_I111@MSTR_SCONN.SCONN288_H44441004(CHIPS)':
 'DQ'<62>: CDS_PINID='DQ(62)';
NODE_NAME     J6M1 280
 '@BASEBOARD_FAB2_LIB.BASEBOARD_FAB2(SCH_1):PAGE50_I158@MSTR_SCONN.SCONN288_H44441003(CHIPS)':
 'DQ'<63>: CDS_PINID='DQ(63)';
NET_NAME
'M_D_DQ<6>'
 '@BASEBOARD_FAB2_LIB.BASEBOARD_FAB2(SCH_1):M_D_DQ'<6>:
 C_SIGNAL='@baseboard_fab2_lib.baseboard_fab2(sch_1):m_d_dq(6)';
NODE_NAME     U5D1 CW86
 '@BASEBOARD_FAB2_LIB.BASEBOARD_FAB2(SCH_1):PAGE26_I172@CHPSET_LIB.SKX_EXT_B(CHIPS)':
 'DDR3_DQ'<6>: CDS_PINID='DDR3_DQ(6)';
NODE_NAME     J4B1 155
 '@BASEBOARD_FAB2_LIB.BASEBOARD_FAB2(SCH_1):PAGE49_I111@MSTR_SCONN.SCONN288_H44441004(CHIPS)':
 'DQ'<7>: CDS_PINID='DQ(7)';
NODE_NAME     J6M1 10
 '@BASEBOARD_FAB2_LIB.BASEBOARD_FAB2(SCH_1):PAGE50_I158@MSTR_SCONN.SCONN288_H44441003(CHIPS)':
 'DQ'<6>: CDS_PINID='DQ(6)';
NET_NAME
'M_D_DQ<7>'
 '@BASEBOARD_FAB2_LIB.BASEBOARD_FAB2(SCH_1):M_D_DQ'<7>:
 C_SIGNAL='@baseboard_fab2_lib.baseboard_fab2(sch_1):m_d_dq(7)';
NODE_NAME     U5D1 CW84
 '@BASEBOARD_FAB2_LIB.BASEBOARD_FAB2(SCH_1):PAGE26_I172@CHPSET_LIB.SKX_EXT_B(CHIPS)':
 'DDR3_DQ'<7>: CDS_PINID='DDR3_DQ(7)';
NODE_NAME     J4B1 10
 '@BASEBOARD_FAB2_LIB.BASEBOARD_FAB2(SCH_1):PAGE49_I111@MSTR_SCONN.SCONN288_H44441004(CHIPS)':
 'DQ'<6>: CDS_PINID='DQ(6)';
NODE_NAME     J6M1 155
 '@BASEBOARD_FAB2_LIB.BASEBOARD_FAB2(SCH_1):PAGE50_I158@MSTR_SCONN.SCONN288_H44441003(CHIPS)':
 'DQ'<7>: CDS_PINID='DQ(7)';
NET_NAME
'M_D_DQ<8>'
 '@BASEBOARD_FAB2_LIB.BASEBOARD_FAB2(SCH_1):M_D_DQ'<8>:
 C_SIGNAL='@baseboard_fab2_lib.baseboard_fab2(sch_1):m_d_dq(8)';
NODE_NAME     U5D1 DG84
 '@BASEBOARD_FAB2_LIB.BASEBOARD_FAB2(SCH_1):PAGE26_I172@CHPSET_LIB.SKX_EXT_B(CHIPS)':
 'DDR3_DQ'<8>: CDS_PINID='DDR3_DQ(8)';
NODE_NAME     J4B1 161
 '@BASEBOARD_FAB2_LIB.BASEBOARD_FAB2(SCH_1):PAGE49_I111@MSTR_SCONN.SCONN288_H44441004(CHIPS)':
 'DQ'<9>: CDS_PINID='DQ(9)';
NODE_NAME     J6M1 16
 '@BASEBOARD_FAB2_LIB.BASEBOARD_FAB2(SCH_1):PAGE50_I158@MSTR_SCONN.SCONN288_H44441003(CHIPS)':
 'DQ'<8>: CDS_PINID='DQ(8)';
NET_NAME
'M_D_DQ<9>'
 '@BASEBOARD_FAB2_LIB.BASEBOARD_FAB2(SCH_1):M_D_DQ'<9>:
 C_SIGNAL='@baseboard_fab2_lib.baseboard_fab2(sch_1):m_d_dq(9)';
NODE_NAME     U5D1 DH85
 '@BASEBOARD_FAB2_LIB.BASEBOARD_FAB2(SCH_1):PAGE26_I172@CHPSET_LIB.SKX_EXT_B(CHIPS)':
 'DDR3_DQ'<9>: CDS_PINID='DDR3_DQ(9)';
NODE_NAME     J4B1 16
 '@BASEBOARD_FAB2_LIB.BASEBOARD_FAB2(SCH_1):PAGE49_I111@MSTR_SCONN.SCONN288_H44441004(CHIPS)':
 'DQ'<8>: CDS_PINID='DQ(8)';
NODE_NAME     J6M1 161
 '@BASEBOARD_FAB2_LIB.BASEBOARD_FAB2(SCH_1):PAGE50_I158@MSTR_SCONN.SCONN288_H44441003(CHIPS)':
 'DQ'<9>: CDS_PINID='DQ(9)';
NET_NAME
'M_D_DQS_DN<0>'
 '@BASEBOARD_FAB2_LIB.BASEBOARD_FAB2(SCH_1):M_D_DQS_DN'<0>:
 C_SIGNAL='@baseboard_fab2_lib.baseboard_fab2(sch_1):m_d_dqs_dn(0)';
NODE_NAME     U5D1 CU84
 '@BASEBOARD_FAB2_LIB.BASEBOARD_FAB2(SCH_1):PAGE26_I172@CHPSET_LIB.SKX_EXT_B(CHIPS)':
 'DDR3_DQS_DN'<0>: CDS_PINID='DDR3_DQS_DN(0)';
NODE_NAME     J4B1 152
 '@BASEBOARD_FAB2_LIB.BASEBOARD_FAB2(SCH_1):PAGE49_I66@MSTR_SCONN.SCONN288_H44441004(CHIPS)':
 'DQS0N': CDS_PINID='DQS0N';
NODE_NAME     J6M1 152
 '@BASEBOARD_FAB2_LIB.BASEBOARD_FAB2(SCH_1):PAGE50_I46@MSTR_SCONN.SCONN288_H44441003(CHIPS)':
 'DQS0N': CDS_PINID='DQS0N';
NET_NAME
'M_D_DQS_DN<10>'
 '@BASEBOARD_FAB2_LIB.BASEBOARD_FAB2(SCH_1):M_D_DQS_DN'<10>:
 C_SIGNAL='@baseboard_fab2_lib.baseboard_fab2(sch_1):m_d_dqs_dn(10)';
NODE_NAME     U5D1 DM85
 '@BASEBOARD_FAB2_LIB.BASEBOARD_FAB2(SCH_1):PAGE26_I172@CHPSET_LIB.SKX_EXT_B(CHIPS)':
 'DDR3_DQS_DN'<10>: CDS_PINID='DDR3_DQS_DN(10)';
NODE_NAME     J4B1 19
 '@BASEBOARD_FAB2_LIB.BASEBOARD_FAB2(SCH_1):PAGE49_I66@MSTR_SCONN.SCONN288_H44441004(CHIPS)':
 'DQS10N': CDS_PINID='DQS10N';
NODE_NAME     J6M1 19
 '@BASEBOARD_FAB2_LIB.BASEBOARD_FAB2(SCH_1):PAGE50_I46@MSTR_SCONN.SCONN288_H44441003(CHIPS)':
 'DQS10N': CDS_PINID='DQS10N';
NET_NAME
'M_D_DQS_DN<11>'
 '@BASEBOARD_FAB2_LIB.BASEBOARD_FAB2(SCH_1):M_D_DQS_DN'<11>:
 C_SIGNAL='@baseboard_fab2_lib.baseboard_fab2(sch_1):m_d_dqs_dn(11)';
NODE_NAME     U5D1 DN80
 '@BASEBOARD_FAB2_LIB.BASEBOARD_FAB2(SCH_1):PAGE26_I172@CHPSET_LIB.SKX_EXT_B(CHIPS)':
 'DDR3_DQS_DN'<11>: CDS_PINID='DDR3_DQS_DN(11)';
NODE_NAME     J4B1 30
 '@BASEBOARD_FAB2_LIB.BASEBOARD_FAB2(SCH_1):PAGE49_I66@MSTR_SCONN.SCONN288_H44441004(CHIPS)':
 'DQS11N': CDS_PINID='DQS11N';
NODE_NAME     J6M1 30
 '@BASEBOARD_FAB2_LIB.BASEBOARD_FAB2(SCH_1):PAGE50_I46@MSTR_SCONN.SCONN288_H44441003(CHIPS)':
 'DQS11N': CDS_PINID='DQS11N';
NET_NAME
'M_D_DQS_DN<12>'
 '@BASEBOARD_FAB2_LIB.BASEBOARD_FAB2(SCH_1):M_D_DQS_DN'<12>:
 C_SIGNAL='@baseboard_fab2_lib.baseboard_fab2(sch_1):m_d_dqs_dn(12)';
NODE_NAME     U5D1 DP75
 '@BASEBOARD_FAB2_LIB.BASEBOARD_FAB2(SCH_1):PAGE26_I172@CHPSET_LIB.SKX_EXT_B(CHIPS)':
 'DDR3_DQS_DN'<12>: CDS_PINID='DDR3_DQS_DN(12)';
NODE_NAME     J4B1 41
 '@BASEBOARD_FAB2_LIB.BASEBOARD_FAB2(SCH_1):PAGE49_I66@MSTR_SCONN.SCONN288_H44441004(CHIPS)':
 'DQS12N': CDS_PINID='DQS12N';
NODE_NAME     J6M1 41
 '@BASEBOARD_FAB2_LIB.BASEBOARD_FAB2(SCH_1):PAGE50_I46@MSTR_SCONN.SCONN288_H44441003(CHIPS)':
 'DQS12N': CDS_PINID='DQS12N';
NET_NAME
'M_D_DQS_DN<13>'
 '@BASEBOARD_FAB2_LIB.BASEBOARD_FAB2(SCH_1):M_D_DQS_DN'<13>:
 C_SIGNAL='@baseboard_fab2_lib.baseboard_fab2(sch_1):m_d_dqs_dn(13)';
NODE_NAME     U5D1 EA38
 '@BASEBOARD_FAB2_LIB.BASEBOARD_FAB2(SCH_1):PAGE26_I172@CHPSET_LIB.SKX_EXT_B(CHIPS)':
 'DDR3_DQS_DN'<13>: CDS_PINID='DDR3_DQS_DN(13)';
NODE_NAME     J4B1 100
 '@BASEBOARD_FAB2_LIB.BASEBOARD_FAB2(SCH_1):PAGE49_I66@MSTR_SCONN.SCONN288_H44441004(CHIPS)':
 'DQS13N': CDS_PINID='DQS13N';
NODE_NAME     J6M1 100
 '@BASEBOARD_FAB2_LIB.BASEBOARD_FAB2(SCH_1):PAGE50_I46@MSTR_SCONN.SCONN288_H44441003(CHIPS)':
 'DQS13N': CDS_PINID='DQS13N';
NET_NAME
'M_D_DQS_DN<14>'
 '@BASEBOARD_FAB2_LIB.BASEBOARD_FAB2(SCH_1):M_D_DQS_DN'<14>:
 C_SIGNAL='@baseboard_fab2_lib.baseboard_fab2(sch_1):m_d_dqs_dn(14)';
NODE_NAME     U5D1 DP35
 '@BASEBOARD_FAB2_LIB.BASEBOARD_FAB2(SCH_1):PAGE26_I172@CHPSET_LIB.SKX_EXT_B(CHIPS)':
 'DDR3_DQS_DN'<14>: CDS_PINID='DDR3_DQS_DN(14)';
NODE_NAME     J4B1 111
 '@BASEBOARD_FAB2_LIB.BASEBOARD_FAB2(SCH_1):PAGE49_I66@MSTR_SCONN.SCONN288_H44441004(CHIPS)':
 'DQS14N': CDS_PINID='DQS14N';
NODE_NAME     J6M1 111
 '@BASEBOARD_FAB2_LIB.BASEBOARD_FAB2(SCH_1):PAGE50_I46@MSTR_SCONN.SCONN288_H44441003(CHIPS)':
 'DQS14N': CDS_PINID='DQS14N';
NET_NAME
'M_D_DQS_DN<15>'
 '@BASEBOARD_FAB2_LIB.BASEBOARD_FAB2(SCH_1):M_D_DQS_DN'<15>:
 C_SIGNAL='@baseboard_fab2_lib.baseboard_fab2(sch_1):m_d_dqs_dn(15)';
NODE_NAME     U5D1 DM29
 '@BASEBOARD_FAB2_LIB.BASEBOARD_FAB2(SCH_1):PAGE26_I172@CHPSET_LIB.SKX_EXT_B(CHIPS)':
 'DDR3_DQS_DN'<15>: CDS_PINID='DDR3_DQS_DN(15)';
NODE_NAME     J4B1 122
 '@BASEBOARD_FAB2_LIB.BASEBOARD_FAB2(SCH_1):PAGE49_I66@MSTR_SCONN.SCONN288_H44441004(CHIPS)':
 'DQS15N': CDS_PINID='DQS15N';
NODE_NAME     J6M1 122
 '@BASEBOARD_FAB2_LIB.BASEBOARD_FAB2(SCH_1):PAGE50_I46@MSTR_SCONN.SCONN288_H44441003(CHIPS)':
 'DQS15N': CDS_PINID='DQS15N';
NET_NAME
'M_D_DQS_DN<16>'
 '@BASEBOARD_FAB2_LIB.BASEBOARD_FAB2(SCH_1):M_D_DQS_DN'<16>:
 C_SIGNAL='@baseboard_fab2_lib.baseboard_fab2(sch_1):m_d_dqs_dn(16)';
NODE_NAME     U5D1 DM23
 '@BASEBOARD_FAB2_LIB.BASEBOARD_FAB2(SCH_1):PAGE26_I172@CHPSET_LIB.SKX_EXT_B(CHIPS)':
 'DDR3_DQS_DN'<16>: CDS_PINID='DDR3_DQS_DN(16)';
NODE_NAME     J4B1 133
 '@BASEBOARD_FAB2_LIB.BASEBOARD_FAB2(SCH_1):PAGE49_I66@MSTR_SCONN.SCONN288_H44441004(CHIPS)':
 'DQS16N': CDS_PINID='DQS16N';
NODE_NAME     J6M1 133
 '@BASEBOARD_FAB2_LIB.BASEBOARD_FAB2(SCH_1):PAGE50_I46@MSTR_SCONN.SCONN288_H44441003(CHIPS)':
 'DQS16N': CDS_PINID='DQS16N';
NET_NAME
'M_D_DQS_DN<17>'
 '@BASEBOARD_FAB2_LIB.BASEBOARD_FAB2(SCH_1):M_D_DQS_DN'<17>:
 C_SIGNAL='@baseboard_fab2_lib.baseboard_fab2(sch_1):m_d_dqs_dn(17)';
NODE_NAME     U5D1 DB67
 '@BASEBOARD_FAB2_LIB.BASEBOARD_FAB2(SCH_1):PAGE26_I172@CHPSET_LIB.SKX_EXT_B(CHIPS)':
 'DDR3_DQS_DN'<17>: CDS_PINID='DDR3_DQS_DN(17)';
NODE_NAME     J4B1 52
 '@BASEBOARD_FAB2_LIB.BASEBOARD_FAB2(SCH_1):PAGE49_I66@MSTR_SCONN.SCONN288_H44441004(CHIPS)':
 'DQS17N': CDS_PINID='DQS17N';
NODE_NAME     J6M1 52
 '@BASEBOARD_FAB2_LIB.BASEBOARD_FAB2(SCH_1):PAGE50_I46@MSTR_SCONN.SCONN288_H44441003(CHIPS)':
 'DQS17N': CDS_PINID='DQS17N';
NET_NAME
'M_D_DQS_DN<1>'
 '@BASEBOARD_FAB2_LIB.BASEBOARD_FAB2(SCH_1):M_D_DQS_DN'<1>:
 C_SIGNAL='@baseboard_fab2_lib.baseboard_fab2(sch_1):m_d_dqs_dn(1)';
NODE_NAME     U5D1 DN84
 '@BASEBOARD_FAB2_LIB.BASEBOARD_FAB2(SCH_1):PAGE26_I172@CHPSET_LIB.SKX_EXT_B(CHIPS)':
 'DDR3_DQS_DN'<1>: CDS_PINID='DDR3_DQS_DN(1)';
NODE_NAME     J4B1 163
 '@BASEBOARD_FAB2_LIB.BASEBOARD_FAB2(SCH_1):PAGE49_I66@MSTR_SCONN.SCONN288_H44441004(CHIPS)':
 'DQS1N': CDS_PINID='DQS1N';
NODE_NAME     J6M1 163
 '@BASEBOARD_FAB2_LIB.BASEBOARD_FAB2(SCH_1):PAGE50_I46@MSTR_SCONN.SCONN288_H44441003(CHIPS)':
 'DQS1N': CDS_PINID='DQS1N';
NET_NAME
'M_D_DQS_DN<2>'
 '@BASEBOARD_FAB2_LIB.BASEBOARD_FAB2(SCH_1):M_D_DQS_DN'<2>:
 C_SIGNAL='@baseboard_fab2_lib.baseboard_fab2(sch_1):m_d_dqs_dn(2)';
NODE_NAME     U5D1 DL82
 '@BASEBOARD_FAB2_LIB.BASEBOARD_FAB2(SCH_1):PAGE26_I172@CHPSET_LIB.SKX_EXT_B(CHIPS)':
 'DDR3_DQS_DN'<2>: CDS_PINID='DDR3_DQS_DN(2)';
NODE_NAME     J4B1 174
 '@BASEBOARD_FAB2_LIB.BASEBOARD_FAB2(SCH_1):PAGE49_I66@MSTR_SCONN.SCONN288_H44441004(CHIPS)':
 'DQS2N': CDS_PINID='DQS2N';
NODE_NAME     J6M1 174
 '@BASEBOARD_FAB2_LIB.BASEBOARD_FAB2(SCH_1):PAGE50_I46@MSTR_SCONN.SCONN288_H44441003(CHIPS)':
 'DQS2N': CDS_PINID='DQS2N';
NET_NAME
'M_D_DQS_DN<3>'
 '@BASEBOARD_FAB2_LIB.BASEBOARD_FAB2(SCH_1):M_D_DQS_DN'<3>:
 C_SIGNAL='@baseboard_fab2_lib.baseboard_fab2(sch_1):m_d_dqs_dn(3)';
NODE_NAME     U5D1 DV75
 '@BASEBOARD_FAB2_LIB.BASEBOARD_FAB2(SCH_1):PAGE26_I172@CHPSET_LIB.SKX_EXT_B(CHIPS)':
 'DDR3_DQS_DN'<3>: CDS_PINID='DDR3_DQS_DN(3)';
NODE_NAME     J4B1 185
 '@BASEBOARD_FAB2_LIB.BASEBOARD_FAB2(SCH_1):PAGE49_I66@MSTR_SCONN.SCONN288_H44441004(CHIPS)':
 'DQS3N': CDS_PINID='DQS3N';
NODE_NAME     J6M1 185
 '@BASEBOARD_FAB2_LIB.BASEBOARD_FAB2(SCH_1):PAGE50_I46@MSTR_SCONN.SCONN288_H44441003(CHIPS)':
 'DQS3N': CDS_PINID='DQS3N';
NET_NAME
'M_D_DQS_DN<4>'
 '@BASEBOARD_FAB2_LIB.BASEBOARD_FAB2(SCH_1):M_D_DQS_DN'<4>:
 C_SIGNAL='@baseboard_fab2_lib.baseboard_fab2(sch_1):m_d_dqs_dn(4)';
NODE_NAME     U5D1 EE38
 '@BASEBOARD_FAB2_LIB.BASEBOARD_FAB2(SCH_1):PAGE26_I172@CHPSET_LIB.SKX_EXT_B(CHIPS)':
 'DDR3_DQS_DN'<4>: CDS_PINID='DDR3_DQS_DN(4)';
NODE_NAME     J4B1 244
 '@BASEBOARD_FAB2_LIB.BASEBOARD_FAB2(SCH_1):PAGE49_I66@MSTR_SCONN.SCONN288_H44441004(CHIPS)':
 'DQS4N': CDS_PINID='DQS4N';
NODE_NAME     J6M1 244
 '@BASEBOARD_FAB2_LIB.BASEBOARD_FAB2(SCH_1):PAGE50_I46@MSTR_SCONN.SCONN288_H44441003(CHIPS)':
 'DQS4N': CDS_PINID='DQS4N';
NET_NAME
'M_D_DQS_DN<5>'
 '@BASEBOARD_FAB2_LIB.BASEBOARD_FAB2(SCH_1):M_D_DQS_DN'<5>:
 C_SIGNAL='@baseboard_fab2_lib.baseboard_fab2(sch_1):m_d_dqs_dn(5)';
NODE_NAME     U5D1 DV35
 '@BASEBOARD_FAB2_LIB.BASEBOARD_FAB2(SCH_1):PAGE26_I172@CHPSET_LIB.SKX_EXT_B(CHIPS)':
 'DDR3_DQS_DN'<5>: CDS_PINID='DDR3_DQS_DN(5)';
NODE_NAME     J4B1 255
 '@BASEBOARD_FAB2_LIB.BASEBOARD_FAB2(SCH_1):PAGE49_I66@MSTR_SCONN.SCONN288_H44441004(CHIPS)':
 'DQS5N': CDS_PINID='DQS5N';
NODE_NAME     J6M1 255
 '@BASEBOARD_FAB2_LIB.BASEBOARD_FAB2(SCH_1):PAGE50_I46@MSTR_SCONN.SCONN288_H44441003(CHIPS)':
 'DQS5N': CDS_PINID='DQS5N';
NET_NAME
'M_D_DQS_DN<6>'
 '@BASEBOARD_FAB2_LIB.BASEBOARD_FAB2(SCH_1):M_D_DQS_DN'<6>:
 C_SIGNAL='@baseboard_fab2_lib.baseboard_fab2(sch_1):m_d_dqs_dn(6)';
NODE_NAME     U5D1 DV29
 '@BASEBOARD_FAB2_LIB.BASEBOARD_FAB2(SCH_1):PAGE26_I172@CHPSET_LIB.SKX_EXT_B(CHIPS)':
 'DDR3_DQS_DN'<6>: CDS_PINID='DDR3_DQS_DN(6)';
NODE_NAME     J4B1 266
 '@BASEBOARD_FAB2_LIB.BASEBOARD_FAB2(SCH_1):PAGE49_I66@MSTR_SCONN.SCONN288_H44441004(CHIPS)':
 'DQS6N': CDS_PINID='DQS6N';
NODE_NAME     J6M1 266
 '@BASEBOARD_FAB2_LIB.BASEBOARD_FAB2(SCH_1):PAGE50_I46@MSTR_SCONN.SCONN288_H44441003(CHIPS)':
 'DQS6N': CDS_PINID='DQS6N';
NET_NAME
'M_D_DQS_DN<7>'
 '@BASEBOARD_FAB2_LIB.BASEBOARD_FAB2(SCH_1):M_D_DQS_DN'<7>:
 C_SIGNAL='@baseboard_fab2_lib.baseboard_fab2(sch_1):m_d_dqs_dn(7)';
NODE_NAME     U5D1 DV23
 '@BASEBOARD_FAB2_LIB.BASEBOARD_FAB2(SCH_1):PAGE26_I172@CHPSET_LIB.SKX_EXT_B(CHIPS)':
 'DDR3_DQS_DN'<7>: CDS_PINID='DDR3_DQS_DN(7)';
NODE_NAME     J4B1 277
 '@BASEBOARD_FAB2_LIB.BASEBOARD_FAB2(SCH_1):PAGE49_I66@MSTR_SCONN.SCONN288_H44441004(CHIPS)':
 'DQS7N': CDS_PINID='DQS7N';
NODE_NAME     J6M1 277
 '@BASEBOARD_FAB2_LIB.BASEBOARD_FAB2(SCH_1):PAGE50_I46@MSTR_SCONN.SCONN288_H44441003(CHIPS)':
 'DQS7N': CDS_PINID='DQS7N';
NET_NAME
'M_D_DQS_DN<8>'
 '@BASEBOARD_FAB2_LIB.BASEBOARD_FAB2(SCH_1):M_D_DQS_DN'<8>:
 C_SIGNAL='@baseboard_fab2_lib.baseboard_fab2(sch_1):m_d_dqs_dn(8)';
NODE_NAME     U5D1 DF67
 '@BASEBOARD_FAB2_LIB.BASEBOARD_FAB2(SCH_1):PAGE26_I172@CHPSET_LIB.SKX_EXT_B(CHIPS)':
 'DDR3_DQS_DN'<8>: CDS_PINID='DDR3_DQS_DN(8)';
NODE_NAME     J4B1 196
 '@BASEBOARD_FAB2_LIB.BASEBOARD_FAB2(SCH_1):PAGE49_I66@MSTR_SCONN.SCONN288_H44441004(CHIPS)':
 'DQS8N': CDS_PINID='DQS8N';
NODE_NAME     J6M1 196
 '@BASEBOARD_FAB2_LIB.BASEBOARD_FAB2(SCH_1):PAGE50_I46@MSTR_SCONN.SCONN288_H44441003(CHIPS)':
 'DQS8N': CDS_PINID='DQS8N';
NET_NAME
'M_D_DQS_DN<9>'
 '@BASEBOARD_FAB2_LIB.BASEBOARD_FAB2(SCH_1):M_D_DQS_DN'<9>:
 C_SIGNAL='@baseboard_fab2_lib.baseboard_fab2(sch_1):m_d_dqs_dn(9)';
NODE_NAME     U5D1 CR84
 '@BASEBOARD_FAB2_LIB.BASEBOARD_FAB2(SCH_1):PAGE26_I172@CHPSET_LIB.SKX_EXT_B(CHIPS)':
 'DDR3_DQS_DN'<9>: CDS_PINID='DDR3_DQS_DN(9)';
NODE_NAME     J4B1 8
 '@BASEBOARD_FAB2_LIB.BASEBOARD_FAB2(SCH_1):PAGE49_I66@MSTR_SCONN.SCONN288_H44441004(CHIPS)':
 'DQS9N': CDS_PINID='DQS9N';
NODE_NAME     J6M1 8
 '@BASEBOARD_FAB2_LIB.BASEBOARD_FAB2(SCH_1):PAGE50_I46@MSTR_SCONN.SCONN288_H44441003(CHIPS)':
 'DQS9N': CDS_PINID='DQS9N';
NET_NAME
'M_D_DQS_DP<0>'
 '@BASEBOARD_FAB2_LIB.BASEBOARD_FAB2(SCH_1):M_D_DQS_DP'<0>:
 C_SIGNAL='@baseboard_fab2_lib.baseboard_fab2(sch_1):m_d_dqs_dp(0)';
NODE_NAME     U5D1 CV85
 '@BASEBOARD_FAB2_LIB.BASEBOARD_FAB2(SCH_1):PAGE26_I172@CHPSET_LIB.SKX_EXT_B(CHIPS)':
 'DDR3_DQS_DP'<0>: CDS_PINID='DDR3_DQS_DP(0)';
NODE_NAME     J4B1 153
 '@BASEBOARD_FAB2_LIB.BASEBOARD_FAB2(SCH_1):PAGE49_I66@MSTR_SCONN.SCONN288_H44441004(CHIPS)':
 'DQS0P': CDS_PINID='DQS0P';
NODE_NAME     J6M1 153
 '@BASEBOARD_FAB2_LIB.BASEBOARD_FAB2(SCH_1):PAGE50_I46@MSTR_SCONN.SCONN288_H44441003(CHIPS)':
 'DQS0P': CDS_PINID='DQS0P';
NET_NAME
'M_D_DQS_DP<10>'
 '@BASEBOARD_FAB2_LIB.BASEBOARD_FAB2(SCH_1):M_D_DQS_DP'<10>:
 C_SIGNAL='@baseboard_fab2_lib.baseboard_fab2(sch_1):m_d_dqs_dp(10)';
NODE_NAME     U5D1 DL84
 '@BASEBOARD_FAB2_LIB.BASEBOARD_FAB2(SCH_1):PAGE26_I172@CHPSET_LIB.SKX_EXT_B(CHIPS)':
 'DDR3_DQS_DP'<10>: CDS_PINID='DDR3_DQS_DP(10)';
NODE_NAME     J4B1 18
 '@BASEBOARD_FAB2_LIB.BASEBOARD_FAB2(SCH_1):PAGE49_I66@MSTR_SCONN.SCONN288_H44441004(CHIPS)':
 'DQS10P': CDS_PINID='DQS10P';
NODE_NAME     J6M1 18
 '@BASEBOARD_FAB2_LIB.BASEBOARD_FAB2(SCH_1):PAGE50_I46@MSTR_SCONN.SCONN288_H44441003(CHIPS)':
 'DQS10P': CDS_PINID='DQS10P';
NET_NAME
'M_D_DQS_DP<11>'
 '@BASEBOARD_FAB2_LIB.BASEBOARD_FAB2(SCH_1):M_D_DQS_DP'<11>:
 C_SIGNAL='@baseboard_fab2_lib.baseboard_fab2(sch_1):m_d_dqs_dp(11)';
NODE_NAME     U5D1 DP79
 '@BASEBOARD_FAB2_LIB.BASEBOARD_FAB2(SCH_1):PAGE26_I172@CHPSET_LIB.SKX_EXT_B(CHIPS)':
 'DDR3_DQS_DP'<11>: CDS_PINID='DDR3_DQS_DP(11)';
NODE_NAME     J4B1 29
 '@BASEBOARD_FAB2_LIB.BASEBOARD_FAB2(SCH_1):PAGE49_I66@MSTR_SCONN.SCONN288_H44441004(CHIPS)':
 'DQS11P': CDS_PINID='DQS11P';
NODE_NAME     J6M1 29
 '@BASEBOARD_FAB2_LIB.BASEBOARD_FAB2(SCH_1):PAGE50_I46@MSTR_SCONN.SCONN288_H44441003(CHIPS)':
 'DQS11P': CDS_PINID='DQS11P';
NET_NAME
'M_D_DQS_DP<12>'
 '@BASEBOARD_FAB2_LIB.BASEBOARD_FAB2(SCH_1):M_D_DQS_DP'<12>:
 C_SIGNAL='@baseboard_fab2_lib.baseboard_fab2(sch_1):m_d_dqs_dp(12)';
NODE_NAME     U5D1 DM75
 '@BASEBOARD_FAB2_LIB.BASEBOARD_FAB2(SCH_1):PAGE26_I172@CHPSET_LIB.SKX_EXT_B(CHIPS)':
 'DDR3_DQS_DP'<12>: CDS_PINID='DDR3_DQS_DP(12)';
NODE_NAME     J4B1 40
 '@BASEBOARD_FAB2_LIB.BASEBOARD_FAB2(SCH_1):PAGE49_I66@MSTR_SCONN.SCONN288_H44441004(CHIPS)':
 'DQS12P': CDS_PINID='DQS12P';
NODE_NAME     J6M1 40
 '@BASEBOARD_FAB2_LIB.BASEBOARD_FAB2(SCH_1):PAGE50_I46@MSTR_SCONN.SCONN288_H44441003(CHIPS)':
 'DQS12P': CDS_PINID='DQS12P';
NET_NAME
'M_D_DQS_DP<13>'
 '@BASEBOARD_FAB2_LIB.BASEBOARD_FAB2(SCH_1):M_D_DQS_DP'<13>:
 C_SIGNAL='@baseboard_fab2_lib.baseboard_fab2(sch_1):m_d_dqs_dp(13)';
NODE_NAME     U5D1 DW38
 '@BASEBOARD_FAB2_LIB.BASEBOARD_FAB2(SCH_1):PAGE26_I172@CHPSET_LIB.SKX_EXT_B(CHIPS)':
 'DDR3_DQS_DP'<13>: CDS_PINID='DDR3_DQS_DP(13)';
NODE_NAME     J4B1 99
 '@BASEBOARD_FAB2_LIB.BASEBOARD_FAB2(SCH_1):PAGE49_I66@MSTR_SCONN.SCONN288_H44441004(CHIPS)':
 'DQS13P': CDS_PINID='DQS13P';
NODE_NAME     J6M1 99
 '@BASEBOARD_FAB2_LIB.BASEBOARD_FAB2(SCH_1):PAGE50_I46@MSTR_SCONN.SCONN288_H44441003(CHIPS)':
 'DQS13P': CDS_PINID='DQS13P';
NET_NAME
'M_D_DQS_DP<14>'
 '@BASEBOARD_FAB2_LIB.BASEBOARD_FAB2(SCH_1):M_D_DQS_DP'<14>:
 C_SIGNAL='@baseboard_fab2_lib.baseboard_fab2(sch_1):m_d_dqs_dp(14)';
NODE_NAME     U5D1 DM35
 '@BASEBOARD_FAB2_LIB.BASEBOARD_FAB2(SCH_1):PAGE26_I172@CHPSET_LIB.SKX_EXT_B(CHIPS)':
 'DDR3_DQS_DP'<14>: CDS_PINID='DDR3_DQS_DP(14)';
NODE_NAME     J4B1 110
 '@BASEBOARD_FAB2_LIB.BASEBOARD_FAB2(SCH_1):PAGE49_I66@MSTR_SCONN.SCONN288_H44441004(CHIPS)':
 'DQS14P': CDS_PINID='DQS14P';
NODE_NAME     J6M1 110
 '@BASEBOARD_FAB2_LIB.BASEBOARD_FAB2(SCH_1):PAGE50_I46@MSTR_SCONN.SCONN288_H44441003(CHIPS)':
 'DQS14P': CDS_PINID='DQS14P';
NET_NAME
'M_D_DQS_DP<15>'
 '@BASEBOARD_FAB2_LIB.BASEBOARD_FAB2(SCH_1):M_D_DQS_DP'<15>:
 C_SIGNAL='@baseboard_fab2_lib.baseboard_fab2(sch_1):m_d_dqs_dp(15)';
NODE_NAME     U5D1 DP29
 '@BASEBOARD_FAB2_LIB.BASEBOARD_FAB2(SCH_1):PAGE26_I172@CHPSET_LIB.SKX_EXT_B(CHIPS)':
 'DDR3_DQS_DP'<15>: CDS_PINID='DDR3_DQS_DP(15)';
NODE_NAME     J4B1 121
 '@BASEBOARD_FAB2_LIB.BASEBOARD_FAB2(SCH_1):PAGE49_I66@MSTR_SCONN.SCONN288_H44441004(CHIPS)':
 'DQS15P': CDS_PINID='DQS15P';
NODE_NAME     J6M1 121
 '@BASEBOARD_FAB2_LIB.BASEBOARD_FAB2(SCH_1):PAGE50_I46@MSTR_SCONN.SCONN288_H44441003(CHIPS)':
 'DQS15P': CDS_PINID='DQS15P';
NET_NAME
'M_D_DQS_DP<16>'
 '@BASEBOARD_FAB2_LIB.BASEBOARD_FAB2(SCH_1):M_D_DQS_DP'<16>:
 C_SIGNAL='@baseboard_fab2_lib.baseboard_fab2(sch_1):m_d_dqs_dp(16)';
NODE_NAME     U5D1 DP23
 '@BASEBOARD_FAB2_LIB.BASEBOARD_FAB2(SCH_1):PAGE26_I172@CHPSET_LIB.SKX_EXT_B(CHIPS)':
 'DDR3_DQS_DP'<16>: CDS_PINID='DDR3_DQS_DP(16)';
NODE_NAME     J4B1 132
 '@BASEBOARD_FAB2_LIB.BASEBOARD_FAB2(SCH_1):PAGE49_I66@MSTR_SCONN.SCONN288_H44441004(CHIPS)':
 'DQS16P': CDS_PINID='DQS16P';
NODE_NAME     J6M1 132
 '@BASEBOARD_FAB2_LIB.BASEBOARD_FAB2(SCH_1):PAGE50_I46@MSTR_SCONN.SCONN288_H44441003(CHIPS)':
 'DQS16P': CDS_PINID='DQS16P';
NET_NAME
'M_D_DQS_DP<17>'
 '@BASEBOARD_FAB2_LIB.BASEBOARD_FAB2(SCH_1):M_D_DQS_DP'<17>:
 C_SIGNAL='@baseboard_fab2_lib.baseboard_fab2(sch_1):m_d_dqs_dp(17)';
NODE_NAME     U5D1 CY67
 '@BASEBOARD_FAB2_LIB.BASEBOARD_FAB2(SCH_1):PAGE26_I172@CHPSET_LIB.SKX_EXT_B(CHIPS)':
 'DDR3_DQS_DP'<17>: CDS_PINID='DDR3_DQS_DP(17)';
NODE_NAME     J4B1 51
 '@BASEBOARD_FAB2_LIB.BASEBOARD_FAB2(SCH_1):PAGE49_I66@MSTR_SCONN.SCONN288_H44441004(CHIPS)':
 'DQS17P': CDS_PINID='DQS17P';
NODE_NAME     J6M1 51
 '@BASEBOARD_FAB2_LIB.BASEBOARD_FAB2(SCH_1):PAGE50_I46@MSTR_SCONN.SCONN288_H44441003(CHIPS)':
 'DQS17P': CDS_PINID='DQS17P';
NET_NAME
'M_D_DQS_DP<1>'
 '@BASEBOARD_FAB2_LIB.BASEBOARD_FAB2(SCH_1):M_D_DQS_DP'<1>:
 C_SIGNAL='@baseboard_fab2_lib.baseboard_fab2(sch_1):m_d_dqs_dp(1)';
NODE_NAME     U5D1 DP85
 '@BASEBOARD_FAB2_LIB.BASEBOARD_FAB2(SCH_1):PAGE26_I172@CHPSET_LIB.SKX_EXT_B(CHIPS)':
 'DDR3_DQS_DP'<1>: CDS_PINID='DDR3_DQS_DP(1)';
NODE_NAME     J4B1 164
 '@BASEBOARD_FAB2_LIB.BASEBOARD_FAB2(SCH_1):PAGE49_I66@MSTR_SCONN.SCONN288_H44441004(CHIPS)':
 'DQS1P': CDS_PINID='DQS1P';
NODE_NAME     J6M1 164
 '@BASEBOARD_FAB2_LIB.BASEBOARD_FAB2(SCH_1):PAGE50_I46@MSTR_SCONN.SCONN288_H44441003(CHIPS)':
 'DQS1P': CDS_PINID='DQS1P';
NET_NAME
'M_D_DQS_DP<2>'
 '@BASEBOARD_FAB2_LIB.BASEBOARD_FAB2(SCH_1):M_D_DQS_DP'<2>:
 C_SIGNAL='@baseboard_fab2_lib.baseboard_fab2(sch_1):m_d_dqs_dp(2)';
NODE_NAME     U5D1 DM81
 '@BASEBOARD_FAB2_LIB.BASEBOARD_FAB2(SCH_1):PAGE26_I172@CHPSET_LIB.SKX_EXT_B(CHIPS)':
 'DDR3_DQS_DP'<2>: CDS_PINID='DDR3_DQS_DP(2)';
NODE_NAME     J4B1 175
 '@BASEBOARD_FAB2_LIB.BASEBOARD_FAB2(SCH_1):PAGE49_I66@MSTR_SCONN.SCONN288_H44441004(CHIPS)':
 'DQS2P': CDS_PINID='DQS2P';
NODE_NAME     J6M1 175
 '@BASEBOARD_FAB2_LIB.BASEBOARD_FAB2(SCH_1):PAGE50_I46@MSTR_SCONN.SCONN288_H44441003(CHIPS)':
 'DQS2P': CDS_PINID='DQS2P';
NET_NAME
'M_D_DQS_DP<3>'
 '@BASEBOARD_FAB2_LIB.BASEBOARD_FAB2(SCH_1):M_D_DQS_DP'<3>:
 C_SIGNAL='@baseboard_fab2_lib.baseboard_fab2(sch_1):m_d_dqs_dp(3)';
NODE_NAME     U5D1 DT75
 '@BASEBOARD_FAB2_LIB.BASEBOARD_FAB2(SCH_1):PAGE26_I172@CHPSET_LIB.SKX_EXT_B(CHIPS)':
 'DDR3_DQS_DP'<3>: CDS_PINID='DDR3_DQS_DP(3)';
NODE_NAME     J4B1 186
 '@BASEBOARD_FAB2_LIB.BASEBOARD_FAB2(SCH_1):PAGE49_I66@MSTR_SCONN.SCONN288_H44441004(CHIPS)':
 'DQS3P': CDS_PINID='DQS3P';
NODE_NAME     J6M1 186
 '@BASEBOARD_FAB2_LIB.BASEBOARD_FAB2(SCH_1):PAGE50_I46@MSTR_SCONN.SCONN288_H44441003(CHIPS)':
 'DQS3P': CDS_PINID='DQS3P';
NET_NAME
'M_D_DQS_DP<4>'
 '@BASEBOARD_FAB2_LIB.BASEBOARD_FAB2(SCH_1):M_D_DQS_DP'<4>:
 C_SIGNAL='@baseboard_fab2_lib.baseboard_fab2(sch_1):m_d_dqs_dp(4)';
NODE_NAME     U5D1 EC38
 '@BASEBOARD_FAB2_LIB.BASEBOARD_FAB2(SCH_1):PAGE26_I172@CHPSET_LIB.SKX_EXT_B(CHIPS)':
 'DDR3_DQS_DP'<4>: CDS_PINID='DDR3_DQS_DP(4)';
NODE_NAME     J4B1 245
 '@BASEBOARD_FAB2_LIB.BASEBOARD_FAB2(SCH_1):PAGE49_I66@MSTR_SCONN.SCONN288_H44441004(CHIPS)':
 'DQS4P': CDS_PINID='DQS4P';
NODE_NAME     J6M1 245
 '@BASEBOARD_FAB2_LIB.BASEBOARD_FAB2(SCH_1):PAGE50_I46@MSTR_SCONN.SCONN288_H44441003(CHIPS)':
 'DQS4P': CDS_PINID='DQS4P';
NET_NAME
'M_D_DQS_DP<5>'
 '@BASEBOARD_FAB2_LIB.BASEBOARD_FAB2(SCH_1):M_D_DQS_DP'<5>:
 C_SIGNAL='@baseboard_fab2_lib.baseboard_fab2(sch_1):m_d_dqs_dp(5)';
NODE_NAME     U5D1 DT35
 '@BASEBOARD_FAB2_LIB.BASEBOARD_FAB2(SCH_1):PAGE26_I172@CHPSET_LIB.SKX_EXT_B(CHIPS)':
 'DDR3_DQS_DP'<5>: CDS_PINID='DDR3_DQS_DP(5)';
NODE_NAME     J4B1 256
 '@BASEBOARD_FAB2_LIB.BASEBOARD_FAB2(SCH_1):PAGE49_I66@MSTR_SCONN.SCONN288_H44441004(CHIPS)':
 'DQS5P': CDS_PINID='DQS5P';
NODE_NAME     J6M1 256
 '@BASEBOARD_FAB2_LIB.BASEBOARD_FAB2(SCH_1):PAGE50_I46@MSTR_SCONN.SCONN288_H44441003(CHIPS)':
 'DQS5P': CDS_PINID='DQS5P';
NET_NAME
'M_D_DQS_DP<6>'
 '@BASEBOARD_FAB2_LIB.BASEBOARD_FAB2(SCH_1):M_D_DQS_DP'<6>:
 C_SIGNAL='@baseboard_fab2_lib.baseboard_fab2(sch_1):m_d_dqs_dp(6)';
NODE_NAME     U5D1 DT29
 '@BASEBOARD_FAB2_LIB.BASEBOARD_FAB2(SCH_1):PAGE26_I172@CHPSET_LIB.SKX_EXT_B(CHIPS)':
 'DDR3_DQS_DP'<6>: CDS_PINID='DDR3_DQS_DP(6)';
NODE_NAME     J4B1 267
 '@BASEBOARD_FAB2_LIB.BASEBOARD_FAB2(SCH_1):PAGE49_I66@MSTR_SCONN.SCONN288_H44441004(CHIPS)':
 'DQS6P': CDS_PINID='DQS6P';
NODE_NAME     J6M1 267
 '@BASEBOARD_FAB2_LIB.BASEBOARD_FAB2(SCH_1):PAGE50_I46@MSTR_SCONN.SCONN288_H44441003(CHIPS)':
 'DQS6P': CDS_PINID='DQS6P';
NET_NAME
'M_D_DQS_DP<7>'
 '@BASEBOARD_FAB2_LIB.BASEBOARD_FAB2(SCH_1):M_D_DQS_DP'<7>:
 C_SIGNAL='@baseboard_fab2_lib.baseboard_fab2(sch_1):m_d_dqs_dp(7)';
NODE_NAME     U5D1 DT23
 '@BASEBOARD_FAB2_LIB.BASEBOARD_FAB2(SCH_1):PAGE26_I172@CHPSET_LIB.SKX_EXT_B(CHIPS)':
 'DDR3_DQS_DP'<7>: CDS_PINID='DDR3_DQS_DP(7)';
NODE_NAME     J4B1 278
 '@BASEBOARD_FAB2_LIB.BASEBOARD_FAB2(SCH_1):PAGE49_I66@MSTR_SCONN.SCONN288_H44441004(CHIPS)':
 'DQS7P': CDS_PINID='DQS7P';
NODE_NAME     J6M1 278
 '@BASEBOARD_FAB2_LIB.BASEBOARD_FAB2(SCH_1):PAGE50_I46@MSTR_SCONN.SCONN288_H44441003(CHIPS)':
 'DQS7P': CDS_PINID='DQS7P';
NET_NAME
'M_D_DQS_DP<8>'
 '@BASEBOARD_FAB2_LIB.BASEBOARD_FAB2(SCH_1):M_D_DQS_DP'<8>:
 C_SIGNAL='@baseboard_fab2_lib.baseboard_fab2(sch_1):m_d_dqs_dp(8)';
NODE_NAME     U5D1 DD67
 '@BASEBOARD_FAB2_LIB.BASEBOARD_FAB2(SCH_1):PAGE26_I172@CHPSET_LIB.SKX_EXT_B(CHIPS)':
 'DDR3_DQS_DP'<8>: CDS_PINID='DDR3_DQS_DP(8)';
NODE_NAME     J4B1 197
 '@BASEBOARD_FAB2_LIB.BASEBOARD_FAB2(SCH_1):PAGE49_I66@MSTR_SCONN.SCONN288_H44441004(CHIPS)':
 'DQS8P': CDS_PINID='DQS8P';
NODE_NAME     J6M1 197
 '@BASEBOARD_FAB2_LIB.BASEBOARD_FAB2(SCH_1):PAGE50_I46@MSTR_SCONN.SCONN288_H44441003(CHIPS)':
 'DQS8P': CDS_PINID='DQS8P';
NET_NAME
'M_D_DQS_DP<9>'
 '@BASEBOARD_FAB2_LIB.BASEBOARD_FAB2(SCH_1):M_D_DQS_DP'<9>:
 C_SIGNAL='@baseboard_fab2_lib.baseboard_fab2(sch_1):m_d_dqs_dp(9)';
NODE_NAME     U5D1 CP85
 '@BASEBOARD_FAB2_LIB.BASEBOARD_FAB2(SCH_1):PAGE26_I172@CHPSET_LIB.SKX_EXT_B(CHIPS)':
 'DDR3_DQS_DP'<9>: CDS_PINID='DDR3_DQS_DP(9)';
NODE_NAME     J4B1 7
 '@BASEBOARD_FAB2_LIB.BASEBOARD_FAB2(SCH_1):PAGE49_I66@MSTR_SCONN.SCONN288_H44441004(CHIPS)':
 'DQS9P': CDS_PINID='DQS9P';
NODE_NAME     J6M1 7
 '@BASEBOARD_FAB2_LIB.BASEBOARD_FAB2(SCH_1):PAGE50_I46@MSTR_SCONN.SCONN288_H44441003(CHIPS)':
 'DQS9P': CDS_PINID='DQS9P';
NET_NAME
'M_D_ECC<0>'
 '@BASEBOARD_FAB2_LIB.BASEBOARD_FAB2(SCH_1):M_D_ECC'<0>:
 C_SIGNAL='@baseboard_fab2_lib.baseboard_fab2(sch_1):m_d_ecc(0)';
NODE_NAME     U5D1 DA68
 '@BASEBOARD_FAB2_LIB.BASEBOARD_FAB2(SCH_1):PAGE26_I172@CHPSET_LIB.SKX_EXT_B(CHIPS)':
 'DDR3_ECC'<0>: CDS_PINID='DDR3_ECC(0)';
NODE_NAME     J4B1 194
 '@BASEBOARD_FAB2_LIB.BASEBOARD_FAB2(SCH_1):PAGE49_I111@MSTR_SCONN.SCONN288_H44441004(CHIPS)':
 'CB'<1>: CDS_PINID='CB(1)';
NODE_NAME     J6M1 49
 '@BASEBOARD_FAB2_LIB.BASEBOARD_FAB2(SCH_1):PAGE50_I158@MSTR_SCONN.SCONN288_H44441003(CHIPS)':
 'CB'<0>: CDS_PINID='CB(0)';
NET_NAME
'M_D_ECC<1>'
 '@BASEBOARD_FAB2_LIB.BASEBOARD_FAB2(SCH_1):M_D_ECC'<1>:
 C_SIGNAL='@baseboard_fab2_lib.baseboard_fab2(sch_1):m_d_ecc(1)';
NODE_NAME     U5D1 DE68
 '@BASEBOARD_FAB2_LIB.BASEBOARD_FAB2(SCH_1):PAGE26_I172@CHPSET_LIB.SKX_EXT_B(CHIPS)':
 'DDR3_ECC'<1>: CDS_PINID='DDR3_ECC(1)';
NODE_NAME     J4B1 49
 '@BASEBOARD_FAB2_LIB.BASEBOARD_FAB2(SCH_1):PAGE49_I111@MSTR_SCONN.SCONN288_H44441004(CHIPS)':
 'CB'<0>: CDS_PINID='CB(0)';
NODE_NAME     J6M1 194
 '@BASEBOARD_FAB2_LIB.BASEBOARD_FAB2(SCH_1):PAGE50_I158@MSTR_SCONN.SCONN288_H44441003(CHIPS)':
 'CB'<1>: CDS_PINID='CB(1)';
NET_NAME
'M_D_ECC<2>'
 '@BASEBOARD_FAB2_LIB.BASEBOARD_FAB2(SCH_1):M_D_ECC'<2>:
 C_SIGNAL='@baseboard_fab2_lib.baseboard_fab2(sch_1):m_d_ecc(2)';
NODE_NAME     U5D1 DB65
 '@BASEBOARD_FAB2_LIB.BASEBOARD_FAB2(SCH_1):PAGE26_I172@CHPSET_LIB.SKX_EXT_B(CHIPS)':
 'DDR3_ECC'<2>: CDS_PINID='DDR3_ECC(2)';
NODE_NAME     J4B1 201
 '@BASEBOARD_FAB2_LIB.BASEBOARD_FAB2(SCH_1):PAGE49_I111@MSTR_SCONN.SCONN288_H44441004(CHIPS)':
 'CB'<3>: CDS_PINID='CB(3)';
NODE_NAME     J6M1 56
 '@BASEBOARD_FAB2_LIB.BASEBOARD_FAB2(SCH_1):PAGE50_I158@MSTR_SCONN.SCONN288_H44441003(CHIPS)':
 'CB'<2>: CDS_PINID='CB(2)';
NET_NAME
'M_D_ECC<3>'
 '@BASEBOARD_FAB2_LIB.BASEBOARD_FAB2(SCH_1):M_D_ECC'<3>:
 C_SIGNAL='@baseboard_fab2_lib.baseboard_fab2(sch_1):m_d_ecc(3)';
NODE_NAME     U5D1 DD65
 '@BASEBOARD_FAB2_LIB.BASEBOARD_FAB2(SCH_1):PAGE26_I172@CHPSET_LIB.SKX_EXT_B(CHIPS)':
 'DDR3_ECC'<3>: CDS_PINID='DDR3_ECC(3)';
NODE_NAME     J4B1 56
 '@BASEBOARD_FAB2_LIB.BASEBOARD_FAB2(SCH_1):PAGE49_I111@MSTR_SCONN.SCONN288_H44441004(CHIPS)':
 'CB'<2>: CDS_PINID='CB(2)';
NODE_NAME     J6M1 201
 '@BASEBOARD_FAB2_LIB.BASEBOARD_FAB2(SCH_1):PAGE50_I158@MSTR_SCONN.SCONN288_H44441003(CHIPS)':
 'CB'<3>: CDS_PINID='CB(3)';
NET_NAME
'M_D_ECC<4>'
 '@BASEBOARD_FAB2_LIB.BASEBOARD_FAB2(SCH_1):M_D_ECC'<4>:
 C_SIGNAL='@baseboard_fab2_lib.baseboard_fab2(sch_1):m_d_ecc(4)';
NODE_NAME     U5D1 DB69
 '@BASEBOARD_FAB2_LIB.BASEBOARD_FAB2(SCH_1):PAGE26_I172@CHPSET_LIB.SKX_EXT_B(CHIPS)':
 'DDR3_ECC'<4>: CDS_PINID='DDR3_ECC(4)';
NODE_NAME     J4B1 192
 '@BASEBOARD_FAB2_LIB.BASEBOARD_FAB2(SCH_1):PAGE49_I111@MSTR_SCONN.SCONN288_H44441004(CHIPS)':
 'CB'<5>: CDS_PINID='CB(5)';
NODE_NAME     J6M1 47
 '@BASEBOARD_FAB2_LIB.BASEBOARD_FAB2(SCH_1):PAGE50_I158@MSTR_SCONN.SCONN288_H44441003(CHIPS)':
 'CB'<4>: CDS_PINID='CB(4)';
NET_NAME
'M_D_ECC<5>'
 '@BASEBOARD_FAB2_LIB.BASEBOARD_FAB2(SCH_1):M_D_ECC'<5>:
 C_SIGNAL='@baseboard_fab2_lib.baseboard_fab2(sch_1):m_d_ecc(5)';
NODE_NAME     U5D1 DD69
 '@BASEBOARD_FAB2_LIB.BASEBOARD_FAB2(SCH_1):PAGE26_I172@CHPSET_LIB.SKX_EXT_B(CHIPS)':
 'DDR3_ECC'<5>: CDS_PINID='DDR3_ECC(5)';
NODE_NAME     J4B1 47
 '@BASEBOARD_FAB2_LIB.BASEBOARD_FAB2(SCH_1):PAGE49_I111@MSTR_SCONN.SCONN288_H44441004(CHIPS)':
 'CB'<4>: CDS_PINID='CB(4)';
NODE_NAME     J6M1 192
 '@BASEBOARD_FAB2_LIB.BASEBOARD_FAB2(SCH_1):PAGE50_I158@MSTR_SCONN.SCONN288_H44441003(CHIPS)':
 'CB'<5>: CDS_PINID='CB(5)';
NET_NAME
'M_D_ECC<6>'
 '@BASEBOARD_FAB2_LIB.BASEBOARD_FAB2(SCH_1):M_D_ECC'<6>:
 C_SIGNAL='@baseboard_fab2_lib.baseboard_fab2(sch_1):m_d_ecc(6)';
NODE_NAME     U5D1 DA66
 '@BASEBOARD_FAB2_LIB.BASEBOARD_FAB2(SCH_1):PAGE26_I172@CHPSET_LIB.SKX_EXT_B(CHIPS)':
 'DDR3_ECC'<6>: CDS_PINID='DDR3_ECC(6)';
NODE_NAME     J4B1 199
 '@BASEBOARD_FAB2_LIB.BASEBOARD_FAB2(SCH_1):PAGE49_I111@MSTR_SCONN.SCONN288_H44441004(CHIPS)':
 'CB'<7>: CDS_PINID='CB(7)';
NODE_NAME     J6M1 54
 '@BASEBOARD_FAB2_LIB.BASEBOARD_FAB2(SCH_1):PAGE50_I158@MSTR_SCONN.SCONN288_H44441003(CHIPS)':
 'CB'<6>: CDS_PINID='CB(6)';
NET_NAME
'M_D_ECC<7>'
 '@BASEBOARD_FAB2_LIB.BASEBOARD_FAB2(SCH_1):M_D_ECC'<7>:
 C_SIGNAL='@baseboard_fab2_lib.baseboard_fab2(sch_1):m_d_ecc(7)';
NODE_NAME     U5D1 DE66
 '@BASEBOARD_FAB2_LIB.BASEBOARD_FAB2(SCH_1):PAGE26_I172@CHPSET_LIB.SKX_EXT_B(CHIPS)':
 'DDR3_ECC'<7>: CDS_PINID='DDR3_ECC(7)';
NODE_NAME     J4B1 54
 '@BASEBOARD_FAB2_LIB.BASEBOARD_FAB2(SCH_1):PAGE49_I111@MSTR_SCONN.SCONN288_H44441004(CHIPS)':
 'CB'<6>: CDS_PINID='CB(6)';
NODE_NAME     J6M1 199
 '@BASEBOARD_FAB2_LIB.BASEBOARD_FAB2(SCH_1):PAGE50_I158@MSTR_SCONN.SCONN288_H44441003(CHIPS)':
 'CB'<7>: CDS_PINID='CB(7)';
NET_NAME
'M_D_MA<0>'
 '@BASEBOARD_FAB2_LIB.BASEBOARD_FAB2(SCH_1):M_D_MA'<0>:
 C_SIGNAL='@baseboard_fab2_lib.baseboard_fab2(sch_1):m_d_ma(0)';
NODE_NAME     U5D1 EB53
 '@BASEBOARD_FAB2_LIB.BASEBOARD_FAB2(SCH_1):PAGE26_I172@CHPSET_LIB.SKX_EXT_B(CHIPS)':
 'DDR3_MA'<0>: CDS_PINID='DDR3_MA(0)';
NODE_NAME     J4B1 79
 '@BASEBOARD_FAB2_LIB.BASEBOARD_FAB2(SCH_1):PAGE49_I111@MSTR_SCONN.SCONN288_H44441004(CHIPS)':
 'A0': CDS_PINID='A0';
NODE_NAME     J6M1 79
 '@BASEBOARD_FAB2_LIB.BASEBOARD_FAB2(SCH_1):PAGE50_I158@MSTR_SCONN.SCONN288_H44441003(CHIPS)':
 'A0': CDS_PINID='A0';
NET_NAME
'M_D_MA<10>'
 '@BASEBOARD_FAB2_LIB.BASEBOARD_FAB2(SCH_1):M_D_MA'<10>:
 C_SIGNAL='@baseboard_fab2_lib.baseboard_fab2(sch_1):m_d_ma(10)';
NODE_NAME     U5D1 DW54
 '@BASEBOARD_FAB2_LIB.BASEBOARD_FAB2(SCH_1):PAGE26_I172@CHPSET_LIB.SKX_EXT_B(CHIPS)':
 'DDR3_MA'<10>: CDS_PINID='DDR3_MA(10)';
NODE_NAME     J4B1 225
 '@BASEBOARD_FAB2_LIB.BASEBOARD_FAB2(SCH_1):PAGE49_I111@MSTR_SCONN.SCONN288_H44441004(CHIPS)':
 'A10': CDS_PINID='A10';
NODE_NAME     J6M1 225
 '@BASEBOARD_FAB2_LIB.BASEBOARD_FAB2(SCH_1):PAGE50_I158@MSTR_SCONN.SCONN288_H44441003(CHIPS)':
 'A10': CDS_PINID='A10';
NET_NAME
'M_D_MA<11>'
 '@BASEBOARD_FAB2_LIB.BASEBOARD_FAB2(SCH_1):M_D_MA'<11>:
 C_SIGNAL='@baseboard_fab2_lib.baseboard_fab2(sch_1):m_d_ma(11)';
NODE_NAME     U5D1 EB61
 '@BASEBOARD_FAB2_LIB.BASEBOARD_FAB2(SCH_1):PAGE26_I172@CHPSET_LIB.SKX_EXT_B(CHIPS)':
 'DDR3_MA'<11>: CDS_PINID='DDR3_MA(11)';
NODE_NAME     J4B1 210
 '@BASEBOARD_FAB2_LIB.BASEBOARD_FAB2(SCH_1):PAGE49_I111@MSTR_SCONN.SCONN288_H44441004(CHIPS)':
 'A11': CDS_PINID='A11';
NODE_NAME     J6M1 210
 '@BASEBOARD_FAB2_LIB.BASEBOARD_FAB2(SCH_1):PAGE50_I158@MSTR_SCONN.SCONN288_H44441003(CHIPS)':
 'A11': CDS_PINID='A11';
NET_NAME
'M_D_MA<12>'
 '@BASEBOARD_FAB2_LIB.BASEBOARD_FAB2(SCH_1):M_D_MA'<12>:
 C_SIGNAL='@baseboard_fab2_lib.baseboard_fab2(sch_1):m_d_ma(12)';
NODE_NAME     U5D1 DT63
 '@BASEBOARD_FAB2_LIB.BASEBOARD_FAB2(SCH_1):PAGE26_I172@CHPSET_LIB.SKX_EXT_B(CHIPS)':
 'DDR3_MA'<12>: CDS_PINID='DDR3_MA(12)';
NODE_NAME     J4B1 65
 '@BASEBOARD_FAB2_LIB.BASEBOARD_FAB2(SCH_1):PAGE49_I111@MSTR_SCONN.SCONN288_H44441004(CHIPS)':
 'A12': CDS_PINID='A12';
NODE_NAME     J6M1 65
 '@BASEBOARD_FAB2_LIB.BASEBOARD_FAB2(SCH_1):PAGE50_I158@MSTR_SCONN.SCONN288_H44441003(CHIPS)':
 'A12': CDS_PINID='A12';
NET_NAME
'M_D_MA<13>'
 '@BASEBOARD_FAB2_LIB.BASEBOARD_FAB2(SCH_1):M_D_MA'<13>:
 C_SIGNAL='@baseboard_fab2_lib.baseboard_fab2(sch_1):m_d_ma(13)';
NODE_NAME     U5D1 DW48
 '@BASEBOARD_FAB2_LIB.BASEBOARD_FAB2(SCH_1):PAGE26_I172@CHPSET_LIB.SKX_EXT_B(CHIPS)':
 'DDR3_MA'<13>: CDS_PINID='DDR3_MA(13)';
NODE_NAME     J4B1 232
 '@BASEBOARD_FAB2_LIB.BASEBOARD_FAB2(SCH_1):PAGE49_I111@MSTR_SCONN.SCONN288_H44441004(CHIPS)':
 'A13': CDS_PINID='A13';
NODE_NAME     J6M1 232
 '@BASEBOARD_FAB2_LIB.BASEBOARD_FAB2(SCH_1):PAGE50_I158@MSTR_SCONN.SCONN288_H44441003(CHIPS)':
 'A13': CDS_PINID='A13';
NET_NAME
'M_D_MA<14>'
 '@BASEBOARD_FAB2_LIB.BASEBOARD_FAB2(SCH_1):M_D_MA'<14>:
 C_SIGNAL='@baseboard_fab2_lib.baseboard_fab2(sch_1):m_d_ma(14)';
NODE_NAME     U5D1 ED51
 '@BASEBOARD_FAB2_LIB.BASEBOARD_FAB2(SCH_1):PAGE26_I172@CHPSET_LIB.SKX_EXT_B(CHIPS)':
 'DDR3_MA'<14>: CDS_PINID='DDR3_MA(14)';
NODE_NAME     J4B1 228
 '@BASEBOARD_FAB2_LIB.BASEBOARD_FAB2(SCH_1):PAGE49_I111@MSTR_SCONN.SCONN288_H44441004(CHIPS)':
 'A14_WE_N': CDS_PINID='A14_WE_N';
NODE_NAME     J6M1 228
 '@BASEBOARD_FAB2_LIB.BASEBOARD_FAB2(SCH_1):PAGE50_I158@MSTR_SCONN.SCONN288_H44441003(CHIPS)':
 'A14_WE_N': CDS_PINID='A14_WE_N';
NET_NAME
'M_D_MA<15>'
 '@BASEBOARD_FAB2_LIB.BASEBOARD_FAB2(SCH_1):M_D_MA'<15>:
 C_SIGNAL='@baseboard_fab2_lib.baseboard_fab2(sch_1):m_d_ma(15)';
NODE_NAME     U5D1 DV49
 '@BASEBOARD_FAB2_LIB.BASEBOARD_FAB2(SCH_1):PAGE26_I172@CHPSET_LIB.SKX_EXT_B(CHIPS)':
 'DDR3_MA'<15>: CDS_PINID='DDR3_MA(15)';
NODE_NAME     J4B1 86
 '@BASEBOARD_FAB2_LIB.BASEBOARD_FAB2(SCH_1):PAGE49_I111@MSTR_SCONN.SCONN288_H44441004(CHIPS)':
 'A15_CAS_N': CDS_PINID='A15_CAS_N';
NODE_NAME     J6M1 86
 '@BASEBOARD_FAB2_LIB.BASEBOARD_FAB2(SCH_1):PAGE50_I158@MSTR_SCONN.SCONN288_H44441003(CHIPS)':
 'A15_CAS_N': CDS_PINID='A15_CAS_N';
NET_NAME
'M_D_MA<16>'
 '@BASEBOARD_FAB2_LIB.BASEBOARD_FAB2(SCH_1):M_D_MA'<16>:
 C_SIGNAL='@baseboard_fab2_lib.baseboard_fab2(sch_1):m_d_ma(16)';
NODE_NAME     U5D1 EA52
 '@BASEBOARD_FAB2_LIB.BASEBOARD_FAB2(SCH_1):PAGE26_I172@CHPSET_LIB.SKX_EXT_B(CHIPS)':
 'DDR3_MA'<16>: CDS_PINID='DDR3_MA(16)';
NODE_NAME     J4B1 82
 '@BASEBOARD_FAB2_LIB.BASEBOARD_FAB2(SCH_1):PAGE49_I111@MSTR_SCONN.SCONN288_H44441004(CHIPS)':
 'A16_RAS_N': CDS_PINID='A16_RAS_N';
NODE_NAME     J6M1 82
 '@BASEBOARD_FAB2_LIB.BASEBOARD_FAB2(SCH_1):PAGE50_I158@MSTR_SCONN.SCONN288_H44441003(CHIPS)':
 'A16_RAS_N': CDS_PINID='A16_RAS_N';
NET_NAME
'M_D_MA<17>'
 '@BASEBOARD_FAB2_LIB.BASEBOARD_FAB2(SCH_1):M_D_MA'<17>:
 C_SIGNAL='@baseboard_fab2_lib.baseboard_fab2(sch_1):m_d_ma(17)';
NODE_NAME     U5D1 EA46
 '@BASEBOARD_FAB2_LIB.BASEBOARD_FAB2(SCH_1):PAGE26_I172@CHPSET_LIB.SKX_EXT_B(CHIPS)':
 'DDR3_MA'<17>: CDS_PINID='DDR3_MA(17)';
NODE_NAME     J4B1 234
 '@BASEBOARD_FAB2_LIB.BASEBOARD_FAB2(SCH_1):PAGE49_I111@MSTR_SCONN.SCONN288_H44441004(CHIPS)':
 'A17': CDS_PINID='A17';
NODE_NAME     J6M1 234
 '@BASEBOARD_FAB2_LIB.BASEBOARD_FAB2(SCH_1):PAGE50_I158@MSTR_SCONN.SCONN288_H44441003(CHIPS)':
 'A17': CDS_PINID='A17';
NET_NAME
'M_D_MA<1>'
 '@BASEBOARD_FAB2_LIB.BASEBOARD_FAB2(SCH_1):M_D_MA'<1>:
 C_SIGNAL='@baseboard_fab2_lib.baseboard_fab2(sch_1):m_d_ma(1)';
NODE_NAME     U5D1 ED57
 '@BASEBOARD_FAB2_LIB.BASEBOARD_FAB2(SCH_1):PAGE26_I172@CHPSET_LIB.SKX_EXT_B(CHIPS)':
 'DDR3_MA'<1>: CDS_PINID='DDR3_MA(1)';
NODE_NAME     J4B1 72
 '@BASEBOARD_FAB2_LIB.BASEBOARD_FAB2(SCH_1):PAGE49_I111@MSTR_SCONN.SCONN288_H44441004(CHIPS)':
 'A1': CDS_PINID='A1';
NODE_NAME     J6M1 72
 '@BASEBOARD_FAB2_LIB.BASEBOARD_FAB2(SCH_1):PAGE50_I158@MSTR_SCONN.SCONN288_H44441003(CHIPS)':
 'A1': CDS_PINID='A1';
NET_NAME
'M_D_MA<2>'
 '@BASEBOARD_FAB2_LIB.BASEBOARD_FAB2(SCH_1):M_D_MA'<2>:
 C_SIGNAL='@baseboard_fab2_lib.baseboard_fab2(sch_1):m_d_ma(2)';
NODE_NAME     U5D1 EE58
 '@BASEBOARD_FAB2_LIB.BASEBOARD_FAB2(SCH_1):PAGE26_I172@CHPSET_LIB.SKX_EXT_B(CHIPS)':
 'DDR3_MA'<2>: CDS_PINID='DDR3_MA(2)';
NODE_NAME     J4B1 216
 '@BASEBOARD_FAB2_LIB.BASEBOARD_FAB2(SCH_1):PAGE49_I111@MSTR_SCONN.SCONN288_H44441004(CHIPS)':
 'A2': CDS_PINID='A2';
NODE_NAME     J6M1 216
 '@BASEBOARD_FAB2_LIB.BASEBOARD_FAB2(SCH_1):PAGE50_I158@MSTR_SCONN.SCONN288_H44441003(CHIPS)':
 'A2': CDS_PINID='A2';
NET_NAME
'M_D_MA<3>'
 '@BASEBOARD_FAB2_LIB.BASEBOARD_FAB2(SCH_1):M_D_MA'<3>:
 C_SIGNAL='@baseboard_fab2_lib.baseboard_fab2(sch_1):m_d_ma(3)';
NODE_NAME     U5D1 EB57
 '@BASEBOARD_FAB2_LIB.BASEBOARD_FAB2(SCH_1):PAGE26_I172@CHPSET_LIB.SKX_EXT_B(CHIPS)':
 'DDR3_MA'<3>: CDS_PINID='DDR3_MA(3)';
NODE_NAME     J4B1 71
 '@BASEBOARD_FAB2_LIB.BASEBOARD_FAB2(SCH_1):PAGE49_I111@MSTR_SCONN.SCONN288_H44441004(CHIPS)':
 'A3': CDS_PINID='A3';
NODE_NAME     J6M1 71
 '@BASEBOARD_FAB2_LIB.BASEBOARD_FAB2(SCH_1):PAGE50_I158@MSTR_SCONN.SCONN288_H44441003(CHIPS)':
 'A3': CDS_PINID='A3';
NET_NAME
'M_D_MA<4>'
 '@BASEBOARD_FAB2_LIB.BASEBOARD_FAB2(SCH_1):M_D_MA'<4>:
 C_SIGNAL='@baseboard_fab2_lib.baseboard_fab2(sch_1):m_d_ma(4)';
NODE_NAME     U5D1 ED59
 '@BASEBOARD_FAB2_LIB.BASEBOARD_FAB2(SCH_1):PAGE26_I172@CHPSET_LIB.SKX_EXT_B(CHIPS)':
 'DDR3_MA'<4>: CDS_PINID='DDR3_MA(4)';
NODE_NAME     J4B1 214
 '@BASEBOARD_FAB2_LIB.BASEBOARD_FAB2(SCH_1):PAGE49_I111@MSTR_SCONN.SCONN288_H44441004(CHIPS)':
 'A4': CDS_PINID='A4';
NODE_NAME     J6M1 214
 '@BASEBOARD_FAB2_LIB.BASEBOARD_FAB2(SCH_1):PAGE50_I158@MSTR_SCONN.SCONN288_H44441003(CHIPS)':
 'A4': CDS_PINID='A4';
NET_NAME
'M_D_MA<5>'
 '@BASEBOARD_FAB2_LIB.BASEBOARD_FAB2(SCH_1):M_D_MA'<5>:
 C_SIGNAL='@baseboard_fab2_lib.baseboard_fab2(sch_1):m_d_ma(5)';
NODE_NAME     U5D1 EA58
 '@BASEBOARD_FAB2_LIB.BASEBOARD_FAB2(SCH_1):PAGE26_I172@CHPSET_LIB.SKX_EXT_B(CHIPS)':
 'DDR3_MA'<5>: CDS_PINID='DDR3_MA(5)';
NODE_NAME     J4B1 213
 '@BASEBOARD_FAB2_LIB.BASEBOARD_FAB2(SCH_1):PAGE49_I111@MSTR_SCONN.SCONN288_H44441004(CHIPS)':
 'A5': CDS_PINID='A5';
NODE_NAME     J6M1 213
 '@BASEBOARD_FAB2_LIB.BASEBOARD_FAB2(SCH_1):PAGE50_I158@MSTR_SCONN.SCONN288_H44441003(CHIPS)':
 'A5': CDS_PINID='A5';
NET_NAME
'M_D_MA<6>'
 '@BASEBOARD_FAB2_LIB.BASEBOARD_FAB2(SCH_1):M_D_MA'<6>:
 C_SIGNAL='@baseboard_fab2_lib.baseboard_fab2(sch_1):m_d_ma(6)';
NODE_NAME     U5D1 EE60
 '@BASEBOARD_FAB2_LIB.BASEBOARD_FAB2(SCH_1):PAGE26_I172@CHPSET_LIB.SKX_EXT_B(CHIPS)':
 'DDR3_MA'<6>: CDS_PINID='DDR3_MA(6)';
NODE_NAME     J4B1 69
 '@BASEBOARD_FAB2_LIB.BASEBOARD_FAB2(SCH_1):PAGE49_I111@MSTR_SCONN.SCONN288_H44441004(CHIPS)':
 'A6': CDS_PINID='A6';
NODE_NAME     J6M1 69
 '@BASEBOARD_FAB2_LIB.BASEBOARD_FAB2(SCH_1):PAGE50_I158@MSTR_SCONN.SCONN288_H44441003(CHIPS)':
 'A6': CDS_PINID='A6';
NET_NAME
'M_D_MA<7>'
 '@BASEBOARD_FAB2_LIB.BASEBOARD_FAB2(SCH_1):M_D_MA'<7>:
 C_SIGNAL='@baseboard_fab2_lib.baseboard_fab2(sch_1):m_d_ma(7)';
NODE_NAME     U5D1 EA60
 '@BASEBOARD_FAB2_LIB.BASEBOARD_FAB2(SCH_1):PAGE26_I172@CHPSET_LIB.SKX_EXT_B(CHIPS)':
 'DDR3_MA'<7>: CDS_PINID='DDR3_MA(7)';
NODE_NAME     J4B1 211
 '@BASEBOARD_FAB2_LIB.BASEBOARD_FAB2(SCH_1):PAGE49_I111@MSTR_SCONN.SCONN288_H44441004(CHIPS)':
 'A7': CDS_PINID='A7';
NODE_NAME     J6M1 211
 '@BASEBOARD_FAB2_LIB.BASEBOARD_FAB2(SCH_1):PAGE50_I158@MSTR_SCONN.SCONN288_H44441003(CHIPS)':
 'A7': CDS_PINID='A7';
NET_NAME
'M_D_MA<8>'
 '@BASEBOARD_FAB2_LIB.BASEBOARD_FAB2(SCH_1):M_D_MA'<8>:
 C_SIGNAL='@baseboard_fab2_lib.baseboard_fab2(sch_1):m_d_ma(8)';
NODE_NAME     U5D1 EB59
 '@BASEBOARD_FAB2_LIB.BASEBOARD_FAB2(SCH_1):PAGE26_I172@CHPSET_LIB.SKX_EXT_B(CHIPS)':
 'DDR3_MA'<8>: CDS_PINID='DDR3_MA(8)';
NODE_NAME     J4B1 68
 '@BASEBOARD_FAB2_LIB.BASEBOARD_FAB2(SCH_1):PAGE49_I111@MSTR_SCONN.SCONN288_H44441004(CHIPS)':
 'A8': CDS_PINID='A8';
NODE_NAME     J6M1 68
 '@BASEBOARD_FAB2_LIB.BASEBOARD_FAB2(SCH_1):PAGE50_I158@MSTR_SCONN.SCONN288_H44441003(CHIPS)':
 'A8': CDS_PINID='A8';
NET_NAME
'M_D_MA<9>'
 '@BASEBOARD_FAB2_LIB.BASEBOARD_FAB2(SCH_1):M_D_MA'<9>:
 C_SIGNAL='@baseboard_fab2_lib.baseboard_fab2(sch_1):m_d_ma(9)';
NODE_NAME     U5D1 EF61
 '@BASEBOARD_FAB2_LIB.BASEBOARD_FAB2(SCH_1):PAGE26_I172@CHPSET_LIB.SKX_EXT_B(CHIPS)':
 'DDR3_MA'<9>: CDS_PINID='DDR3_MA(9)';
NODE_NAME     J4B1 66
 '@BASEBOARD_FAB2_LIB.BASEBOARD_FAB2(SCH_1):PAGE49_I111@MSTR_SCONN.SCONN288_H44441004(CHIPS)':
 'A9': CDS_PINID='A9';
NODE_NAME     J6M1 66
 '@BASEBOARD_FAB2_LIB.BASEBOARD_FAB2(SCH_1):PAGE50_I158@MSTR_SCONN.SCONN288_H44441003(CHIPS)':
 'A9': CDS_PINID='A9';
NET_NAME
'M_D_ODT<0>'
 '@BASEBOARD_FAB2_LIB.BASEBOARD_FAB2(SCH_1):M_D_ODT'<0>:
 C_SIGNAL='@baseboard_fab2_lib.baseboard_fab2(sch_1):m_d_odt(0)';
NODE_NAME     U5D1 EE50
 '@BASEBOARD_FAB2_LIB.BASEBOARD_FAB2(SCH_1):PAGE26_I172@CHPSET_LIB.SKX_EXT_B(CHIPS)':
 'DDR3_ODT'<0>: CDS_PINID='DDR3_ODT(0)';
NODE_NAME     J4B1 87
 '@BASEBOARD_FAB2_LIB.BASEBOARD_FAB2(SCH_1):PAGE49_I111@MSTR_SCONN.SCONN288_H44441004(CHIPS)':
 'ODT'<0>: CDS_PINID='ODT(0)';
NET_NAME
'M_D_ODT<1>'
 '@BASEBOARD_FAB2_LIB.BASEBOARD_FAB2(SCH_1):M_D_ODT'<1>:
 C_SIGNAL='@baseboard_fab2_lib.baseboard_fab2(sch_1):m_d_odt(1)';
NODE_NAME     U5D1 EE48
 '@BASEBOARD_FAB2_LIB.BASEBOARD_FAB2(SCH_1):PAGE26_I172@CHPSET_LIB.SKX_EXT_B(CHIPS)':
 'DDR3_ODT'<1>: CDS_PINID='DDR3_ODT(1)';
NODE_NAME     J4B1 91
 '@BASEBOARD_FAB2_LIB.BASEBOARD_FAB2(SCH_1):PAGE49_I111@MSTR_SCONN.SCONN288_H44441004(CHIPS)':
 'ODT'<1>: CDS_PINID='ODT(1)';
NET_NAME
'M_D_ODT<2>'
 '@BASEBOARD_FAB2_LIB.BASEBOARD_FAB2(SCH_1):M_D_ODT'<2>:
 C_SIGNAL='@baseboard_fab2_lib.baseboard_fab2(sch_1):m_d_odt(2)';
NODE_NAME     U5D1 EA50
 '@BASEBOARD_FAB2_LIB.BASEBOARD_FAB2(SCH_1):PAGE26_I172@CHPSET_LIB.SKX_EXT_B(CHIPS)':
 'DDR3_ODT'<2>: CDS_PINID='DDR3_ODT(2)';
NODE_NAME     J6M1 87
 '@BASEBOARD_FAB2_LIB.BASEBOARD_FAB2(SCH_1):PAGE50_I158@MSTR_SCONN.SCONN288_H44441003(CHIPS)':
 'ODT'<0>: CDS_PINID='ODT(0)';
NET_NAME
'M_D_ODT<3>'
 '@BASEBOARD_FAB2_LIB.BASEBOARD_FAB2(SCH_1):M_D_ODT'<3>:
 C_SIGNAL='@baseboard_fab2_lib.baseboard_fab2(sch_1):m_d_odt(3)';
NODE_NAME     U5D1 EA48
 '@BASEBOARD_FAB2_LIB.BASEBOARD_FAB2(SCH_1):PAGE26_I172@CHPSET_LIB.SKX_EXT_B(CHIPS)':
 'DDR3_ODT'<3>: CDS_PINID='DDR3_ODT(3)';
NODE_NAME     J6M1 91
 '@BASEBOARD_FAB2_LIB.BASEBOARD_FAB2(SCH_1):PAGE50_I158@MSTR_SCONN.SCONN288_H44441003(CHIPS)':
 'ODT'<1>: CDS_PINID='ODT(1)';
NET_NAME
'M_D_PAR'
 '@BASEBOARD_FAB2_LIB.BASEBOARD_FAB2(SCH_1):M_D_PAR':
 C_SIGNAL='@baseboard_fab2_lib.baseboard_fab2(sch_1):m_d_par';
NODE_NAME     U5D1 ED53
 '@BASEBOARD_FAB2_LIB.BASEBOARD_FAB2(SCH_1):PAGE26_I172@CHPSET_LIB.SKX_EXT_B(CHIPS)':
 'DDR3_PAR': CDS_PINID='DDR3_PAR';
NODE_NAME     J4B1 222
 '@BASEBOARD_FAB2_LIB.BASEBOARD_FAB2(SCH_1):PAGE49_I111@MSTR_SCONN.SCONN288_H44441004(CHIPS)':
 'PAR': CDS_PINID='PAR';
NODE_NAME     J6M1 222
 '@BASEBOARD_FAB2_LIB.BASEBOARD_FAB2(SCH_1):PAGE50_I158@MSTR_SCONN.SCONN288_H44441003(CHIPS)':
 'PAR': CDS_PINID='PAR';
NET_NAME
'M_D_VREF'
 '@BASEBOARD_FAB2_LIB.BASEBOARD_FAB2(SCH_1):M_D_VREF':
 C_SIGNAL='@baseboard_fab2_lib.baseboard_fab2(sch_1):m_d_vref';
NODE_NAME     J4B1 146
 '@BASEBOARD_FAB2_LIB.BASEBOARD_FAB2(SCH_1):PAGE49_I111@MSTR_SCONN.SCONN288_H44441004(CHIPS)':
 'VREFCA': CDS_PINID='VREFCA';
NODE_NAME     C4B12 1
 '@BASEBOARD_FAB2_LIB.BASEBOARD_FAB2(SCH_1):PAGE49_I179@DEV_DISCRETE.CAP_A(CHIPS)':
 'A': CDS_PINID='A';
NODE_NAME     J6M1 146
 '@BASEBOARD_FAB2_LIB.BASEBOARD_FAB2(SCH_1):PAGE50_I158@MSTR_SCONN.SCONN288_H44441003(CHIPS)':
 'VREFCA': CDS_PINID='VREFCA';
NODE_NAME     C6M1 1
 '@BASEBOARD_FAB2_LIB.BASEBOARD_FAB2(SCH_1):PAGE50_I177@DEV_DISCRETE.CAP_A(CHIPS)':
 'A': CDS_PINID='A';
NODE_NAME     R6M1 2
 '@BASEBOARD_FAB2_LIB.BASEBOARD_FAB2(SCH_1):PAGE98_I9@MSTR_DISCRETE.RES(CHIPS)':
 'B': CDS_PINID='B';
NODE_NAME     R6L16 1
 '@BASEBOARD_FAB2_LIB.BASEBOARD_FAB2(SCH_1):PAGE98_I12@MSTR_DISCRETE.RES(CHIPS)':
 'A': CDS_PINID='A';
NODE_NAME     R6M2 2
 '@BASEBOARD_FAB2_LIB.BASEBOARD_FAB2(SCH_1):PAGE98_I14@MSTR_DISCRETE.RES(CHIPS)':
 'B': CDS_PINID='B';
NET_NAME
'M_E_ACT_N'
 '@BASEBOARD_FAB2_LIB.BASEBOARD_FAB2(SCH_1):M_E_ACT_N':
 C_SIGNAL='@baseboard_fab2_lib.baseboard_fab2(sch_1):m_e_act_n';
NODE_NAME     U5D1 DR62
 '@BASEBOARD_FAB2_LIB.BASEBOARD_FAB2(SCH_1):PAGE27_I172@CHPSET_LIB.SKX_EXT_B(CHIPS)':
 'DDR4_ACT_N': CDS_PINID='DDR4_ACT_N';
NODE_NAME     J4A2 62
 '@BASEBOARD_FAB2_LIB.BASEBOARD_FAB2(SCH_1):PAGE51_I111@MSTR_SCONN.SCONN288_H44441004(CHIPS)':
 'ACT_N': CDS_PINID='ACT_N';
NODE_NAME     J6L2 62
 '@BASEBOARD_FAB2_LIB.BASEBOARD_FAB2(SCH_1):PAGE52_I12@MSTR_SCONN.SCONN288_H44441003(CHIPS)':
 'ACT_N': CDS_PINID='ACT_N';
NET_NAME
'M_E_ALERT_N'
 '@BASEBOARD_FAB2_LIB.BASEBOARD_FAB2(SCH_1):M_E_ALERT_N':
 C_SIGNAL='@baseboard_fab2_lib.baseboard_fab2(sch_1):m_e_alert_n';
NODE_NAME     U5D1 DT61
 '@BASEBOARD_FAB2_LIB.BASEBOARD_FAB2(SCH_1):PAGE27_I172@CHPSET_LIB.SKX_EXT_B(CHIPS)':
 'DDR4_ALERT_N': CDS_PINID='DDR4_ALERT_N';
NODE_NAME     J4A2 208
 '@BASEBOARD_FAB2_LIB.BASEBOARD_FAB2(SCH_1):PAGE51_I111@MSTR_SCONN.SCONN288_H44441004(CHIPS)':
 'ALERT_N': CDS_PINID='ALERT_N';
NODE_NAME     J6L2 208
 '@BASEBOARD_FAB2_LIB.BASEBOARD_FAB2(SCH_1):PAGE52_I12@MSTR_SCONN.SCONN288_H44441003(CHIPS)':
 'ALERT_N': CDS_PINID='ALERT_N';
NET_NAME
'M_E_BA<0>'
 '@BASEBOARD_FAB2_LIB.BASEBOARD_FAB2(SCH_1):M_E_BA'<0>:
 C_SIGNAL='@baseboard_fab2_lib.baseboard_fab2(sch_1):m_e_ba(0)';
NODE_NAME     U5D1 DM53
 '@BASEBOARD_FAB2_LIB.BASEBOARD_FAB2(SCH_1):PAGE27_I172@CHPSET_LIB.SKX_EXT_B(CHIPS)':
 'DDR4_BA'<0>: CDS_PINID='DDR4_BA(0)';
NODE_NAME     J4A2 81
 '@BASEBOARD_FAB2_LIB.BASEBOARD_FAB2(SCH_1):PAGE51_I111@MSTR_SCONN.SCONN288_H44441004(CHIPS)':
 'BA'<0>: CDS_PINID='BA(0)';
NODE_NAME     J6L2 81
 '@BASEBOARD_FAB2_LIB.BASEBOARD_FAB2(SCH_1):PAGE52_I12@MSTR_SCONN.SCONN288_H44441003(CHIPS)':
 'BA'<0>: CDS_PINID='BA(0)';
NET_NAME
'M_E_BA<1>'
 '@BASEBOARD_FAB2_LIB.BASEBOARD_FAB2(SCH_1):M_E_BA'<1>:
 C_SIGNAL='@baseboard_fab2_lib.baseboard_fab2(sch_1):m_e_ba(1)';
NODE_NAME     U5D1 DV55
 '@BASEBOARD_FAB2_LIB.BASEBOARD_FAB2(SCH_1):PAGE27_I172@CHPSET_LIB.SKX_EXT_B(CHIPS)':
 'DDR4_BA'<1>: CDS_PINID='DDR4_BA(1)';
NODE_NAME     J4A2 224
 '@BASEBOARD_FAB2_LIB.BASEBOARD_FAB2(SCH_1):PAGE51_I111@MSTR_SCONN.SCONN288_H44441004(CHIPS)':
 'BA'<1>: CDS_PINID='BA(1)';
NODE_NAME     J6L2 224
 '@BASEBOARD_FAB2_LIB.BASEBOARD_FAB2(SCH_1):PAGE52_I12@MSTR_SCONN.SCONN288_H44441003(CHIPS)':
 'BA'<1>: CDS_PINID='BA(1)';
NET_NAME
'M_E_BG<0>'
 '@BASEBOARD_FAB2_LIB.BASEBOARD_FAB2(SCH_1):M_E_BG'<0>:
 C_SIGNAL='@baseboard_fab2_lib.baseboard_fab2(sch_1):m_e_bg(0)';
NODE_NAME     U5D1 DJ62
 '@BASEBOARD_FAB2_LIB.BASEBOARD_FAB2(SCH_1):PAGE27_I172@CHPSET_LIB.SKX_EXT_B(CHIPS)':
 'DDR4_BG'<0>: CDS_PINID='DDR4_BG(0)';
NODE_NAME     J4A2 63
 '@BASEBOARD_FAB2_LIB.BASEBOARD_FAB2(SCH_1):PAGE51_I111@MSTR_SCONN.SCONN288_H44441004(CHIPS)':
 'BG'<0>: CDS_PINID='BG(0)';
NODE_NAME     J6L2 63
 '@BASEBOARD_FAB2_LIB.BASEBOARD_FAB2(SCH_1):PAGE52_I12@MSTR_SCONN.SCONN288_H44441003(CHIPS)':
 'BG'<0>: CDS_PINID='BG(0)';
NET_NAME
'M_E_BG<1>'
 '@BASEBOARD_FAB2_LIB.BASEBOARD_FAB2(SCH_1):M_E_BG'<1>:
 C_SIGNAL='@baseboard_fab2_lib.baseboard_fab2(sch_1):m_e_bg(1)';
NODE_NAME     U5D1 DM61
 '@BASEBOARD_FAB2_LIB.BASEBOARD_FAB2(SCH_1):PAGE27_I172@CHPSET_LIB.SKX_EXT_B(CHIPS)':
 'DDR4_BG'<1>: CDS_PINID='DDR4_BG(1)';
NODE_NAME     J4A2 207
 '@BASEBOARD_FAB2_LIB.BASEBOARD_FAB2(SCH_1):PAGE51_I111@MSTR_SCONN.SCONN288_H44441004(CHIPS)':
 'BG'<1>: CDS_PINID='BG(1)';
NODE_NAME     J6L2 207
 '@BASEBOARD_FAB2_LIB.BASEBOARD_FAB2(SCH_1):PAGE52_I12@MSTR_SCONN.SCONN288_H44441003(CHIPS)':
 'BG'<1>: CDS_PINID='BG(1)';
NET_NAME
'M_E_C<2>'
 '@BASEBOARD_FAB2_LIB.BASEBOARD_FAB2(SCH_1):M_E_C'<2>:
 C_SIGNAL='@baseboard_fab2_lib.baseboard_fab2(sch_1):m_e_c(2)';
NODE_NAME     U5D1 DT47
 '@BASEBOARD_FAB2_LIB.BASEBOARD_FAB2(SCH_1):PAGE27_I172@CHPSET_LIB.SKX_EXT_B(CHIPS)':
 'DDR4_CID'<2>: CDS_PINID='DDR4_CID(2)';
NODE_NAME     J4A2 235
 '@BASEBOARD_FAB2_LIB.BASEBOARD_FAB2(SCH_1):PAGE51_I111@MSTR_SCONN.SCONN288_H44441004(CHIPS)':
 'C'<2>: CDS_PINID='C(2)';
NODE_NAME     J6L2 235
 '@BASEBOARD_FAB2_LIB.BASEBOARD_FAB2(SCH_1):PAGE52_I12@MSTR_SCONN.SCONN288_H44441003(CHIPS)':
 'C'<2>: CDS_PINID='C(2)';
NET_NAME
'M_E_CKE<0>'
 '@BASEBOARD_FAB2_LIB.BASEBOARD_FAB2(SCH_1):M_E_CKE'<0>:
 C_SIGNAL='@baseboard_fab2_lib.baseboard_fab2(sch_1):m_e_cke(0)';
NODE_NAME     U5D1 DM63
 '@BASEBOARD_FAB2_LIB.BASEBOARD_FAB2(SCH_1):PAGE27_I172@CHPSET_LIB.SKX_EXT_B(CHIPS)':
 'DDR4_CKE'<0>: CDS_PINID='DDR4_CKE(0)';
NODE_NAME     J4A2 60
 '@BASEBOARD_FAB2_LIB.BASEBOARD_FAB2(SCH_1):PAGE51_I111@MSTR_SCONN.SCONN288_H44441004(CHIPS)':
 'CKE'<0>: CDS_PINID='CKE(0)';
NET_NAME
'M_E_CKE<1>'
 '@BASEBOARD_FAB2_LIB.BASEBOARD_FAB2(SCH_1):M_E_CKE'<1>:
 C_SIGNAL='@baseboard_fab2_lib.baseboard_fab2(sch_1):m_e_cke(1)';
NODE_NAME     U5D1 DN64
 '@BASEBOARD_FAB2_LIB.BASEBOARD_FAB2(SCH_1):PAGE27_I172@CHPSET_LIB.SKX_EXT_B(CHIPS)':
 'DDR4_CKE'<1>: CDS_PINID='DDR4_CKE(1)';
NODE_NAME     J4A2 203
 '@BASEBOARD_FAB2_LIB.BASEBOARD_FAB2(SCH_1):PAGE51_I111@MSTR_SCONN.SCONN288_H44441004(CHIPS)':
 'CKE'<1>: CDS_PINID='CKE(1)';
NET_NAME
'M_E_CKE<2>'
 '@BASEBOARD_FAB2_LIB.BASEBOARD_FAB2(SCH_1):M_E_CKE'<2>:
 C_SIGNAL='@baseboard_fab2_lib.baseboard_fab2(sch_1):m_e_cke(2)';
NODE_NAME     U5D1 DL64
 '@BASEBOARD_FAB2_LIB.BASEBOARD_FAB2(SCH_1):PAGE27_I172@CHPSET_LIB.SKX_EXT_B(CHIPS)':
 'DDR4_CKE'<2>: CDS_PINID='DDR4_CKE(2)';
NODE_NAME     J6L2 60
 '@BASEBOARD_FAB2_LIB.BASEBOARD_FAB2(SCH_1):PAGE52_I12@MSTR_SCONN.SCONN288_H44441003(CHIPS)':
 'CKE'<0>: CDS_PINID='CKE(0)';
NET_NAME
'M_E_CKE<3>'
 '@BASEBOARD_FAB2_LIB.BASEBOARD_FAB2(SCH_1):M_E_CKE'<3>:
 C_SIGNAL='@baseboard_fab2_lib.baseboard_fab2(sch_1):m_e_cke(3)';
NODE_NAME     U5D1 DR64
 '@BASEBOARD_FAB2_LIB.BASEBOARD_FAB2(SCH_1):PAGE27_I172@CHPSET_LIB.SKX_EXT_B(CHIPS)':
 'DDR4_CKE'<3>: CDS_PINID='DDR4_CKE(3)';
NODE_NAME     J6L2 203
 '@BASEBOARD_FAB2_LIB.BASEBOARD_FAB2(SCH_1):PAGE52_I12@MSTR_SCONN.SCONN288_H44441003(CHIPS)':
 'CKE'<1>: CDS_PINID='CKE(1)';
NET_NAME
'M_E_CLK_DN<0>'
 '@BASEBOARD_FAB2_LIB.BASEBOARD_FAB2(SCH_1):M_E_CLK_DN'<0>:
 C_SIGNAL='@baseboard_fab2_lib.baseboard_fab2(sch_1):m_e_clk_dn(0)';
NODE_NAME     U5D1 DM55
 '@BASEBOARD_FAB2_LIB.BASEBOARD_FAB2(SCH_1):PAGE27_I172@CHPSET_LIB.SKX_EXT_B(CHIPS)':
 'DDR4_CLK_DN'<0>: CDS_PINID='DDR4_CLK_DN(0)';
NODE_NAME     J4A2 75
 '@BASEBOARD_FAB2_LIB.BASEBOARD_FAB2(SCH_1):PAGE51_I111@MSTR_SCONN.SCONN288_H44441004(CHIPS)':
 'CK0N': CDS_PINID='CK0N';
NET_NAME
'M_E_CLK_DN<1>'
 '@BASEBOARD_FAB2_LIB.BASEBOARD_FAB2(SCH_1):M_E_CLK_DN'<1>:
 C_SIGNAL='@baseboard_fab2_lib.baseboard_fab2(sch_1):m_e_clk_dn(1)';
NODE_NAME     U5D1 DR54
 '@BASEBOARD_FAB2_LIB.BASEBOARD_FAB2(SCH_1):PAGE27_I172@CHPSET_LIB.SKX_EXT_B(CHIPS)':
 'DDR4_CLK_DN'<1>: CDS_PINID='DDR4_CLK_DN(1)';
NODE_NAME     J4A2 219
 '@BASEBOARD_FAB2_LIB.BASEBOARD_FAB2(SCH_1):PAGE51_I111@MSTR_SCONN.SCONN288_H44441004(CHIPS)':
 'CK1N': CDS_PINID='CK1N';
NET_NAME
'M_E_CLK_DN<2>'
 '@BASEBOARD_FAB2_LIB.BASEBOARD_FAB2(SCH_1):M_E_CLK_DN'<2>:
 C_SIGNAL='@baseboard_fab2_lib.baseboard_fab2(sch_1):m_e_clk_dn(2)';
NODE_NAME     U5D1 DM57
 '@BASEBOARD_FAB2_LIB.BASEBOARD_FAB2(SCH_1):PAGE27_I172@CHPSET_LIB.SKX_EXT_B(CHIPS)':
 'DDR4_CLK_DN'<2>: CDS_PINID='DDR4_CLK_DN(2)';
NODE_NAME     J6L2 75
 '@BASEBOARD_FAB2_LIB.BASEBOARD_FAB2(SCH_1):PAGE52_I12@MSTR_SCONN.SCONN288_H44441003(CHIPS)':
 'CK0N': CDS_PINID='CK0N';
NET_NAME
'M_E_CLK_DN<3>'
 '@BASEBOARD_FAB2_LIB.BASEBOARD_FAB2(SCH_1):M_E_CLK_DN'<3>:
 C_SIGNAL='@baseboard_fab2_lib.baseboard_fab2(sch_1):m_e_clk_dn(3)';
NODE_NAME     U5D1 DT57
 '@BASEBOARD_FAB2_LIB.BASEBOARD_FAB2(SCH_1):PAGE27_I172@CHPSET_LIB.SKX_EXT_B(CHIPS)':
 'DDR4_CLK_DN'<3>: CDS_PINID='DDR4_CLK_DN(3)';
NODE_NAME     J6L2 219
 '@BASEBOARD_FAB2_LIB.BASEBOARD_FAB2(SCH_1):PAGE52_I12@MSTR_SCONN.SCONN288_H44441003(CHIPS)':
 'CK1N': CDS_PINID='CK1N';
NET_NAME
'M_E_CLK_DP<0>'
 '@BASEBOARD_FAB2_LIB.BASEBOARD_FAB2(SCH_1):M_E_CLK_DP'<0>:
 C_SIGNAL='@baseboard_fab2_lib.baseboard_fab2(sch_1):m_e_clk_dp(0)';
NODE_NAME     U5D1 DN54
 '@BASEBOARD_FAB2_LIB.BASEBOARD_FAB2(SCH_1):PAGE27_I172@CHPSET_LIB.SKX_EXT_B(CHIPS)':
 'DDR4_CLK_DP'<0>: CDS_PINID='DDR4_CLK_DP(0)';
NODE_NAME     J4A2 74
 '@BASEBOARD_FAB2_LIB.BASEBOARD_FAB2(SCH_1):PAGE51_I111@MSTR_SCONN.SCONN288_H44441004(CHIPS)':
 'CK0P': CDS_PINID='CK0P';
NET_NAME
'M_E_CLK_DP<1>'
 '@BASEBOARD_FAB2_LIB.BASEBOARD_FAB2(SCH_1):M_E_CLK_DP'<1>:
 C_SIGNAL='@baseboard_fab2_lib.baseboard_fab2(sch_1):m_e_clk_dp(1)';
NODE_NAME     U5D1 DT53
 '@BASEBOARD_FAB2_LIB.BASEBOARD_FAB2(SCH_1):PAGE27_I172@CHPSET_LIB.SKX_EXT_B(CHIPS)':
 'DDR4_CLK_DP'<1>: CDS_PINID='DDR4_CLK_DP(1)';
NODE_NAME     J4A2 218
 '@BASEBOARD_FAB2_LIB.BASEBOARD_FAB2(SCH_1):PAGE51_I111@MSTR_SCONN.SCONN288_H44441004(CHIPS)':
 'CK1P': CDS_PINID='CK1P';
NET_NAME
'M_E_CLK_DP<2>'
 '@BASEBOARD_FAB2_LIB.BASEBOARD_FAB2(SCH_1):M_E_CLK_DP'<2>:
 C_SIGNAL='@baseboard_fab2_lib.baseboard_fab2(sch_1):m_e_clk_dp(2)';
NODE_NAME     U5D1 DN56
 '@BASEBOARD_FAB2_LIB.BASEBOARD_FAB2(SCH_1):PAGE27_I172@CHPSET_LIB.SKX_EXT_B(CHIPS)':
 'DDR4_CLK_DP'<2>: CDS_PINID='DDR4_CLK_DP(2)';
NODE_NAME     J6L2 74
 '@BASEBOARD_FAB2_LIB.BASEBOARD_FAB2(SCH_1):PAGE52_I12@MSTR_SCONN.SCONN288_H44441003(CHIPS)':
 'CK0P': CDS_PINID='CK0P';
NET_NAME
'M_E_CLK_DP<3>'
 '@BASEBOARD_FAB2_LIB.BASEBOARD_FAB2(SCH_1):M_E_CLK_DP'<3>:
 C_SIGNAL='@baseboard_fab2_lib.baseboard_fab2(sch_1):m_e_clk_dp(3)';
NODE_NAME     U5D1 DR56
 '@BASEBOARD_FAB2_LIB.BASEBOARD_FAB2(SCH_1):PAGE27_I172@CHPSET_LIB.SKX_EXT_B(CHIPS)':
 'DDR4_CLK_DP'<3>: CDS_PINID='DDR4_CLK_DP(3)';
NODE_NAME     J6L2 218
 '@BASEBOARD_FAB2_LIB.BASEBOARD_FAB2(SCH_1):PAGE52_I12@MSTR_SCONN.SCONN288_H44441003(CHIPS)':
 'CK1P': CDS_PINID='CK1P';
NET_NAME
'M_E_CPU_VREF'
 '@BASEBOARD_FAB2_LIB.BASEBOARD_FAB2(SCH_1):M_E_CPU_VREF':
 C_SIGNAL='@baseboard_fab2_lib.baseboard_fab2(sch_1):m_e_cpu_vref';
NODE_NAME     U5D1 CT61
 '@BASEBOARD_FAB2_LIB.BASEBOARD_FAB2(SCH_1):PAGE21_I259@CHPSET_LIB.SKX_EXT_B(CHIPS)':
 'DDR4_CAVREF': CDS_PINID='DDR4_CAVREF';
NODE_NAME     R6L14 1
 '@BASEBOARD_FAB2_LIB.BASEBOARD_FAB2(SCH_1):PAGE98_I58@MSTR_DISCRETE.RES(CHIPS)':
 'A': CDS_PINID='A';
NODE_NAME     C6L7 1
 '@BASEBOARD_FAB2_LIB.BASEBOARD_FAB2(SCH_1):PAGE98_I59@DEV_DISCRETE.CAP_A(CHIPS)':
 'A': CDS_PINID='A';
NET_NAME
'M_E_CS_N<0>'
 '@BASEBOARD_FAB2_LIB.BASEBOARD_FAB2(SCH_1):M_E_CS_N'<0>:
 C_SIGNAL='@baseboard_fab2_lib.baseboard_fab2(sch_1):m_e_cs_n(0)';
NODE_NAME     U5D1 DV51
 '@BASEBOARD_FAB2_LIB.BASEBOARD_FAB2(SCH_1):PAGE27_I172@CHPSET_LIB.SKX_EXT_B(CHIPS)':
 'DDR4_CS_N'<0>: CDS_PINID='DDR4_CS_N(0)';
NODE_NAME     J4A2 84
 '@BASEBOARD_FAB2_LIB.BASEBOARD_FAB2(SCH_1):PAGE51_I111@MSTR_SCONN.SCONN288_H44441004(CHIPS)':
 'S0_N': CDS_PINID='S0_N';
NET_NAME
'M_E_CS_N<1>'
 '@BASEBOARD_FAB2_LIB.BASEBOARD_FAB2(SCH_1):M_E_CS_N'<1>:
 C_SIGNAL='@baseboard_fab2_lib.baseboard_fab2(sch_1):m_e_cs_n(1)';
NODE_NAME     U5D1 DN50
 '@BASEBOARD_FAB2_LIB.BASEBOARD_FAB2(SCH_1):PAGE27_I172@CHPSET_LIB.SKX_EXT_B(CHIPS)':
 'DDR4_CS_N'<1>: CDS_PINID='DDR4_CS_N(1)';
NODE_NAME     J4A2 89
 '@BASEBOARD_FAB2_LIB.BASEBOARD_FAB2(SCH_1):PAGE51_I111@MSTR_SCONN.SCONN288_H44441004(CHIPS)':
 'S1_N': CDS_PINID='S1_N';
NET_NAME
'M_E_CS_N<2>'
 '@BASEBOARD_FAB2_LIB.BASEBOARD_FAB2(SCH_1):M_E_CS_N'<2>:
 C_SIGNAL='@baseboard_fab2_lib.baseboard_fab2(sch_1):m_e_cs_n(2)';
NODE_NAME     U5D1 DR46
 '@BASEBOARD_FAB2_LIB.BASEBOARD_FAB2(SCH_1):PAGE27_I172@CHPSET_LIB.SKX_EXT_B(CHIPS)':
 'DDR4_CS_N'<2>: CDS_PINID='DDR4_CS_N(2)';
NODE_NAME     J4A2 93
 '@BASEBOARD_FAB2_LIB.BASEBOARD_FAB2(SCH_1):PAGE51_I111@MSTR_SCONN.SCONN288_H44441004(CHIPS)':
 'S2_N_C'<0>: CDS_PINID='S2_N_C(0)';
NET_NAME
'M_E_CS_N<3>'
 '@BASEBOARD_FAB2_LIB.BASEBOARD_FAB2(SCH_1):M_E_CS_N'<3>:
 C_SIGNAL='@baseboard_fab2_lib.baseboard_fab2(sch_1):m_e_cs_n(3)';
NODE_NAME     U5D1 DK47
 '@BASEBOARD_FAB2_LIB.BASEBOARD_FAB2(SCH_1):PAGE27_I172@CHPSET_LIB.SKX_EXT_B(CHIPS)':
 'DDR4_CS_N'<3>: CDS_PINID='DDR4_CS_N(3)';
NODE_NAME     J4A2 237
 '@BASEBOARD_FAB2_LIB.BASEBOARD_FAB2(SCH_1):PAGE51_I111@MSTR_SCONN.SCONN288_H44441004(CHIPS)':
 'S3_N_C'<1>: CDS_PINID='S3_N_C(1)';
NET_NAME
'M_E_CS_N<4>'
 '@BASEBOARD_FAB2_LIB.BASEBOARD_FAB2(SCH_1):M_E_CS_N'<4>:
 C_SIGNAL='@baseboard_fab2_lib.baseboard_fab2(sch_1):m_e_cs_n(4)';
NODE_NAME     U5D1 DW50
 '@BASEBOARD_FAB2_LIB.BASEBOARD_FAB2(SCH_1):PAGE27_I172@CHPSET_LIB.SKX_EXT_B(CHIPS)':
 'DDR4_CS_N'<4>: CDS_PINID='DDR4_CS_N(4)';
NODE_NAME     J6L2 84
 '@BASEBOARD_FAB2_LIB.BASEBOARD_FAB2(SCH_1):PAGE52_I12@MSTR_SCONN.SCONN288_H44441003(CHIPS)':
 'S0_N': CDS_PINID='S0_N';
NET_NAME
'M_E_CS_N<5>'
 '@BASEBOARD_FAB2_LIB.BASEBOARD_FAB2(SCH_1):M_E_CS_N'<5>:
 C_SIGNAL='@baseboard_fab2_lib.baseboard_fab2(sch_1):m_e_cs_n(5)';
NODE_NAME     U5D1 DM49
 '@BASEBOARD_FAB2_LIB.BASEBOARD_FAB2(SCH_1):PAGE27_I172@CHPSET_LIB.SKX_EXT_B(CHIPS)':
 'DDR4_CS_N'<5>: CDS_PINID='DDR4_CS_N(5)';
NODE_NAME     J6L2 89
 '@BASEBOARD_FAB2_LIB.BASEBOARD_FAB2(SCH_1):PAGE52_I12@MSTR_SCONN.SCONN288_H44441003(CHIPS)':
 'S1_N': CDS_PINID='S1_N';
NET_NAME
'M_E_CS_N<6>'
 '@BASEBOARD_FAB2_LIB.BASEBOARD_FAB2(SCH_1):M_E_CS_N'<6>:
 C_SIGNAL='@baseboard_fab2_lib.baseboard_fab2(sch_1):m_e_cs_n(6)';
NODE_NAME     U5D1 DT45
 '@BASEBOARD_FAB2_LIB.BASEBOARD_FAB2(SCH_1):PAGE27_I172@CHPSET_LIB.SKX_EXT_B(CHIPS)':
 'DDR4_CS_N'<6>: CDS_PINID='DDR4_CS_N(6)';
NODE_NAME     J6L2 93
 '@BASEBOARD_FAB2_LIB.BASEBOARD_FAB2(SCH_1):PAGE52_I12@MSTR_SCONN.SCONN288_H44441003(CHIPS)':
 'S2_N_C'<0>: CDS_PINID='S2_N_C(0)';
NET_NAME
'M_E_CS_N<7>'
 '@BASEBOARD_FAB2_LIB.BASEBOARD_FAB2(SCH_1):M_E_CS_N'<7>:
 C_SIGNAL='@baseboard_fab2_lib.baseboard_fab2(sch_1):m_e_cs_n(7)';
NODE_NAME     U5D1 DN46
 '@BASEBOARD_FAB2_LIB.BASEBOARD_FAB2(SCH_1):PAGE27_I172@CHPSET_LIB.SKX_EXT_B(CHIPS)':
 'DDR4_CS_N'<7>: CDS_PINID='DDR4_CS_N(7)';
NODE_NAME     J6L2 237
 '@BASEBOARD_FAB2_LIB.BASEBOARD_FAB2(SCH_1):PAGE52_I12@MSTR_SCONN.SCONN288_H44441003(CHIPS)':
 'S3_N_C'<1>: CDS_PINID='S3_N_C(1)';
NET_NAME
'M_E_DQ<0>'
 '@BASEBOARD_FAB2_LIB.BASEBOARD_FAB2(SCH_1):M_E_DQ'<0>:
 C_SIGNAL='@baseboard_fab2_lib.baseboard_fab2(sch_1):m_e_dq(0)';
NODE_NAME     U5D1 CM79
 '@BASEBOARD_FAB2_LIB.BASEBOARD_FAB2(SCH_1):PAGE27_I172@CHPSET_LIB.SKX_EXT_B(CHIPS)':
 'DDR4_DQ'<0>: CDS_PINID='DDR4_DQ(0)';
NODE_NAME     J4A2 150
 '@BASEBOARD_FAB2_LIB.BASEBOARD_FAB2(SCH_1):PAGE51_I111@MSTR_SCONN.SCONN288_H44441004(CHIPS)':
 'DQ'<1>: CDS_PINID='DQ(1)';
NODE_NAME     J6L2 5
 '@BASEBOARD_FAB2_LIB.BASEBOARD_FAB2(SCH_1):PAGE52_I12@MSTR_SCONN.SCONN288_H44441003(CHIPS)':
 'DQ'<0>: CDS_PINID='DQ(0)';
NET_NAME
'M_E_DQ<10>'
 '@BASEBOARD_FAB2_LIB.BASEBOARD_FAB2(SCH_1):M_E_DQ'<10>:
 C_SIGNAL='@baseboard_fab2_lib.baseboard_fab2(sch_1):m_e_dq(10)';
NODE_NAME     U5D1 DE80
 '@BASEBOARD_FAB2_LIB.BASEBOARD_FAB2(SCH_1):PAGE27_I172@CHPSET_LIB.SKX_EXT_B(CHIPS)':
 'DDR4_DQ'<10>: CDS_PINID='DDR4_DQ(10)';
NODE_NAME     J4A2 168
 '@BASEBOARD_FAB2_LIB.BASEBOARD_FAB2(SCH_1):PAGE51_I111@MSTR_SCONN.SCONN288_H44441004(CHIPS)':
 'DQ'<11>: CDS_PINID='DQ(11)';
NODE_NAME     J6L2 23
 '@BASEBOARD_FAB2_LIB.BASEBOARD_FAB2(SCH_1):PAGE52_I12@MSTR_SCONN.SCONN288_H44441003(CHIPS)':
 'DQ'<10>: CDS_PINID='DQ(10)';
NET_NAME
'M_E_DQ<11>'
 '@BASEBOARD_FAB2_LIB.BASEBOARD_FAB2(SCH_1):M_E_DQ'<11>:
 C_SIGNAL='@baseboard_fab2_lib.baseboard_fab2(sch_1):m_e_dq(11)';
NODE_NAME     U5D1 DF81
 '@BASEBOARD_FAB2_LIB.BASEBOARD_FAB2(SCH_1):PAGE27_I172@CHPSET_LIB.SKX_EXT_B(CHIPS)':
 'DDR4_DQ'<11>: CDS_PINID='DDR4_DQ(11)';
NODE_NAME     J4A2 23
 '@BASEBOARD_FAB2_LIB.BASEBOARD_FAB2(SCH_1):PAGE51_I111@MSTR_SCONN.SCONN288_H44441004(CHIPS)':
 'DQ'<10>: CDS_PINID='DQ(10)';
NODE_NAME     J6L2 168
 '@BASEBOARD_FAB2_LIB.BASEBOARD_FAB2(SCH_1):PAGE52_I12@MSTR_SCONN.SCONN288_H44441003(CHIPS)':
 'DQ'<11>: CDS_PINID='DQ(11)';
NET_NAME
'M_E_DQ<12>'
 '@BASEBOARD_FAB2_LIB.BASEBOARD_FAB2(SCH_1):M_E_DQ'<12>:
 C_SIGNAL='@baseboard_fab2_lib.baseboard_fab2(sch_1):m_e_dq(12)';
NODE_NAME     U5D1 CY79
 '@BASEBOARD_FAB2_LIB.BASEBOARD_FAB2(SCH_1):PAGE27_I172@CHPSET_LIB.SKX_EXT_B(CHIPS)':
 'DDR4_DQ'<12>: CDS_PINID='DDR4_DQ(12)';
NODE_NAME     J4A2 159
 '@BASEBOARD_FAB2_LIB.BASEBOARD_FAB2(SCH_1):PAGE51_I111@MSTR_SCONN.SCONN288_H44441004(CHIPS)':
 'DQ'<13>: CDS_PINID='DQ(13)';
NODE_NAME     J6L2 14
 '@BASEBOARD_FAB2_LIB.BASEBOARD_FAB2(SCH_1):PAGE52_I12@MSTR_SCONN.SCONN288_H44441003(CHIPS)':
 'DQ'<12>: CDS_PINID='DQ(12)';
NET_NAME
'M_E_DQ<13>'
 '@BASEBOARD_FAB2_LIB.BASEBOARD_FAB2(SCH_1):M_E_DQ'<13>:
 C_SIGNAL='@baseboard_fab2_lib.baseboard_fab2(sch_1):m_e_dq(13)';
NODE_NAME     U5D1 CW80
 '@BASEBOARD_FAB2_LIB.BASEBOARD_FAB2(SCH_1):PAGE27_I172@CHPSET_LIB.SKX_EXT_B(CHIPS)':
 'DDR4_DQ'<13>: CDS_PINID='DDR4_DQ(13)';
NODE_NAME     J4A2 14
 '@BASEBOARD_FAB2_LIB.BASEBOARD_FAB2(SCH_1):PAGE51_I111@MSTR_SCONN.SCONN288_H44441004(CHIPS)':
 'DQ'<12>: CDS_PINID='DQ(12)';
NODE_NAME     J6L2 159
 '@BASEBOARD_FAB2_LIB.BASEBOARD_FAB2(SCH_1):PAGE52_I12@MSTR_SCONN.SCONN288_H44441003(CHIPS)':
 'DQ'<13>: CDS_PINID='DQ(13)';
NET_NAME
'M_E_DQ<14>'
 '@BASEBOARD_FAB2_LIB.BASEBOARD_FAB2(SCH_1):M_E_DQ'<14>:
 C_SIGNAL='@baseboard_fab2_lib.baseboard_fab2(sch_1):m_e_dq(14)';
NODE_NAME     U5D1 DC82
 '@BASEBOARD_FAB2_LIB.BASEBOARD_FAB2(SCH_1):PAGE27_I172@CHPSET_LIB.SKX_EXT_B(CHIPS)':
 'DDR4_DQ'<14>: CDS_PINID='DDR4_DQ(14)';
NODE_NAME     J4A2 166
 '@BASEBOARD_FAB2_LIB.BASEBOARD_FAB2(SCH_1):PAGE51_I111@MSTR_SCONN.SCONN288_H44441004(CHIPS)':
 'DQ'<15>: CDS_PINID='DQ(15)';
NODE_NAME     J6L2 21
 '@BASEBOARD_FAB2_LIB.BASEBOARD_FAB2(SCH_1):PAGE52_I12@MSTR_SCONN.SCONN288_H44441003(CHIPS)':
 'DQ'<14>: CDS_PINID='DQ(14)';
NET_NAME
'M_E_DQ<15>'
 '@BASEBOARD_FAB2_LIB.BASEBOARD_FAB2(SCH_1):M_E_DQ'<15>:
 C_SIGNAL='@baseboard_fab2_lib.baseboard_fab2(sch_1):m_e_dq(15)';
NODE_NAME     U5D1 DE82
 '@BASEBOARD_FAB2_LIB.BASEBOARD_FAB2(SCH_1):PAGE27_I172@CHPSET_LIB.SKX_EXT_B(CHIPS)':
 'DDR4_DQ'<15>: CDS_PINID='DDR4_DQ(15)';
NODE_NAME     J4A2 21
 '@BASEBOARD_FAB2_LIB.BASEBOARD_FAB2(SCH_1):PAGE51_I111@MSTR_SCONN.SCONN288_H44441004(CHIPS)':
 'DQ'<14>: CDS_PINID='DQ(14)';
NODE_NAME     J6L2 166
 '@BASEBOARD_FAB2_LIB.BASEBOARD_FAB2(SCH_1):PAGE52_I12@MSTR_SCONN.SCONN288_H44441003(CHIPS)':
 'DQ'<15>: CDS_PINID='DQ(15)';
NET_NAME
'M_E_DQ<16>'
 '@BASEBOARD_FAB2_LIB.BASEBOARD_FAB2(SCH_1):M_E_DQ'<16>:
 C_SIGNAL='@baseboard_fab2_lib.baseboard_fab2(sch_1):m_e_dq(16)';
NODE_NAME     U5D1 DW80
 '@BASEBOARD_FAB2_LIB.BASEBOARD_FAB2(SCH_1):PAGE27_I172@CHPSET_LIB.SKX_EXT_B(CHIPS)':
 'DDR4_DQ'<16>: CDS_PINID='DDR4_DQ(16)';
NODE_NAME     J4A2 172
 '@BASEBOARD_FAB2_LIB.BASEBOARD_FAB2(SCH_1):PAGE51_I111@MSTR_SCONN.SCONN288_H44441004(CHIPS)':
 'DQ'<17>: CDS_PINID='DQ(17)';
NODE_NAME     J6L2 27
 '@BASEBOARD_FAB2_LIB.BASEBOARD_FAB2(SCH_1):PAGE52_I12@MSTR_SCONN.SCONN288_H44441003(CHIPS)':
 'DQ'<16>: CDS_PINID='DQ(16)';
NET_NAME
'M_E_DQ<17>'
 '@BASEBOARD_FAB2_LIB.BASEBOARD_FAB2(SCH_1):M_E_DQ'<17>:
 C_SIGNAL='@baseboard_fab2_lib.baseboard_fab2(sch_1):m_e_dq(17)';
NODE_NAME     U5D1 EC80
 '@BASEBOARD_FAB2_LIB.BASEBOARD_FAB2(SCH_1):PAGE27_I172@CHPSET_LIB.SKX_EXT_B(CHIPS)':
 'DDR4_DQ'<17>: CDS_PINID='DDR4_DQ(17)';
NODE_NAME     J4A2 27
 '@BASEBOARD_FAB2_LIB.BASEBOARD_FAB2(SCH_1):PAGE51_I111@MSTR_SCONN.SCONN288_H44441004(CHIPS)':
 'DQ'<16>: CDS_PINID='DQ(16)';
NODE_NAME     J6L2 172
 '@BASEBOARD_FAB2_LIB.BASEBOARD_FAB2(SCH_1):PAGE52_I12@MSTR_SCONN.SCONN288_H44441003(CHIPS)':
 'DQ'<17>: CDS_PINID='DQ(17)';
NET_NAME
'M_E_DQ<18>'
 '@BASEBOARD_FAB2_LIB.BASEBOARD_FAB2(SCH_1):M_E_DQ'<18>:
 C_SIGNAL='@baseboard_fab2_lib.baseboard_fab2(sch_1):m_e_dq(18)';
NODE_NAME     U5D1 DY77
 '@BASEBOARD_FAB2_LIB.BASEBOARD_FAB2(SCH_1):PAGE27_I172@CHPSET_LIB.SKX_EXT_B(CHIPS)':
 'DDR4_DQ'<18>: CDS_PINID='DDR4_DQ(18)';
NODE_NAME     J4A2 179
 '@BASEBOARD_FAB2_LIB.BASEBOARD_FAB2(SCH_1):PAGE51_I111@MSTR_SCONN.SCONN288_H44441004(CHIPS)':
 'DQ'<19>: CDS_PINID='DQ(19)';
NODE_NAME     J6L2 34
 '@BASEBOARD_FAB2_LIB.BASEBOARD_FAB2(SCH_1):PAGE52_I12@MSTR_SCONN.SCONN288_H44441003(CHIPS)':
 'DQ'<18>: CDS_PINID='DQ(18)';
NET_NAME
'M_E_DQ<19>'
 '@BASEBOARD_FAB2_LIB.BASEBOARD_FAB2(SCH_1):M_E_DQ'<19>:
 C_SIGNAL='@baseboard_fab2_lib.baseboard_fab2(sch_1):m_e_dq(19)';
NODE_NAME     U5D1 EB77
 '@BASEBOARD_FAB2_LIB.BASEBOARD_FAB2(SCH_1):PAGE27_I172@CHPSET_LIB.SKX_EXT_B(CHIPS)':
 'DDR4_DQ'<19>: CDS_PINID='DDR4_DQ(19)';
NODE_NAME     J4A2 34
 '@BASEBOARD_FAB2_LIB.BASEBOARD_FAB2(SCH_1):PAGE51_I111@MSTR_SCONN.SCONN288_H44441004(CHIPS)':
 'DQ'<18>: CDS_PINID='DQ(18)';
NODE_NAME     J6L2 179
 '@BASEBOARD_FAB2_LIB.BASEBOARD_FAB2(SCH_1):PAGE52_I12@MSTR_SCONN.SCONN288_H44441003(CHIPS)':
 'DQ'<19>: CDS_PINID='DQ(19)';
NET_NAME
'M_E_DQ<1>'
 '@BASEBOARD_FAB2_LIB.BASEBOARD_FAB2(SCH_1):M_E_DQ'<1>:
 C_SIGNAL='@baseboard_fab2_lib.baseboard_fab2(sch_1):m_e_dq(1)';
NODE_NAME     U5D1 CK81
 '@BASEBOARD_FAB2_LIB.BASEBOARD_FAB2(SCH_1):PAGE27_I172@CHPSET_LIB.SKX_EXT_B(CHIPS)':
 'DDR4_DQ'<1>: CDS_PINID='DDR4_DQ(1)';
NODE_NAME     J4A2 5
 '@BASEBOARD_FAB2_LIB.BASEBOARD_FAB2(SCH_1):PAGE51_I111@MSTR_SCONN.SCONN288_H44441004(CHIPS)':
 'DQ'<0>: CDS_PINID='DQ(0)';
NODE_NAME     J6L2 150
 '@BASEBOARD_FAB2_LIB.BASEBOARD_FAB2(SCH_1):PAGE52_I12@MSTR_SCONN.SCONN288_H44441003(CHIPS)':
 'DQ'<1>: CDS_PINID='DQ(1)';
NET_NAME
'M_E_DQ<20>'
 '@BASEBOARD_FAB2_LIB.BASEBOARD_FAB2(SCH_1):M_E_DQ'<20>:
 C_SIGNAL='@baseboard_fab2_lib.baseboard_fab2(sch_1):m_e_dq(20)';
NODE_NAME     U5D1 DY81
 '@BASEBOARD_FAB2_LIB.BASEBOARD_FAB2(SCH_1):PAGE27_I172@CHPSET_LIB.SKX_EXT_B(CHIPS)':
 'DDR4_DQ'<20>: CDS_PINID='DDR4_DQ(20)';
NODE_NAME     J4A2 170
 '@BASEBOARD_FAB2_LIB.BASEBOARD_FAB2(SCH_1):PAGE51_I111@MSTR_SCONN.SCONN288_H44441004(CHIPS)':
 'DQ'<21>: CDS_PINID='DQ(21)';
NODE_NAME     J6L2 25
 '@BASEBOARD_FAB2_LIB.BASEBOARD_FAB2(SCH_1):PAGE52_I12@MSTR_SCONN.SCONN288_H44441003(CHIPS)':
 'DQ'<20>: CDS_PINID='DQ(20)';
NET_NAME
'M_E_DQ<21>'
 '@BASEBOARD_FAB2_LIB.BASEBOARD_FAB2(SCH_1):M_E_DQ'<21>:
 C_SIGNAL='@baseboard_fab2_lib.baseboard_fab2(sch_1):m_e_dq(21)';
NODE_NAME     U5D1 EB81
 '@BASEBOARD_FAB2_LIB.BASEBOARD_FAB2(SCH_1):PAGE27_I172@CHPSET_LIB.SKX_EXT_B(CHIPS)':
 'DDR4_DQ'<21>: CDS_PINID='DDR4_DQ(21)';
NODE_NAME     J4A2 25
 '@BASEBOARD_FAB2_LIB.BASEBOARD_FAB2(SCH_1):PAGE51_I111@MSTR_SCONN.SCONN288_H44441004(CHIPS)':
 'DQ'<20>: CDS_PINID='DQ(20)';
NODE_NAME     J6L2 170
 '@BASEBOARD_FAB2_LIB.BASEBOARD_FAB2(SCH_1):PAGE52_I12@MSTR_SCONN.SCONN288_H44441003(CHIPS)':
 'DQ'<21>: CDS_PINID='DQ(21)';
NET_NAME
'M_E_DQ<22>'
 '@BASEBOARD_FAB2_LIB.BASEBOARD_FAB2(SCH_1):M_E_DQ'<22>:
 C_SIGNAL='@baseboard_fab2_lib.baseboard_fab2(sch_1):m_e_dq(22)';
NODE_NAME     U5D1 DW78
 '@BASEBOARD_FAB2_LIB.BASEBOARD_FAB2(SCH_1):PAGE27_I172@CHPSET_LIB.SKX_EXT_B(CHIPS)':
 'DDR4_DQ'<22>: CDS_PINID='DDR4_DQ(22)';
NODE_NAME     J4A2 177
 '@BASEBOARD_FAB2_LIB.BASEBOARD_FAB2(SCH_1):PAGE51_I111@MSTR_SCONN.SCONN288_H44441004(CHIPS)':
 'DQ'<23>: CDS_PINID='DQ(23)';
NODE_NAME     J6L2 32
 '@BASEBOARD_FAB2_LIB.BASEBOARD_FAB2(SCH_1):PAGE52_I12@MSTR_SCONN.SCONN288_H44441003(CHIPS)':
 'DQ'<22>: CDS_PINID='DQ(22)';
NET_NAME
'M_E_DQ<23>'
 '@BASEBOARD_FAB2_LIB.BASEBOARD_FAB2(SCH_1):M_E_DQ'<23>:
 C_SIGNAL='@baseboard_fab2_lib.baseboard_fab2(sch_1):m_e_dq(23)';
NODE_NAME     U5D1 EC78
 '@BASEBOARD_FAB2_LIB.BASEBOARD_FAB2(SCH_1):PAGE27_I172@CHPSET_LIB.SKX_EXT_B(CHIPS)':
 'DDR4_DQ'<23>: CDS_PINID='DDR4_DQ(23)';
NODE_NAME     J4A2 32
 '@BASEBOARD_FAB2_LIB.BASEBOARD_FAB2(SCH_1):PAGE51_I111@MSTR_SCONN.SCONN288_H44441004(CHIPS)':
 'DQ'<22>: CDS_PINID='DQ(22)';
NODE_NAME     J6L2 177
 '@BASEBOARD_FAB2_LIB.BASEBOARD_FAB2(SCH_1):PAGE52_I12@MSTR_SCONN.SCONN288_H44441003(CHIPS)':
 'DQ'<23>: CDS_PINID='DQ(23)';
NET_NAME
'M_E_DQ<24>'
 '@BASEBOARD_FAB2_LIB.BASEBOARD_FAB2(SCH_1):M_E_DQ'<24>:
 C_SIGNAL='@baseboard_fab2_lib.baseboard_fab2(sch_1):m_e_dq(24)';
NODE_NAME     U5D1 ED75
 '@BASEBOARD_FAB2_LIB.BASEBOARD_FAB2(SCH_1):PAGE27_I172@CHPSET_LIB.SKX_EXT_B(CHIPS)':
 'DDR4_DQ'<24>: CDS_PINID='DDR4_DQ(24)';
NODE_NAME     J4A2 183
 '@BASEBOARD_FAB2_LIB.BASEBOARD_FAB2(SCH_1):PAGE51_I111@MSTR_SCONN.SCONN288_H44441004(CHIPS)':
 'DQ'<25>: CDS_PINID='DQ(25)';
NODE_NAME     J6L2 38
 '@BASEBOARD_FAB2_LIB.BASEBOARD_FAB2(SCH_1):PAGE52_I12@MSTR_SCONN.SCONN288_H44441003(CHIPS)':
 'DQ'<24>: CDS_PINID='DQ(24)';
NET_NAME
'M_E_DQ<25>'
 '@BASEBOARD_FAB2_LIB.BASEBOARD_FAB2(SCH_1):M_E_DQ'<25>:
 C_SIGNAL='@baseboard_fab2_lib.baseboard_fab2(sch_1):m_e_dq(25)';
NODE_NAME     U5D1 EE74
 '@BASEBOARD_FAB2_LIB.BASEBOARD_FAB2(SCH_1):PAGE27_I172@CHPSET_LIB.SKX_EXT_B(CHIPS)':
 'DDR4_DQ'<25>: CDS_PINID='DDR4_DQ(25)';
NODE_NAME     J4A2 38
 '@BASEBOARD_FAB2_LIB.BASEBOARD_FAB2(SCH_1):PAGE51_I111@MSTR_SCONN.SCONN288_H44441004(CHIPS)':
 'DQ'<24>: CDS_PINID='DQ(24)';
NODE_NAME     J6L2 183
 '@BASEBOARD_FAB2_LIB.BASEBOARD_FAB2(SCH_1):PAGE52_I12@MSTR_SCONN.SCONN288_H44441003(CHIPS)':
 'DQ'<25>: CDS_PINID='DQ(25)';
NET_NAME
'M_E_DQ<26>'
 '@BASEBOARD_FAB2_LIB.BASEBOARD_FAB2(SCH_1):M_E_DQ'<26>:
 C_SIGNAL='@baseboard_fab2_lib.baseboard_fab2(sch_1):m_e_dq(26)';
NODE_NAME     U5D1 EB71
 '@BASEBOARD_FAB2_LIB.BASEBOARD_FAB2(SCH_1):PAGE27_I172@CHPSET_LIB.SKX_EXT_B(CHIPS)':
 'DDR4_DQ'<26>: CDS_PINID='DDR4_DQ(26)';
NODE_NAME     J4A2 190
 '@BASEBOARD_FAB2_LIB.BASEBOARD_FAB2(SCH_1):PAGE51_I111@MSTR_SCONN.SCONN288_H44441004(CHIPS)':
 'DQ'<27>: CDS_PINID='DQ(27)';
NODE_NAME     J6L2 45
 '@BASEBOARD_FAB2_LIB.BASEBOARD_FAB2(SCH_1):PAGE52_I12@MSTR_SCONN.SCONN288_H44441003(CHIPS)':
 'DQ'<26>: CDS_PINID='DQ(26)';
NET_NAME
'M_E_DQ<27>'
 '@BASEBOARD_FAB2_LIB.BASEBOARD_FAB2(SCH_1):M_E_DQ'<27>:
 C_SIGNAL='@baseboard_fab2_lib.baseboard_fab2(sch_1):m_e_dq(27)';
NODE_NAME     U5D1 ED71
 '@BASEBOARD_FAB2_LIB.BASEBOARD_FAB2(SCH_1):PAGE27_I172@CHPSET_LIB.SKX_EXT_B(CHIPS)':
 'DDR4_DQ'<27>: CDS_PINID='DDR4_DQ(27)';
NODE_NAME     J4A2 45
 '@BASEBOARD_FAB2_LIB.BASEBOARD_FAB2(SCH_1):PAGE51_I111@MSTR_SCONN.SCONN288_H44441004(CHIPS)':
 'DQ'<26>: CDS_PINID='DQ(26)';
NODE_NAME     J6L2 190
 '@BASEBOARD_FAB2_LIB.BASEBOARD_FAB2(SCH_1):PAGE52_I12@MSTR_SCONN.SCONN288_H44441003(CHIPS)':
 'DQ'<27>: CDS_PINID='DQ(27)';
NET_NAME
'M_E_DQ<28>'
 '@BASEBOARD_FAB2_LIB.BASEBOARD_FAB2(SCH_1):M_E_DQ'<28>:
 C_SIGNAL='@baseboard_fab2_lib.baseboard_fab2(sch_1):m_e_dq(28)';
NODE_NAME     U5D1 EA74
 '@BASEBOARD_FAB2_LIB.BASEBOARD_FAB2(SCH_1):PAGE27_I172@CHPSET_LIB.SKX_EXT_B(CHIPS)':
 'DDR4_DQ'<28>: CDS_PINID='DDR4_DQ(28)';
NODE_NAME     J4A2 181
 '@BASEBOARD_FAB2_LIB.BASEBOARD_FAB2(SCH_1):PAGE51_I111@MSTR_SCONN.SCONN288_H44441004(CHIPS)':
 'DQ'<29>: CDS_PINID='DQ(29)';
NODE_NAME     J6L2 36
 '@BASEBOARD_FAB2_LIB.BASEBOARD_FAB2(SCH_1):PAGE52_I12@MSTR_SCONN.SCONN288_H44441003(CHIPS)':
 'DQ'<28>: CDS_PINID='DQ(28)';
NET_NAME
'M_E_DQ<29>'
 '@BASEBOARD_FAB2_LIB.BASEBOARD_FAB2(SCH_1):M_E_DQ'<29>:
 C_SIGNAL='@baseboard_fab2_lib.baseboard_fab2(sch_1):m_e_dq(29)';
NODE_NAME     U5D1 EB75
 '@BASEBOARD_FAB2_LIB.BASEBOARD_FAB2(SCH_1):PAGE27_I172@CHPSET_LIB.SKX_EXT_B(CHIPS)':
 'DDR4_DQ'<29>: CDS_PINID='DDR4_DQ(29)';
NODE_NAME     J4A2 36
 '@BASEBOARD_FAB2_LIB.BASEBOARD_FAB2(SCH_1):PAGE51_I111@MSTR_SCONN.SCONN288_H44441004(CHIPS)':
 'DQ'<28>: CDS_PINID='DQ(28)';
NODE_NAME     J6L2 181
 '@BASEBOARD_FAB2_LIB.BASEBOARD_FAB2(SCH_1):PAGE52_I12@MSTR_SCONN.SCONN288_H44441003(CHIPS)':
 'DQ'<29>: CDS_PINID='DQ(29)';
NET_NAME
'M_E_DQ<2>'
 '@BASEBOARD_FAB2_LIB.BASEBOARD_FAB2(SCH_1):M_E_DQ'<2>:
 C_SIGNAL='@baseboard_fab2_lib.baseboard_fab2(sch_1):m_e_dq(2)';
NODE_NAME     U5D1 CT81
 '@BASEBOARD_FAB2_LIB.BASEBOARD_FAB2(SCH_1):PAGE27_I172@CHPSET_LIB.SKX_EXT_B(CHIPS)':
 'DDR4_DQ'<2>: CDS_PINID='DDR4_DQ(2)';
NODE_NAME     J4A2 157
 '@BASEBOARD_FAB2_LIB.BASEBOARD_FAB2(SCH_1):PAGE51_I111@MSTR_SCONN.SCONN288_H44441004(CHIPS)':
 'DQ'<3>: CDS_PINID='DQ(3)';
NODE_NAME     J6L2 12
 '@BASEBOARD_FAB2_LIB.BASEBOARD_FAB2(SCH_1):PAGE52_I12@MSTR_SCONN.SCONN288_H44441003(CHIPS)':
 'DQ'<2>: CDS_PINID='DQ(2)';
NET_NAME
'M_E_DQ<30>'
 '@BASEBOARD_FAB2_LIB.BASEBOARD_FAB2(SCH_1):M_E_DQ'<30>:
 C_SIGNAL='@baseboard_fab2_lib.baseboard_fab2(sch_1):m_e_dq(30)';
NODE_NAME     U5D1 EA72
 '@BASEBOARD_FAB2_LIB.BASEBOARD_FAB2(SCH_1):PAGE27_I172@CHPSET_LIB.SKX_EXT_B(CHIPS)':
 'DDR4_DQ'<30>: CDS_PINID='DDR4_DQ(30)';
NODE_NAME     J4A2 188
 '@BASEBOARD_FAB2_LIB.BASEBOARD_FAB2(SCH_1):PAGE51_I111@MSTR_SCONN.SCONN288_H44441004(CHIPS)':
 'DQ'<31>: CDS_PINID='DQ(31)';
NODE_NAME     J6L2 43
 '@BASEBOARD_FAB2_LIB.BASEBOARD_FAB2(SCH_1):PAGE52_I12@MSTR_SCONN.SCONN288_H44441003(CHIPS)':
 'DQ'<30>: CDS_PINID='DQ(30)';
NET_NAME
'M_E_DQ<31>'
 '@BASEBOARD_FAB2_LIB.BASEBOARD_FAB2(SCH_1):M_E_DQ'<31>:
 C_SIGNAL='@baseboard_fab2_lib.baseboard_fab2(sch_1):m_e_dq(31)';
NODE_NAME     U5D1 EE72
 '@BASEBOARD_FAB2_LIB.BASEBOARD_FAB2(SCH_1):PAGE27_I172@CHPSET_LIB.SKX_EXT_B(CHIPS)':
 'DDR4_DQ'<31>: CDS_PINID='DDR4_DQ(31)';
NODE_NAME     J4A2 43
 '@BASEBOARD_FAB2_LIB.BASEBOARD_FAB2(SCH_1):PAGE51_I111@MSTR_SCONN.SCONN288_H44441004(CHIPS)':
 'DQ'<30>: CDS_PINID='DQ(30)';
NODE_NAME     J6L2 188
 '@BASEBOARD_FAB2_LIB.BASEBOARD_FAB2(SCH_1):PAGE52_I12@MSTR_SCONN.SCONN288_H44441003(CHIPS)':
 'DQ'<31>: CDS_PINID='DQ(31)';
NET_NAME
'M_E_DQ<32>'
 '@BASEBOARD_FAB2_LIB.BASEBOARD_FAB2(SCH_1):M_E_DQ'<32>:
 C_SIGNAL='@baseboard_fab2_lib.baseboard_fab2(sch_1):m_e_dq(32)';
NODE_NAME     U5D1 DU42
 '@BASEBOARD_FAB2_LIB.BASEBOARD_FAB2(SCH_1):PAGE27_I172@CHPSET_LIB.SKX_EXT_B(CHIPS)':
 'DDR4_DQ'<32>: CDS_PINID='DDR4_DQ(32)';
NODE_NAME     J4A2 242
 '@BASEBOARD_FAB2_LIB.BASEBOARD_FAB2(SCH_1):PAGE51_I111@MSTR_SCONN.SCONN288_H44441004(CHIPS)':
 'DQ'<33>: CDS_PINID='DQ(33)';
NODE_NAME     J6L2 97
 '@BASEBOARD_FAB2_LIB.BASEBOARD_FAB2(SCH_1):PAGE52_I12@MSTR_SCONN.SCONN288_H44441003(CHIPS)':
 'DQ'<32>: CDS_PINID='DQ(32)';
NET_NAME
'M_E_DQ<33>'
 '@BASEBOARD_FAB2_LIB.BASEBOARD_FAB2(SCH_1):M_E_DQ'<33>:
 C_SIGNAL='@baseboard_fab2_lib.baseboard_fab2(sch_1):m_e_dq(33)';
NODE_NAME     U5D1 DW42
 '@BASEBOARD_FAB2_LIB.BASEBOARD_FAB2(SCH_1):PAGE27_I172@CHPSET_LIB.SKX_EXT_B(CHIPS)':
 'DDR4_DQ'<33>: CDS_PINID='DDR4_DQ(33)';
NODE_NAME     J4A2 97
 '@BASEBOARD_FAB2_LIB.BASEBOARD_FAB2(SCH_1):PAGE51_I111@MSTR_SCONN.SCONN288_H44441004(CHIPS)':
 'DQ'<32>: CDS_PINID='DQ(32)';
NODE_NAME     J6L2 242
 '@BASEBOARD_FAB2_LIB.BASEBOARD_FAB2(SCH_1):PAGE52_I12@MSTR_SCONN.SCONN288_H44441003(CHIPS)':
 'DQ'<33>: CDS_PINID='DQ(33)';
NET_NAME
'M_E_DQ<34>'
 '@BASEBOARD_FAB2_LIB.BASEBOARD_FAB2(SCH_1):M_E_DQ'<34>:
 C_SIGNAL='@baseboard_fab2_lib.baseboard_fab2(sch_1):m_e_dq(34)';
NODE_NAME     U5D1 DP39
 '@BASEBOARD_FAB2_LIB.BASEBOARD_FAB2(SCH_1):PAGE27_I172@CHPSET_LIB.SKX_EXT_B(CHIPS)':
 'DDR4_DQ'<34>: CDS_PINID='DDR4_DQ(34)';
NODE_NAME     J4A2 249
 '@BASEBOARD_FAB2_LIB.BASEBOARD_FAB2(SCH_1):PAGE51_I111@MSTR_SCONN.SCONN288_H44441004(CHIPS)':
 'DQ'<35>: CDS_PINID='DQ(35)';
NODE_NAME     J6L2 104
 '@BASEBOARD_FAB2_LIB.BASEBOARD_FAB2(SCH_1):PAGE52_I12@MSTR_SCONN.SCONN288_H44441003(CHIPS)':
 'DQ'<34>: CDS_PINID='DQ(34)';
NET_NAME
'M_E_DQ<35>'
 '@BASEBOARD_FAB2_LIB.BASEBOARD_FAB2(SCH_1):M_E_DQ'<35>:
 C_SIGNAL='@baseboard_fab2_lib.baseboard_fab2(sch_1):m_e_dq(35)';
NODE_NAME     U5D1 DT39
 '@BASEBOARD_FAB2_LIB.BASEBOARD_FAB2(SCH_1):PAGE27_I172@CHPSET_LIB.SKX_EXT_B(CHIPS)':
 'DDR4_DQ'<35>: CDS_PINID='DDR4_DQ(35)';
NODE_NAME     J4A2 104
 '@BASEBOARD_FAB2_LIB.BASEBOARD_FAB2(SCH_1):PAGE51_I111@MSTR_SCONN.SCONN288_H44441004(CHIPS)':
 'DQ'<34>: CDS_PINID='DQ(34)';
NODE_NAME     J6L2 249
 '@BASEBOARD_FAB2_LIB.BASEBOARD_FAB2(SCH_1):PAGE52_I12@MSTR_SCONN.SCONN288_H44441003(CHIPS)':
 'DQ'<35>: CDS_PINID='DQ(35)';
NET_NAME
'M_E_DQ<36>'
 '@BASEBOARD_FAB2_LIB.BASEBOARD_FAB2(SCH_1):M_E_DQ'<36>:
 C_SIGNAL='@baseboard_fab2_lib.baseboard_fab2(sch_1):m_e_dq(36)';
NODE_NAME     U5D1 DL42
 '@BASEBOARD_FAB2_LIB.BASEBOARD_FAB2(SCH_1):PAGE27_I172@CHPSET_LIB.SKX_EXT_B(CHIPS)':
 'DDR4_DQ'<36>: CDS_PINID='DDR4_DQ(36)';
NODE_NAME     J4A2 240
 '@BASEBOARD_FAB2_LIB.BASEBOARD_FAB2(SCH_1):PAGE51_I111@MSTR_SCONN.SCONN288_H44441004(CHIPS)':
 'DQ'<37>: CDS_PINID='DQ(37)';
NODE_NAME     J6L2 95
 '@BASEBOARD_FAB2_LIB.BASEBOARD_FAB2(SCH_1):PAGE52_I12@MSTR_SCONN.SCONN288_H44441003(CHIPS)':
 'DQ'<36>: CDS_PINID='DQ(36)';
NET_NAME
'M_E_DQ<37>'
 '@BASEBOARD_FAB2_LIB.BASEBOARD_FAB2(SCH_1):M_E_DQ'<37>:
 C_SIGNAL='@baseboard_fab2_lib.baseboard_fab2(sch_1):m_e_dq(37)';
NODE_NAME     U5D1 DN42
 '@BASEBOARD_FAB2_LIB.BASEBOARD_FAB2(SCH_1):PAGE27_I172@CHPSET_LIB.SKX_EXT_B(CHIPS)':
 'DDR4_DQ'<37>: CDS_PINID='DDR4_DQ(37)';
NODE_NAME     J4A2 95
 '@BASEBOARD_FAB2_LIB.BASEBOARD_FAB2(SCH_1):PAGE51_I111@MSTR_SCONN.SCONN288_H44441004(CHIPS)':
 'DQ'<36>: CDS_PINID='DQ(36)';
NODE_NAME     J6L2 240
 '@BASEBOARD_FAB2_LIB.BASEBOARD_FAB2(SCH_1):PAGE52_I12@MSTR_SCONN.SCONN288_H44441003(CHIPS)':
 'DQ'<37>: CDS_PINID='DQ(37)';
NET_NAME
'M_E_DQ<38>'
 '@BASEBOARD_FAB2_LIB.BASEBOARD_FAB2(SCH_1):M_E_DQ'<38>:
 C_SIGNAL='@baseboard_fab2_lib.baseboard_fab2(sch_1):m_e_dq(38)';
NODE_NAME     U5D1 DN40
 '@BASEBOARD_FAB2_LIB.BASEBOARD_FAB2(SCH_1):PAGE27_I172@CHPSET_LIB.SKX_EXT_B(CHIPS)':
 'DDR4_DQ'<38>: CDS_PINID='DDR4_DQ(38)';
NODE_NAME     J4A2 247
 '@BASEBOARD_FAB2_LIB.BASEBOARD_FAB2(SCH_1):PAGE51_I111@MSTR_SCONN.SCONN288_H44441004(CHIPS)':
 'DQ'<39>: CDS_PINID='DQ(39)';
NODE_NAME     J6L2 102
 '@BASEBOARD_FAB2_LIB.BASEBOARD_FAB2(SCH_1):PAGE52_I12@MSTR_SCONN.SCONN288_H44441003(CHIPS)':
 'DQ'<38>: CDS_PINID='DQ(38)';
NET_NAME
'M_E_DQ<39>'
 '@BASEBOARD_FAB2_LIB.BASEBOARD_FAB2(SCH_1):M_E_DQ'<39>:
 C_SIGNAL='@baseboard_fab2_lib.baseboard_fab2(sch_1):m_e_dq(39)';
NODE_NAME     U5D1 DU40
 '@BASEBOARD_FAB2_LIB.BASEBOARD_FAB2(SCH_1):PAGE27_I172@CHPSET_LIB.SKX_EXT_B(CHIPS)':
 'DDR4_DQ'<39>: CDS_PINID='DDR4_DQ(39)';
NODE_NAME     J4A2 102
 '@BASEBOARD_FAB2_LIB.BASEBOARD_FAB2(SCH_1):PAGE51_I111@MSTR_SCONN.SCONN288_H44441004(CHIPS)':
 'DQ'<38>: CDS_PINID='DQ(38)';
NODE_NAME     J6L2 247
 '@BASEBOARD_FAB2_LIB.BASEBOARD_FAB2(SCH_1):PAGE52_I12@MSTR_SCONN.SCONN288_H44441003(CHIPS)':
 'DQ'<39>: CDS_PINID='DQ(39)';
NET_NAME
'M_E_DQ<3>'
 '@BASEBOARD_FAB2_LIB.BASEBOARD_FAB2(SCH_1):M_E_DQ'<3>:
 C_SIGNAL='@baseboard_fab2_lib.baseboard_fab2(sch_1):m_e_dq(3)';
NODE_NAME     U5D1 CR82
 '@BASEBOARD_FAB2_LIB.BASEBOARD_FAB2(SCH_1):PAGE27_I172@CHPSET_LIB.SKX_EXT_B(CHIPS)':
 'DDR4_DQ'<3>: CDS_PINID='DDR4_DQ(3)';
NODE_NAME     J4A2 12
 '@BASEBOARD_FAB2_LIB.BASEBOARD_FAB2(SCH_1):PAGE51_I111@MSTR_SCONN.SCONN288_H44441004(CHIPS)':
 'DQ'<2>: CDS_PINID='DQ(2)';
NODE_NAME     J6L2 157
 '@BASEBOARD_FAB2_LIB.BASEBOARD_FAB2(SCH_1):PAGE52_I12@MSTR_SCONN.SCONN288_H44441003(CHIPS)':
 'DQ'<3>: CDS_PINID='DQ(3)';
NET_NAME
'M_E_DQ<40>'
 '@BASEBOARD_FAB2_LIB.BASEBOARD_FAB2(SCH_1):M_E_DQ'<40>:
 C_SIGNAL='@baseboard_fab2_lib.baseboard_fab2(sch_1):m_e_dq(40)';
NODE_NAME     U5D1 EC34
 '@BASEBOARD_FAB2_LIB.BASEBOARD_FAB2(SCH_1):PAGE27_I172@CHPSET_LIB.SKX_EXT_B(CHIPS)':
 'DDR4_DQ'<40>: CDS_PINID='DDR4_DQ(40)';
NODE_NAME     J4A2 253
 '@BASEBOARD_FAB2_LIB.BASEBOARD_FAB2(SCH_1):PAGE51_I111@MSTR_SCONN.SCONN288_H44441004(CHIPS)':
 'DQ'<41>: CDS_PINID='DQ(41)';
NODE_NAME     J6L2 108
 '@BASEBOARD_FAB2_LIB.BASEBOARD_FAB2(SCH_1):PAGE52_I12@MSTR_SCONN.SCONN288_H44441003(CHIPS)':
 'DQ'<40>: CDS_PINID='DQ(40)';
NET_NAME
'M_E_DQ<41>'
 '@BASEBOARD_FAB2_LIB.BASEBOARD_FAB2(SCH_1):M_E_DQ'<41>:
 C_SIGNAL='@baseboard_fab2_lib.baseboard_fab2(sch_1):m_e_dq(41)';
NODE_NAME     U5D1 ED33
 '@BASEBOARD_FAB2_LIB.BASEBOARD_FAB2(SCH_1):PAGE27_I172@CHPSET_LIB.SKX_EXT_B(CHIPS)':
 'DDR4_DQ'<41>: CDS_PINID='DDR4_DQ(41)';
NODE_NAME     J4A2 108
 '@BASEBOARD_FAB2_LIB.BASEBOARD_FAB2(SCH_1):PAGE51_I111@MSTR_SCONN.SCONN288_H44441004(CHIPS)':
 'DQ'<40>: CDS_PINID='DQ(40)';
NODE_NAME     J6L2 253
 '@BASEBOARD_FAB2_LIB.BASEBOARD_FAB2(SCH_1):PAGE52_I12@MSTR_SCONN.SCONN288_H44441003(CHIPS)':
 'DQ'<41>: CDS_PINID='DQ(41)';
NET_NAME
'M_E_DQ<42>'
 '@BASEBOARD_FAB2_LIB.BASEBOARD_FAB2(SCH_1):M_E_DQ'<42>:
 C_SIGNAL='@baseboard_fab2_lib.baseboard_fab2(sch_1):m_e_dq(42)';
NODE_NAME     U5D1 EA30
 '@BASEBOARD_FAB2_LIB.BASEBOARD_FAB2(SCH_1):PAGE27_I172@CHPSET_LIB.SKX_EXT_B(CHIPS)':
 'DDR4_DQ'<42>: CDS_PINID='DDR4_DQ(42)';
NODE_NAME     J4A2 260
 '@BASEBOARD_FAB2_LIB.BASEBOARD_FAB2(SCH_1):PAGE51_I111@MSTR_SCONN.SCONN288_H44441004(CHIPS)':
 'DQ'<43>: CDS_PINID='DQ(43)';
NODE_NAME     J6L2 115
 '@BASEBOARD_FAB2_LIB.BASEBOARD_FAB2(SCH_1):PAGE52_I12@MSTR_SCONN.SCONN288_H44441003(CHIPS)':
 'DQ'<42>: CDS_PINID='DQ(42)';
NET_NAME
'M_E_DQ<43>'
 '@BASEBOARD_FAB2_LIB.BASEBOARD_FAB2(SCH_1):M_E_DQ'<43>:
 C_SIGNAL='@baseboard_fab2_lib.baseboard_fab2(sch_1):m_e_dq(43)';
NODE_NAME     U5D1 EC30
 '@BASEBOARD_FAB2_LIB.BASEBOARD_FAB2(SCH_1):PAGE27_I172@CHPSET_LIB.SKX_EXT_B(CHIPS)':
 'DDR4_DQ'<43>: CDS_PINID='DDR4_DQ(43)';
NODE_NAME     J4A2 115
 '@BASEBOARD_FAB2_LIB.BASEBOARD_FAB2(SCH_1):PAGE51_I111@MSTR_SCONN.SCONN288_H44441004(CHIPS)':
 'DQ'<42>: CDS_PINID='DQ(42)';
NODE_NAME     J6L2 260
 '@BASEBOARD_FAB2_LIB.BASEBOARD_FAB2(SCH_1):PAGE52_I12@MSTR_SCONN.SCONN288_H44441003(CHIPS)':
 'DQ'<43>: CDS_PINID='DQ(43)';
NET_NAME
'M_E_DQ<44>'
 '@BASEBOARD_FAB2_LIB.BASEBOARD_FAB2(SCH_1):M_E_DQ'<44>:
 C_SIGNAL='@baseboard_fab2_lib.baseboard_fab2(sch_1):m_e_dq(44)';
NODE_NAME     U5D1 DY33
 '@BASEBOARD_FAB2_LIB.BASEBOARD_FAB2(SCH_1):PAGE27_I172@CHPSET_LIB.SKX_EXT_B(CHIPS)':
 'DDR4_DQ'<44>: CDS_PINID='DDR4_DQ(44)';
NODE_NAME     J4A2 251
 '@BASEBOARD_FAB2_LIB.BASEBOARD_FAB2(SCH_1):PAGE51_I111@MSTR_SCONN.SCONN288_H44441004(CHIPS)':
 'DQ'<45>: CDS_PINID='DQ(45)';
NODE_NAME     J6L2 106
 '@BASEBOARD_FAB2_LIB.BASEBOARD_FAB2(SCH_1):PAGE52_I12@MSTR_SCONN.SCONN288_H44441003(CHIPS)':
 'DQ'<44>: CDS_PINID='DQ(44)';
NET_NAME
'M_E_DQ<45>'
 '@BASEBOARD_FAB2_LIB.BASEBOARD_FAB2(SCH_1):M_E_DQ'<45>:
 C_SIGNAL='@baseboard_fab2_lib.baseboard_fab2(sch_1):m_e_dq(45)';
NODE_NAME     U5D1 EA34
 '@BASEBOARD_FAB2_LIB.BASEBOARD_FAB2(SCH_1):PAGE27_I172@CHPSET_LIB.SKX_EXT_B(CHIPS)':
 'DDR4_DQ'<45>: CDS_PINID='DDR4_DQ(45)';
NODE_NAME     J4A2 106
 '@BASEBOARD_FAB2_LIB.BASEBOARD_FAB2(SCH_1):PAGE51_I111@MSTR_SCONN.SCONN288_H44441004(CHIPS)':
 'DQ'<44>: CDS_PINID='DQ(44)';
NODE_NAME     J6L2 251
 '@BASEBOARD_FAB2_LIB.BASEBOARD_FAB2(SCH_1):PAGE52_I12@MSTR_SCONN.SCONN288_H44441003(CHIPS)':
 'DQ'<45>: CDS_PINID='DQ(45)';
NET_NAME
'M_E_DQ<46>'
 '@BASEBOARD_FAB2_LIB.BASEBOARD_FAB2(SCH_1):M_E_DQ'<46>:
 C_SIGNAL='@baseboard_fab2_lib.baseboard_fab2(sch_1):m_e_dq(46)';
NODE_NAME     U5D1 DY31
 '@BASEBOARD_FAB2_LIB.BASEBOARD_FAB2(SCH_1):PAGE27_I172@CHPSET_LIB.SKX_EXT_B(CHIPS)':
 'DDR4_DQ'<46>: CDS_PINID='DDR4_DQ(46)';
NODE_NAME     J4A2 258
 '@BASEBOARD_FAB2_LIB.BASEBOARD_FAB2(SCH_1):PAGE51_I111@MSTR_SCONN.SCONN288_H44441004(CHIPS)':
 'DQ'<47>: CDS_PINID='DQ(47)';
NODE_NAME     J6L2 113
 '@BASEBOARD_FAB2_LIB.BASEBOARD_FAB2(SCH_1):PAGE52_I12@MSTR_SCONN.SCONN288_H44441003(CHIPS)':
 'DQ'<46>: CDS_PINID='DQ(46)';
NET_NAME
'M_E_DQ<47>'
 '@BASEBOARD_FAB2_LIB.BASEBOARD_FAB2(SCH_1):M_E_DQ'<47>:
 C_SIGNAL='@baseboard_fab2_lib.baseboard_fab2(sch_1):m_e_dq(47)';
NODE_NAME     U5D1 ED31
 '@BASEBOARD_FAB2_LIB.BASEBOARD_FAB2(SCH_1):PAGE27_I172@CHPSET_LIB.SKX_EXT_B(CHIPS)':
 'DDR4_DQ'<47>: CDS_PINID='DDR4_DQ(47)';
NODE_NAME     J4A2 113
 '@BASEBOARD_FAB2_LIB.BASEBOARD_FAB2(SCH_1):PAGE51_I111@MSTR_SCONN.SCONN288_H44441004(CHIPS)':
 'DQ'<46>: CDS_PINID='DQ(46)';
NODE_NAME     J6L2 258
 '@BASEBOARD_FAB2_LIB.BASEBOARD_FAB2(SCH_1):PAGE52_I12@MSTR_SCONN.SCONN288_H44441003(CHIPS)':
 'DQ'<47>: CDS_PINID='DQ(47)';
NET_NAME
'M_E_DQ<48>'
 '@BASEBOARD_FAB2_LIB.BASEBOARD_FAB2(SCH_1):M_E_DQ'<48>:
 C_SIGNAL='@baseboard_fab2_lib.baseboard_fab2(sch_1):m_e_dq(48)';
NODE_NAME     U5D1 EC28
 '@BASEBOARD_FAB2_LIB.BASEBOARD_FAB2(SCH_1):PAGE27_I172@CHPSET_LIB.SKX_EXT_B(CHIPS)':
 'DDR4_DQ'<48>: CDS_PINID='DDR4_DQ(48)';
NODE_NAME     J4A2 264
 '@BASEBOARD_FAB2_LIB.BASEBOARD_FAB2(SCH_1):PAGE51_I111@MSTR_SCONN.SCONN288_H44441004(CHIPS)':
 'DQ'<49>: CDS_PINID='DQ(49)';
NODE_NAME     J6L2 119
 '@BASEBOARD_FAB2_LIB.BASEBOARD_FAB2(SCH_1):PAGE52_I12@MSTR_SCONN.SCONN288_H44441003(CHIPS)':
 'DQ'<48>: CDS_PINID='DQ(48)';
NET_NAME
'M_E_DQ<49>'
 '@BASEBOARD_FAB2_LIB.BASEBOARD_FAB2(SCH_1):M_E_DQ'<49>:
 C_SIGNAL='@baseboard_fab2_lib.baseboard_fab2(sch_1):m_e_dq(49)';
NODE_NAME     U5D1 ED27
 '@BASEBOARD_FAB2_LIB.BASEBOARD_FAB2(SCH_1):PAGE27_I172@CHPSET_LIB.SKX_EXT_B(CHIPS)':
 'DDR4_DQ'<49>: CDS_PINID='DDR4_DQ(49)';
NODE_NAME     J4A2 119
 '@BASEBOARD_FAB2_LIB.BASEBOARD_FAB2(SCH_1):PAGE51_I111@MSTR_SCONN.SCONN288_H44441004(CHIPS)':
 'DQ'<48>: CDS_PINID='DQ(48)';
NODE_NAME     J6L2 264
 '@BASEBOARD_FAB2_LIB.BASEBOARD_FAB2(SCH_1):PAGE52_I12@MSTR_SCONN.SCONN288_H44441003(CHIPS)':
 'DQ'<49>: CDS_PINID='DQ(49)';
NET_NAME
'M_E_DQ<4>'
 '@BASEBOARD_FAB2_LIB.BASEBOARD_FAB2(SCH_1):M_E_DQ'<4>:
 C_SIGNAL='@baseboard_fab2_lib.baseboard_fab2(sch_1):m_e_dq(4)';
NODE_NAME     U5D1 CK79
 '@BASEBOARD_FAB2_LIB.BASEBOARD_FAB2(SCH_1):PAGE27_I172@CHPSET_LIB.SKX_EXT_B(CHIPS)':
 'DDR4_DQ'<4>: CDS_PINID='DDR4_DQ(4)';
NODE_NAME     J4A2 148
 '@BASEBOARD_FAB2_LIB.BASEBOARD_FAB2(SCH_1):PAGE51_I111@MSTR_SCONN.SCONN288_H44441004(CHIPS)':
 'DQ'<5>: CDS_PINID='DQ(5)';
NODE_NAME     J6L2 3
 '@BASEBOARD_FAB2_LIB.BASEBOARD_FAB2(SCH_1):PAGE52_I12@MSTR_SCONN.SCONN288_H44441003(CHIPS)':
 'DQ'<4>: CDS_PINID='DQ(4)';
NET_NAME
'M_E_DQ<50>'
 '@BASEBOARD_FAB2_LIB.BASEBOARD_FAB2(SCH_1):M_E_DQ'<50>:
 C_SIGNAL='@baseboard_fab2_lib.baseboard_fab2(sch_1):m_e_dq(50)';
NODE_NAME     U5D1 EA24
 '@BASEBOARD_FAB2_LIB.BASEBOARD_FAB2(SCH_1):PAGE27_I172@CHPSET_LIB.SKX_EXT_B(CHIPS)':
 'DDR4_DQ'<50>: CDS_PINID='DDR4_DQ(50)';
NODE_NAME     J4A2 271
 '@BASEBOARD_FAB2_LIB.BASEBOARD_FAB2(SCH_1):PAGE51_I111@MSTR_SCONN.SCONN288_H44441004(CHIPS)':
 'DQ'<51>: CDS_PINID='DQ(51)';
NODE_NAME     J6L2 126
 '@BASEBOARD_FAB2_LIB.BASEBOARD_FAB2(SCH_1):PAGE52_I12@MSTR_SCONN.SCONN288_H44441003(CHIPS)':
 'DQ'<50>: CDS_PINID='DQ(50)';
NET_NAME
'M_E_DQ<51>'
 '@BASEBOARD_FAB2_LIB.BASEBOARD_FAB2(SCH_1):M_E_DQ'<51>:
 C_SIGNAL='@baseboard_fab2_lib.baseboard_fab2(sch_1):m_e_dq(51)';
NODE_NAME     U5D1 EC24
 '@BASEBOARD_FAB2_LIB.BASEBOARD_FAB2(SCH_1):PAGE27_I172@CHPSET_LIB.SKX_EXT_B(CHIPS)':
 'DDR4_DQ'<51>: CDS_PINID='DDR4_DQ(51)';
NODE_NAME     J4A2 126
 '@BASEBOARD_FAB2_LIB.BASEBOARD_FAB2(SCH_1):PAGE51_I111@MSTR_SCONN.SCONN288_H44441004(CHIPS)':
 'DQ'<50>: CDS_PINID='DQ(50)';
NODE_NAME     J6L2 271
 '@BASEBOARD_FAB2_LIB.BASEBOARD_FAB2(SCH_1):PAGE52_I12@MSTR_SCONN.SCONN288_H44441003(CHIPS)':
 'DQ'<51>: CDS_PINID='DQ(51)';
NET_NAME
'M_E_DQ<52>'
 '@BASEBOARD_FAB2_LIB.BASEBOARD_FAB2(SCH_1):M_E_DQ'<52>:
 C_SIGNAL='@baseboard_fab2_lib.baseboard_fab2(sch_1):m_e_dq(52)';
NODE_NAME     U5D1 DY27
 '@BASEBOARD_FAB2_LIB.BASEBOARD_FAB2(SCH_1):PAGE27_I172@CHPSET_LIB.SKX_EXT_B(CHIPS)':
 'DDR4_DQ'<52>: CDS_PINID='DDR4_DQ(52)';
NODE_NAME     J4A2 262
 '@BASEBOARD_FAB2_LIB.BASEBOARD_FAB2(SCH_1):PAGE51_I111@MSTR_SCONN.SCONN288_H44441004(CHIPS)':
 'DQ'<53>: CDS_PINID='DQ(53)';
NODE_NAME     J6L2 117
 '@BASEBOARD_FAB2_LIB.BASEBOARD_FAB2(SCH_1):PAGE52_I12@MSTR_SCONN.SCONN288_H44441003(CHIPS)':
 'DQ'<52>: CDS_PINID='DQ(52)';
NET_NAME
'M_E_DQ<53>'
 '@BASEBOARD_FAB2_LIB.BASEBOARD_FAB2(SCH_1):M_E_DQ'<53>:
 C_SIGNAL='@baseboard_fab2_lib.baseboard_fab2(sch_1):m_e_dq(53)';
NODE_NAME     U5D1 EA28
 '@BASEBOARD_FAB2_LIB.BASEBOARD_FAB2(SCH_1):PAGE27_I172@CHPSET_LIB.SKX_EXT_B(CHIPS)':
 'DDR4_DQ'<53>: CDS_PINID='DDR4_DQ(53)';
NODE_NAME     J4A2 117
 '@BASEBOARD_FAB2_LIB.BASEBOARD_FAB2(SCH_1):PAGE51_I111@MSTR_SCONN.SCONN288_H44441004(CHIPS)':
 'DQ'<52>: CDS_PINID='DQ(52)';
NODE_NAME     J6L2 262
 '@BASEBOARD_FAB2_LIB.BASEBOARD_FAB2(SCH_1):PAGE52_I12@MSTR_SCONN.SCONN288_H44441003(CHIPS)':
 'DQ'<53>: CDS_PINID='DQ(53)';
NET_NAME
'M_E_DQ<54>'
 '@BASEBOARD_FAB2_LIB.BASEBOARD_FAB2(SCH_1):M_E_DQ'<54>:
 C_SIGNAL='@baseboard_fab2_lib.baseboard_fab2(sch_1):m_e_dq(54)';
NODE_NAME     U5D1 DY25
 '@BASEBOARD_FAB2_LIB.BASEBOARD_FAB2(SCH_1):PAGE27_I172@CHPSET_LIB.SKX_EXT_B(CHIPS)':
 'DDR4_DQ'<54>: CDS_PINID='DDR4_DQ(54)';
NODE_NAME     J4A2 269
 '@BASEBOARD_FAB2_LIB.BASEBOARD_FAB2(SCH_1):PAGE51_I111@MSTR_SCONN.SCONN288_H44441004(CHIPS)':
 'DQ'<55>: CDS_PINID='DQ(55)';
NODE_NAME     J6L2 124
 '@BASEBOARD_FAB2_LIB.BASEBOARD_FAB2(SCH_1):PAGE52_I12@MSTR_SCONN.SCONN288_H44441003(CHIPS)':
 'DQ'<54>: CDS_PINID='DQ(54)';
NET_NAME
'M_E_DQ<55>'
 '@BASEBOARD_FAB2_LIB.BASEBOARD_FAB2(SCH_1):M_E_DQ'<55>:
 C_SIGNAL='@baseboard_fab2_lib.baseboard_fab2(sch_1):m_e_dq(55)';
NODE_NAME     U5D1 ED25
 '@BASEBOARD_FAB2_LIB.BASEBOARD_FAB2(SCH_1):PAGE27_I172@CHPSET_LIB.SKX_EXT_B(CHIPS)':
 'DDR4_DQ'<55>: CDS_PINID='DDR4_DQ(55)';
NODE_NAME     J4A2 124
 '@BASEBOARD_FAB2_LIB.BASEBOARD_FAB2(SCH_1):PAGE51_I111@MSTR_SCONN.SCONN288_H44441004(CHIPS)':
 'DQ'<54>: CDS_PINID='DQ(54)';
NODE_NAME     J6L2 269
 '@BASEBOARD_FAB2_LIB.BASEBOARD_FAB2(SCH_1):PAGE52_I12@MSTR_SCONN.SCONN288_H44441003(CHIPS)':
 'DQ'<55>: CDS_PINID='DQ(55)';
NET_NAME
'M_E_DQ<56>'
 '@BASEBOARD_FAB2_LIB.BASEBOARD_FAB2(SCH_1):M_E_DQ'<56>:
 C_SIGNAL='@baseboard_fab2_lib.baseboard_fab2(sch_1):m_e_dq(56)';
NODE_NAME     U5D1 DF27
 '@BASEBOARD_FAB2_LIB.BASEBOARD_FAB2(SCH_1):PAGE27_I172@CHPSET_LIB.SKX_EXT_B(CHIPS)':
 'DDR4_DQ'<56>: CDS_PINID='DDR4_DQ(56)';
NODE_NAME     J4A2 275
 '@BASEBOARD_FAB2_LIB.BASEBOARD_FAB2(SCH_1):PAGE51_I111@MSTR_SCONN.SCONN288_H44441004(CHIPS)':
 'DQ'<57>: CDS_PINID='DQ(57)';
NODE_NAME     J6L2 130
 '@BASEBOARD_FAB2_LIB.BASEBOARD_FAB2(SCH_1):PAGE52_I12@MSTR_SCONN.SCONN288_H44441003(CHIPS)':
 'DQ'<56>: CDS_PINID='DQ(56)';
NET_NAME
'M_E_DQ<57>'
 '@BASEBOARD_FAB2_LIB.BASEBOARD_FAB2(SCH_1):M_E_DQ'<57>:
 C_SIGNAL='@baseboard_fab2_lib.baseboard_fab2(sch_1):m_e_dq(57)';
NODE_NAME     U5D1 DK27
 '@BASEBOARD_FAB2_LIB.BASEBOARD_FAB2(SCH_1):PAGE27_I172@CHPSET_LIB.SKX_EXT_B(CHIPS)':
 'DDR4_DQ'<57>: CDS_PINID='DDR4_DQ(57)';
NODE_NAME     J4A2 130
 '@BASEBOARD_FAB2_LIB.BASEBOARD_FAB2(SCH_1):PAGE51_I111@MSTR_SCONN.SCONN288_H44441004(CHIPS)':
 'DQ'<56>: CDS_PINID='DQ(56)';
NODE_NAME     J6L2 275
 '@BASEBOARD_FAB2_LIB.BASEBOARD_FAB2(SCH_1):PAGE52_I12@MSTR_SCONN.SCONN288_H44441003(CHIPS)':
 'DQ'<57>: CDS_PINID='DQ(57)';
NET_NAME
'M_E_DQ<58>'
 '@BASEBOARD_FAB2_LIB.BASEBOARD_FAB2(SCH_1):M_E_DQ'<58>:
 C_SIGNAL='@baseboard_fab2_lib.baseboard_fab2(sch_1):m_e_dq(58)';
NODE_NAME     U5D1 DD25
 '@BASEBOARD_FAB2_LIB.BASEBOARD_FAB2(SCH_1):PAGE27_I172@CHPSET_LIB.SKX_EXT_B(CHIPS)':
 'DDR4_DQ'<58>: CDS_PINID='DDR4_DQ(58)';
NODE_NAME     J4A2 282
 '@BASEBOARD_FAB2_LIB.BASEBOARD_FAB2(SCH_1):PAGE51_I111@MSTR_SCONN.SCONN288_H44441004(CHIPS)':
 'DQ'<59>: CDS_PINID='DQ(59)';
NODE_NAME     J6L2 137
 '@BASEBOARD_FAB2_LIB.BASEBOARD_FAB2(SCH_1):PAGE52_I12@MSTR_SCONN.SCONN288_H44441003(CHIPS)':
 'DQ'<58>: CDS_PINID='DQ(58)';
NET_NAME
'M_E_DQ<59>'
 '@BASEBOARD_FAB2_LIB.BASEBOARD_FAB2(SCH_1):M_E_DQ'<59>:
 C_SIGNAL='@baseboard_fab2_lib.baseboard_fab2(sch_1):m_e_dq(59)';
NODE_NAME     U5D1 DJ24
 '@BASEBOARD_FAB2_LIB.BASEBOARD_FAB2(SCH_1):PAGE27_I172@CHPSET_LIB.SKX_EXT_B(CHIPS)':
 'DDR4_DQ'<59>: CDS_PINID='DDR4_DQ(59)';
NODE_NAME     J4A2 137
 '@BASEBOARD_FAB2_LIB.BASEBOARD_FAB2(SCH_1):PAGE51_I111@MSTR_SCONN.SCONN288_H44441004(CHIPS)':
 'DQ'<58>: CDS_PINID='DQ(58)';
NODE_NAME     J6L2 282
 '@BASEBOARD_FAB2_LIB.BASEBOARD_FAB2(SCH_1):PAGE52_I12@MSTR_SCONN.SCONN288_H44441003(CHIPS)':
 'DQ'<59>: CDS_PINID='DQ(59)';
NET_NAME
'M_E_DQ<5>'
 '@BASEBOARD_FAB2_LIB.BASEBOARD_FAB2(SCH_1):M_E_DQ'<5>:
 C_SIGNAL='@baseboard_fab2_lib.baseboard_fab2(sch_1):m_e_dq(5)';
NODE_NAME     U5D1 CJ80
 '@BASEBOARD_FAB2_LIB.BASEBOARD_FAB2(SCH_1):PAGE27_I172@CHPSET_LIB.SKX_EXT_B(CHIPS)':
 'DDR4_DQ'<5>: CDS_PINID='DDR4_DQ(5)';
NODE_NAME     J4A2 3
 '@BASEBOARD_FAB2_LIB.BASEBOARD_FAB2(SCH_1):PAGE51_I111@MSTR_SCONN.SCONN288_H44441004(CHIPS)':
 'DQ'<4>: CDS_PINID='DQ(4)';
NODE_NAME     J6L2 148
 '@BASEBOARD_FAB2_LIB.BASEBOARD_FAB2(SCH_1):PAGE52_I12@MSTR_SCONN.SCONN288_H44441003(CHIPS)':
 'DQ'<5>: CDS_PINID='DQ(5)';
NET_NAME
'M_E_DQ<60>'
 '@BASEBOARD_FAB2_LIB.BASEBOARD_FAB2(SCH_1):M_E_DQ'<60>:
 C_SIGNAL='@baseboard_fab2_lib.baseboard_fab2(sch_1):m_e_dq(60)';
NODE_NAME     U5D1 DG28
 '@BASEBOARD_FAB2_LIB.BASEBOARD_FAB2(SCH_1):PAGE27_I172@CHPSET_LIB.SKX_EXT_B(CHIPS)':
 'DDR4_DQ'<60>: CDS_PINID='DDR4_DQ(60)';
NODE_NAME     J4A2 273
 '@BASEBOARD_FAB2_LIB.BASEBOARD_FAB2(SCH_1):PAGE51_I111@MSTR_SCONN.SCONN288_H44441004(CHIPS)':
 'DQ'<61>: CDS_PINID='DQ(61)';
NODE_NAME     J6L2 128
 '@BASEBOARD_FAB2_LIB.BASEBOARD_FAB2(SCH_1):PAGE52_I12@MSTR_SCONN.SCONN288_H44441003(CHIPS)':
 'DQ'<60>: CDS_PINID='DQ(60)';
NET_NAME
'M_E_DQ<61>'
 '@BASEBOARD_FAB2_LIB.BASEBOARD_FAB2(SCH_1):M_E_DQ'<61>:
 C_SIGNAL='@baseboard_fab2_lib.baseboard_fab2(sch_1):m_e_dq(61)';
NODE_NAME     U5D1 DJ28
 '@BASEBOARD_FAB2_LIB.BASEBOARD_FAB2(SCH_1):PAGE27_I172@CHPSET_LIB.SKX_EXT_B(CHIPS)':
 'DDR4_DQ'<61>: CDS_PINID='DDR4_DQ(61)';
NODE_NAME     J4A2 128
 '@BASEBOARD_FAB2_LIB.BASEBOARD_FAB2(SCH_1):PAGE51_I111@MSTR_SCONN.SCONN288_H44441004(CHIPS)':
 'DQ'<60>: CDS_PINID='DQ(60)';
NODE_NAME     J6L2 273
 '@BASEBOARD_FAB2_LIB.BASEBOARD_FAB2(SCH_1):PAGE52_I12@MSTR_SCONN.SCONN288_H44441003(CHIPS)':
 'DQ'<61>: CDS_PINID='DQ(61)';
NET_NAME
'M_E_DQ<62>'
 '@BASEBOARD_FAB2_LIB.BASEBOARD_FAB2(SCH_1):M_E_DQ'<62>:
 C_SIGNAL='@baseboard_fab2_lib.baseboard_fab2(sch_1):m_e_dq(62)';
NODE_NAME     U5D1 DF25
 '@BASEBOARD_FAB2_LIB.BASEBOARD_FAB2(SCH_1):PAGE27_I172@CHPSET_LIB.SKX_EXT_B(CHIPS)':
 'DDR4_DQ'<62>: CDS_PINID='DDR4_DQ(62)';
NODE_NAME     J4A2 280
 '@BASEBOARD_FAB2_LIB.BASEBOARD_FAB2(SCH_1):PAGE51_I111@MSTR_SCONN.SCONN288_H44441004(CHIPS)':
 'DQ'<63>: CDS_PINID='DQ(63)';
NODE_NAME     J6L2 135
 '@BASEBOARD_FAB2_LIB.BASEBOARD_FAB2(SCH_1):PAGE52_I12@MSTR_SCONN.SCONN288_H44441003(CHIPS)':
 'DQ'<62>: CDS_PINID='DQ(62)';
NET_NAME
'M_E_DQ<63>'
 '@BASEBOARD_FAB2_LIB.BASEBOARD_FAB2(SCH_1):M_E_DQ'<63>:
 C_SIGNAL='@baseboard_fab2_lib.baseboard_fab2(sch_1):m_e_dq(63)';
NODE_NAME     U5D1 DK25
 '@BASEBOARD_FAB2_LIB.BASEBOARD_FAB2(SCH_1):PAGE27_I172@CHPSET_LIB.SKX_EXT_B(CHIPS)':
 'DDR4_DQ'<63>: CDS_PINID='DDR4_DQ(63)';
NODE_NAME     J4A2 135
 '@BASEBOARD_FAB2_LIB.BASEBOARD_FAB2(SCH_1):PAGE51_I111@MSTR_SCONN.SCONN288_H44441004(CHIPS)':
 'DQ'<62>: CDS_PINID='DQ(62)';
NODE_NAME     J6L2 280
 '@BASEBOARD_FAB2_LIB.BASEBOARD_FAB2(SCH_1):PAGE52_I12@MSTR_SCONN.SCONN288_H44441003(CHIPS)':
 'DQ'<63>: CDS_PINID='DQ(63)';
NET_NAME
'M_E_DQ<6>'
 '@BASEBOARD_FAB2_LIB.BASEBOARD_FAB2(SCH_1):M_E_DQ'<6>:
 C_SIGNAL='@baseboard_fab2_lib.baseboard_fab2(sch_1):m_e_dq(6)';
NODE_NAME     U5D1 CR80
 '@BASEBOARD_FAB2_LIB.BASEBOARD_FAB2(SCH_1):PAGE27_I172@CHPSET_LIB.SKX_EXT_B(CHIPS)':
 'DDR4_DQ'<6>: CDS_PINID='DDR4_DQ(6)';
NODE_NAME     J4A2 155
 '@BASEBOARD_FAB2_LIB.BASEBOARD_FAB2(SCH_1):PAGE51_I111@MSTR_SCONN.SCONN288_H44441004(CHIPS)':
 'DQ'<7>: CDS_PINID='DQ(7)';
NODE_NAME     J6L2 10
 '@BASEBOARD_FAB2_LIB.BASEBOARD_FAB2(SCH_1):PAGE52_I12@MSTR_SCONN.SCONN288_H44441003(CHIPS)':
 'DQ'<6>: CDS_PINID='DQ(6)';
NET_NAME
'M_E_DQ<7>'
 '@BASEBOARD_FAB2_LIB.BASEBOARD_FAB2(SCH_1):M_E_DQ'<7>:
 C_SIGNAL='@baseboard_fab2_lib.baseboard_fab2(sch_1):m_e_dq(7)';
NODE_NAME     U5D1 CN82
 '@BASEBOARD_FAB2_LIB.BASEBOARD_FAB2(SCH_1):PAGE27_I172@CHPSET_LIB.SKX_EXT_B(CHIPS)':
 'DDR4_DQ'<7>: CDS_PINID='DDR4_DQ(7)';
NODE_NAME     J4A2 10
 '@BASEBOARD_FAB2_LIB.BASEBOARD_FAB2(SCH_1):PAGE51_I111@MSTR_SCONN.SCONN288_H44441004(CHIPS)':
 'DQ'<6>: CDS_PINID='DQ(6)';
NODE_NAME     J6L2 155
 '@BASEBOARD_FAB2_LIB.BASEBOARD_FAB2(SCH_1):PAGE52_I12@MSTR_SCONN.SCONN288_H44441003(CHIPS)':
 'DQ'<7>: CDS_PINID='DQ(7)';
NET_NAME
'M_E_DQ<8>'
 '@BASEBOARD_FAB2_LIB.BASEBOARD_FAB2(SCH_1):M_E_DQ'<8>:
 C_SIGNAL='@baseboard_fab2_lib.baseboard_fab2(sch_1):m_e_dq(8)';
NODE_NAME     U5D1 DB79
 '@BASEBOARD_FAB2_LIB.BASEBOARD_FAB2(SCH_1):PAGE27_I172@CHPSET_LIB.SKX_EXT_B(CHIPS)':
 'DDR4_DQ'<8>: CDS_PINID='DDR4_DQ(8)';
NODE_NAME     J4A2 161
 '@BASEBOARD_FAB2_LIB.BASEBOARD_FAB2(SCH_1):PAGE51_I111@MSTR_SCONN.SCONN288_H44441004(CHIPS)':
 'DQ'<9>: CDS_PINID='DQ(9)';
NODE_NAME     J6L2 16
 '@BASEBOARD_FAB2_LIB.BASEBOARD_FAB2(SCH_1):PAGE52_I12@MSTR_SCONN.SCONN288_H44441003(CHIPS)':
 'DQ'<8>: CDS_PINID='DQ(8)';
NET_NAME
'M_E_DQ<9>'
 '@BASEBOARD_FAB2_LIB.BASEBOARD_FAB2(SCH_1):M_E_DQ'<9>:
 C_SIGNAL='@baseboard_fab2_lib.baseboard_fab2(sch_1):m_e_dq(9)';
NODE_NAME     U5D1 CY81
 '@BASEBOARD_FAB2_LIB.BASEBOARD_FAB2(SCH_1):PAGE27_I172@CHPSET_LIB.SKX_EXT_B(CHIPS)':
 'DDR4_DQ'<9>: CDS_PINID='DDR4_DQ(9)';
NODE_NAME     J4A2 16
 '@BASEBOARD_FAB2_LIB.BASEBOARD_FAB2(SCH_1):PAGE51_I111@MSTR_SCONN.SCONN288_H44441004(CHIPS)':
 'DQ'<8>: CDS_PINID='DQ(8)';
NODE_NAME     J6L2 161
 '@BASEBOARD_FAB2_LIB.BASEBOARD_FAB2(SCH_1):PAGE52_I12@MSTR_SCONN.SCONN288_H44441003(CHIPS)':
 'DQ'<9>: CDS_PINID='DQ(9)';
NET_NAME
'M_E_DQS_DN<0>'
 '@BASEBOARD_FAB2_LIB.BASEBOARD_FAB2(SCH_1):M_E_DQS_DN'<0>:
 C_SIGNAL='@baseboard_fab2_lib.baseboard_fab2(sch_1):m_e_dqs_dn(0)';
NODE_NAME     U5D1 CL82
 '@BASEBOARD_FAB2_LIB.BASEBOARD_FAB2(SCH_1):PAGE27_I172@CHPSET_LIB.SKX_EXT_B(CHIPS)':
 'DDR4_DQS_DN'<0>: CDS_PINID='DDR4_DQS_DN(0)';
NODE_NAME     J4A2 152
 '@BASEBOARD_FAB2_LIB.BASEBOARD_FAB2(SCH_1):PAGE51_I66@MSTR_SCONN.SCONN288_H44441004(CHIPS)':
 'DQS0N': CDS_PINID='DQS0N';
NODE_NAME     J6L2 152
 '@BASEBOARD_FAB2_LIB.BASEBOARD_FAB2(SCH_1):PAGE52_I100@MSTR_SCONN.SCONN288_H44441003(CHIPS)':
 'DQS0N': CDS_PINID='DQS0N';
NET_NAME
'M_E_DQS_DN<10>'
 '@BASEBOARD_FAB2_LIB.BASEBOARD_FAB2(SCH_1):M_E_DQS_DN'<10>:
 C_SIGNAL='@baseboard_fab2_lib.baseboard_fab2(sch_1):m_e_dqs_dn(10)';
NODE_NAME     U5D1 DC80
 '@BASEBOARD_FAB2_LIB.BASEBOARD_FAB2(SCH_1):PAGE27_I172@CHPSET_LIB.SKX_EXT_B(CHIPS)':
 'DDR4_DQS_DN'<10>: CDS_PINID='DDR4_DQS_DN(10)';
NODE_NAME     J4A2 19
 '@BASEBOARD_FAB2_LIB.BASEBOARD_FAB2(SCH_1):PAGE51_I66@MSTR_SCONN.SCONN288_H44441004(CHIPS)':
 'DQS10N': CDS_PINID='DQS10N';
NODE_NAME     J6L2 19
 '@BASEBOARD_FAB2_LIB.BASEBOARD_FAB2(SCH_1):PAGE52_I100@MSTR_SCONN.SCONN288_H44441003(CHIPS)':
 'DQS10N': CDS_PINID='DQS10N';
NET_NAME
'M_E_DQS_DN<11>'
 '@BASEBOARD_FAB2_LIB.BASEBOARD_FAB2(SCH_1):M_E_DQS_DN'<11>:
 C_SIGNAL='@baseboard_fab2_lib.baseboard_fab2(sch_1):m_e_dqs_dn(11)';
NODE_NAME     U5D1 DY79
 '@BASEBOARD_FAB2_LIB.BASEBOARD_FAB2(SCH_1):PAGE27_I172@CHPSET_LIB.SKX_EXT_B(CHIPS)':
 'DDR4_DQS_DN'<11>: CDS_PINID='DDR4_DQS_DN(11)';
NODE_NAME     J4A2 30
 '@BASEBOARD_FAB2_LIB.BASEBOARD_FAB2(SCH_1):PAGE51_I66@MSTR_SCONN.SCONN288_H44441004(CHIPS)':
 'DQS11N': CDS_PINID='DQS11N';
NODE_NAME     J6L2 30
 '@BASEBOARD_FAB2_LIB.BASEBOARD_FAB2(SCH_1):PAGE52_I100@MSTR_SCONN.SCONN288_H44441003(CHIPS)':
 'DQS11N': CDS_PINID='DQS11N';
NET_NAME
'M_E_DQS_DN<12>'
 '@BASEBOARD_FAB2_LIB.BASEBOARD_FAB2(SCH_1):M_E_DQS_DN'<12>:
 C_SIGNAL='@baseboard_fab2_lib.baseboard_fab2(sch_1):m_e_dqs_dn(12)';
NODE_NAME     U5D1 EB73
 '@BASEBOARD_FAB2_LIB.BASEBOARD_FAB2(SCH_1):PAGE27_I172@CHPSET_LIB.SKX_EXT_B(CHIPS)':
 'DDR4_DQS_DN'<12>: CDS_PINID='DDR4_DQS_DN(12)';
NODE_NAME     J4A2 41
 '@BASEBOARD_FAB2_LIB.BASEBOARD_FAB2(SCH_1):PAGE51_I66@MSTR_SCONN.SCONN288_H44441004(CHIPS)':
 'DQS12N': CDS_PINID='DQS12N';
NODE_NAME     J6L2 41
 '@BASEBOARD_FAB2_LIB.BASEBOARD_FAB2(SCH_1):PAGE52_I100@MSTR_SCONN.SCONN288_H44441003(CHIPS)':
 'DQS12N': CDS_PINID='DQS12N';
NET_NAME
'M_E_DQS_DN<13>'
 '@BASEBOARD_FAB2_LIB.BASEBOARD_FAB2(SCH_1):M_E_DQS_DN'<13>:
 C_SIGNAL='@baseboard_fab2_lib.baseboard_fab2(sch_1):m_e_dqs_dn(13)';
NODE_NAME     U5D1 DP41
 '@BASEBOARD_FAB2_LIB.BASEBOARD_FAB2(SCH_1):PAGE27_I172@CHPSET_LIB.SKX_EXT_B(CHIPS)':
 'DDR4_DQS_DN'<13>: CDS_PINID='DDR4_DQS_DN(13)';
NODE_NAME     J4A2 100
 '@BASEBOARD_FAB2_LIB.BASEBOARD_FAB2(SCH_1):PAGE51_I66@MSTR_SCONN.SCONN288_H44441004(CHIPS)':
 'DQS13N': CDS_PINID='DQS13N';
NODE_NAME     J6L2 100
 '@BASEBOARD_FAB2_LIB.BASEBOARD_FAB2(SCH_1):PAGE52_I100@MSTR_SCONN.SCONN288_H44441003(CHIPS)':
 'DQS13N': CDS_PINID='DQS13N';
NET_NAME
'M_E_DQS_DN<14>'
 '@BASEBOARD_FAB2_LIB.BASEBOARD_FAB2(SCH_1):M_E_DQS_DN'<14>:
 C_SIGNAL='@baseboard_fab2_lib.baseboard_fab2(sch_1):m_e_dqs_dn(14)';
NODE_NAME     U5D1 EA32
 '@BASEBOARD_FAB2_LIB.BASEBOARD_FAB2(SCH_1):PAGE27_I172@CHPSET_LIB.SKX_EXT_B(CHIPS)':
 'DDR4_DQS_DN'<14>: CDS_PINID='DDR4_DQS_DN(14)';
NODE_NAME     J4A2 111
 '@BASEBOARD_FAB2_LIB.BASEBOARD_FAB2(SCH_1):PAGE51_I66@MSTR_SCONN.SCONN288_H44441004(CHIPS)':
 'DQS14N': CDS_PINID='DQS14N';
NODE_NAME     J6L2 111
 '@BASEBOARD_FAB2_LIB.BASEBOARD_FAB2(SCH_1):PAGE52_I100@MSTR_SCONN.SCONN288_H44441003(CHIPS)':
 'DQS14N': CDS_PINID='DQS14N';
NET_NAME
'M_E_DQS_DN<15>'
 '@BASEBOARD_FAB2_LIB.BASEBOARD_FAB2(SCH_1):M_E_DQS_DN'<15>:
 C_SIGNAL='@baseboard_fab2_lib.baseboard_fab2(sch_1):m_e_dqs_dn(15)';
NODE_NAME     U5D1 EA26
 '@BASEBOARD_FAB2_LIB.BASEBOARD_FAB2(SCH_1):PAGE27_I172@CHPSET_LIB.SKX_EXT_B(CHIPS)':
 'DDR4_DQS_DN'<15>: CDS_PINID='DDR4_DQS_DN(15)';
NODE_NAME     J4A2 122
 '@BASEBOARD_FAB2_LIB.BASEBOARD_FAB2(SCH_1):PAGE51_I66@MSTR_SCONN.SCONN288_H44441004(CHIPS)':
 'DQS15N': CDS_PINID='DQS15N';
NODE_NAME     J6L2 122
 '@BASEBOARD_FAB2_LIB.BASEBOARD_FAB2(SCH_1):PAGE52_I100@MSTR_SCONN.SCONN288_H44441003(CHIPS)':
 'DQS15N': CDS_PINID='DQS15N';
NET_NAME
'M_E_DQS_DN<16>'
 '@BASEBOARD_FAB2_LIB.BASEBOARD_FAB2(SCH_1):M_E_DQS_DN'<16>:
 C_SIGNAL='@baseboard_fab2_lib.baseboard_fab2(sch_1):m_e_dqs_dn(16)';
NODE_NAME     U5D1 DG26
 '@BASEBOARD_FAB2_LIB.BASEBOARD_FAB2(SCH_1):PAGE27_I172@CHPSET_LIB.SKX_EXT_B(CHIPS)':
 'DDR4_DQS_DN'<16>: CDS_PINID='DDR4_DQS_DN(16)';
NODE_NAME     J4A2 133
 '@BASEBOARD_FAB2_LIB.BASEBOARD_FAB2(SCH_1):PAGE51_I66@MSTR_SCONN.SCONN288_H44441004(CHIPS)':
 'DQS16N': CDS_PINID='DQS16N';
NODE_NAME     J6L2 133
 '@BASEBOARD_FAB2_LIB.BASEBOARD_FAB2(SCH_1):PAGE52_I100@MSTR_SCONN.SCONN288_H44441003(CHIPS)':
 'DQS16N': CDS_PINID='DQS16N';
NET_NAME
'M_E_DQS_DN<17>'
 '@BASEBOARD_FAB2_LIB.BASEBOARD_FAB2(SCH_1):M_E_DQS_DN'<17>:
 C_SIGNAL='@baseboard_fab2_lib.baseboard_fab2(sch_1):m_e_dqs_dn(17)';
NODE_NAME     U5D1 DV67
 '@BASEBOARD_FAB2_LIB.BASEBOARD_FAB2(SCH_1):PAGE27_I172@CHPSET_LIB.SKX_EXT_B(CHIPS)':
 'DDR4_DQS_DN'<17>: CDS_PINID='DDR4_DQS_DN(17)';
NODE_NAME     J4A2 52
 '@BASEBOARD_FAB2_LIB.BASEBOARD_FAB2(SCH_1):PAGE51_I66@MSTR_SCONN.SCONN288_H44441004(CHIPS)':
 'DQS17N': CDS_PINID='DQS17N';
NODE_NAME     J6L2 52
 '@BASEBOARD_FAB2_LIB.BASEBOARD_FAB2(SCH_1):PAGE52_I100@MSTR_SCONN.SCONN288_H44441003(CHIPS)':
 'DQS17N': CDS_PINID='DQS17N';
NET_NAME
'M_E_DQS_DN<1>'
 '@BASEBOARD_FAB2_LIB.BASEBOARD_FAB2(SCH_1):M_E_DQS_DN'<1>:
 C_SIGNAL='@baseboard_fab2_lib.baseboard_fab2(sch_1):m_e_dqs_dn(1)';
NODE_NAME     U5D1 DA82
 '@BASEBOARD_FAB2_LIB.BASEBOARD_FAB2(SCH_1):PAGE27_I172@CHPSET_LIB.SKX_EXT_B(CHIPS)':
 'DDR4_DQS_DN'<1>: CDS_PINID='DDR4_DQS_DN(1)';
NODE_NAME     J4A2 163
 '@BASEBOARD_FAB2_LIB.BASEBOARD_FAB2(SCH_1):PAGE51_I66@MSTR_SCONN.SCONN288_H44441004(CHIPS)':
 'DQS1N': CDS_PINID='DQS1N';
NODE_NAME     J6L2 163
 '@BASEBOARD_FAB2_LIB.BASEBOARD_FAB2(SCH_1):PAGE52_I100@MSTR_SCONN.SCONN288_H44441003(CHIPS)':
 'DQS1N': CDS_PINID='DQS1N';
NET_NAME
'M_E_DQS_DN<2>'
 '@BASEBOARD_FAB2_LIB.BASEBOARD_FAB2(SCH_1):M_E_DQS_DN'<2>:
 C_SIGNAL='@baseboard_fab2_lib.baseboard_fab2(sch_1):m_e_dqs_dn(2)';
NODE_NAME     U5D1 ED79
 '@BASEBOARD_FAB2_LIB.BASEBOARD_FAB2(SCH_1):PAGE27_I172@CHPSET_LIB.SKX_EXT_B(CHIPS)':
 'DDR4_DQS_DN'<2>: CDS_PINID='DDR4_DQS_DN(2)';
NODE_NAME     J4A2 174
 '@BASEBOARD_FAB2_LIB.BASEBOARD_FAB2(SCH_1):PAGE51_I66@MSTR_SCONN.SCONN288_H44441004(CHIPS)':
 'DQS2N': CDS_PINID='DQS2N';
NODE_NAME     J6L2 174
 '@BASEBOARD_FAB2_LIB.BASEBOARD_FAB2(SCH_1):PAGE52_I100@MSTR_SCONN.SCONN288_H44441003(CHIPS)':
 'DQS2N': CDS_PINID='DQS2N';
NET_NAME
'M_E_DQS_DN<3>'
 '@BASEBOARD_FAB2_LIB.BASEBOARD_FAB2(SCH_1):M_E_DQS_DN'<3>:
 C_SIGNAL='@baseboard_fab2_lib.baseboard_fab2(sch_1):m_e_dqs_dn(3)';
NODE_NAME     U5D1 EF73
 '@BASEBOARD_FAB2_LIB.BASEBOARD_FAB2(SCH_1):PAGE27_I172@CHPSET_LIB.SKX_EXT_B(CHIPS)':
 'DDR4_DQS_DN'<3>: CDS_PINID='DDR4_DQS_DN(3)';
NODE_NAME     J4A2 185
 '@BASEBOARD_FAB2_LIB.BASEBOARD_FAB2(SCH_1):PAGE51_I66@MSTR_SCONN.SCONN288_H44441004(CHIPS)':
 'DQS3N': CDS_PINID='DQS3N';
NODE_NAME     J6L2 185
 '@BASEBOARD_FAB2_LIB.BASEBOARD_FAB2(SCH_1):PAGE52_I100@MSTR_SCONN.SCONN288_H44441003(CHIPS)':
 'DQS3N': CDS_PINID='DQS3N';
NET_NAME
'M_E_DQS_DN<4>'
 '@BASEBOARD_FAB2_LIB.BASEBOARD_FAB2(SCH_1):M_E_DQS_DN'<4>:
 C_SIGNAL='@baseboard_fab2_lib.baseboard_fab2(sch_1):m_e_dqs_dn(4)';
NODE_NAME     U5D1 DV41
 '@BASEBOARD_FAB2_LIB.BASEBOARD_FAB2(SCH_1):PAGE27_I172@CHPSET_LIB.SKX_EXT_B(CHIPS)':
 'DDR4_DQS_DN'<4>: CDS_PINID='DDR4_DQS_DN(4)';
NODE_NAME     J4A2 244
 '@BASEBOARD_FAB2_LIB.BASEBOARD_FAB2(SCH_1):PAGE51_I66@MSTR_SCONN.SCONN288_H44441004(CHIPS)':
 'DQS4N': CDS_PINID='DQS4N';
NODE_NAME     J6L2 244
 '@BASEBOARD_FAB2_LIB.BASEBOARD_FAB2(SCH_1):PAGE52_I100@MSTR_SCONN.SCONN288_H44441003(CHIPS)':
 'DQS4N': CDS_PINID='DQS4N';
NET_NAME
'M_E_DQS_DN<5>'
 '@BASEBOARD_FAB2_LIB.BASEBOARD_FAB2(SCH_1):M_E_DQS_DN'<5>:
 C_SIGNAL='@baseboard_fab2_lib.baseboard_fab2(sch_1):m_e_dqs_dn(5)';
NODE_NAME     U5D1 EE32
 '@BASEBOARD_FAB2_LIB.BASEBOARD_FAB2(SCH_1):PAGE27_I172@CHPSET_LIB.SKX_EXT_B(CHIPS)':
 'DDR4_DQS_DN'<5>: CDS_PINID='DDR4_DQS_DN(5)';
NODE_NAME     J4A2 255
 '@BASEBOARD_FAB2_LIB.BASEBOARD_FAB2(SCH_1):PAGE51_I66@MSTR_SCONN.SCONN288_H44441004(CHIPS)':
 'DQS5N': CDS_PINID='DQS5N';
NODE_NAME     J6L2 255
 '@BASEBOARD_FAB2_LIB.BASEBOARD_FAB2(SCH_1):PAGE52_I100@MSTR_SCONN.SCONN288_H44441003(CHIPS)':
 'DQS5N': CDS_PINID='DQS5N';
NET_NAME
'M_E_DQS_DN<6>'
 '@BASEBOARD_FAB2_LIB.BASEBOARD_FAB2(SCH_1):M_E_DQS_DN'<6>:
 C_SIGNAL='@baseboard_fab2_lib.baseboard_fab2(sch_1):m_e_dqs_dn(6)';
NODE_NAME     U5D1 EE26
 '@BASEBOARD_FAB2_LIB.BASEBOARD_FAB2(SCH_1):PAGE27_I172@CHPSET_LIB.SKX_EXT_B(CHIPS)':
 'DDR4_DQS_DN'<6>: CDS_PINID='DDR4_DQS_DN(6)';
NODE_NAME     J4A2 266
 '@BASEBOARD_FAB2_LIB.BASEBOARD_FAB2(SCH_1):PAGE51_I66@MSTR_SCONN.SCONN288_H44441004(CHIPS)':
 'DQS6N': CDS_PINID='DQS6N';
NODE_NAME     J6L2 266
 '@BASEBOARD_FAB2_LIB.BASEBOARD_FAB2(SCH_1):PAGE52_I100@MSTR_SCONN.SCONN288_H44441003(CHIPS)':
 'DQS6N': CDS_PINID='DQS6N';
NET_NAME
'M_E_DQS_DN<7>'
 '@BASEBOARD_FAB2_LIB.BASEBOARD_FAB2(SCH_1):M_E_DQS_DN'<7>:
 C_SIGNAL='@baseboard_fab2_lib.baseboard_fab2(sch_1):m_e_dqs_dn(7)';
NODE_NAME     U5D1 DL26
 '@BASEBOARD_FAB2_LIB.BASEBOARD_FAB2(SCH_1):PAGE27_I172@CHPSET_LIB.SKX_EXT_B(CHIPS)':
 'DDR4_DQS_DN'<7>: CDS_PINID='DDR4_DQS_DN(7)';
NODE_NAME     J4A2 277
 '@BASEBOARD_FAB2_LIB.BASEBOARD_FAB2(SCH_1):PAGE51_I66@MSTR_SCONN.SCONN288_H44441004(CHIPS)':
 'DQS7N': CDS_PINID='DQS7N';
NODE_NAME     J6L2 277
 '@BASEBOARD_FAB2_LIB.BASEBOARD_FAB2(SCH_1):PAGE52_I100@MSTR_SCONN.SCONN288_H44441003(CHIPS)':
 'DQS7N': CDS_PINID='DQS7N';
NET_NAME
'M_E_DQS_DN<8>'
 '@BASEBOARD_FAB2_LIB.BASEBOARD_FAB2(SCH_1):M_E_DQS_DN'<8>:
 C_SIGNAL='@baseboard_fab2_lib.baseboard_fab2(sch_1):m_e_dqs_dn(8)';
NODE_NAME     U5D1 EB67
 '@BASEBOARD_FAB2_LIB.BASEBOARD_FAB2(SCH_1):PAGE27_I172@CHPSET_LIB.SKX_EXT_B(CHIPS)':
 'DDR4_DQS_DN'<8>: CDS_PINID='DDR4_DQS_DN(8)';
NODE_NAME     J4A2 196
 '@BASEBOARD_FAB2_LIB.BASEBOARD_FAB2(SCH_1):PAGE51_I66@MSTR_SCONN.SCONN288_H44441004(CHIPS)':
 'DQS8N': CDS_PINID='DQS8N';
NODE_NAME     J6L2 196
 '@BASEBOARD_FAB2_LIB.BASEBOARD_FAB2(SCH_1):PAGE52_I100@MSTR_SCONN.SCONN288_H44441003(CHIPS)':
 'DQS8N': CDS_PINID='DQS8N';
NET_NAME
'M_E_DQS_DN<9>'
 '@BASEBOARD_FAB2_LIB.BASEBOARD_FAB2(SCH_1):M_E_DQS_DN'<9>:
 C_SIGNAL='@baseboard_fab2_lib.baseboard_fab2(sch_1):m_e_dqs_dn(9)';
NODE_NAME     U5D1 CN80
 '@BASEBOARD_FAB2_LIB.BASEBOARD_FAB2(SCH_1):PAGE27_I172@CHPSET_LIB.SKX_EXT_B(CHIPS)':
 'DDR4_DQS_DN'<9>: CDS_PINID='DDR4_DQS_DN(9)';
NODE_NAME     J4A2 8
 '@BASEBOARD_FAB2_LIB.BASEBOARD_FAB2(SCH_1):PAGE51_I66@MSTR_SCONN.SCONN288_H44441004(CHIPS)':
 'DQS9N': CDS_PINID='DQS9N';
NODE_NAME     J6L2 8
 '@BASEBOARD_FAB2_LIB.BASEBOARD_FAB2(SCH_1):PAGE52_I100@MSTR_SCONN.SCONN288_H44441003(CHIPS)':
 'DQS9N': CDS_PINID='DQS9N';
NET_NAME
'M_E_DQS_DP<0>'
 '@BASEBOARD_FAB2_LIB.BASEBOARD_FAB2(SCH_1):M_E_DQS_DP'<0>:
 C_SIGNAL='@baseboard_fab2_lib.baseboard_fab2(sch_1):m_e_dqs_dp(0)';
NODE_NAME     U5D1 CM81
 '@BASEBOARD_FAB2_LIB.BASEBOARD_FAB2(SCH_1):PAGE27_I172@CHPSET_LIB.SKX_EXT_B(CHIPS)':
 'DDR4_DQS_DP'<0>: CDS_PINID='DDR4_DQS_DP(0)';
NODE_NAME     J4A2 153
 '@BASEBOARD_FAB2_LIB.BASEBOARD_FAB2(SCH_1):PAGE51_I66@MSTR_SCONN.SCONN288_H44441004(CHIPS)':
 'DQS0P': CDS_PINID='DQS0P';
NODE_NAME     J6L2 153
 '@BASEBOARD_FAB2_LIB.BASEBOARD_FAB2(SCH_1):PAGE52_I100@MSTR_SCONN.SCONN288_H44441003(CHIPS)':
 'DQS0P': CDS_PINID='DQS0P';
NET_NAME
'M_E_DQS_DP<10>'
 '@BASEBOARD_FAB2_LIB.BASEBOARD_FAB2(SCH_1):M_E_DQS_DP'<10>:
 C_SIGNAL='@baseboard_fab2_lib.baseboard_fab2(sch_1):m_e_dqs_dp(10)';
NODE_NAME     U5D1 DD79
 '@BASEBOARD_FAB2_LIB.BASEBOARD_FAB2(SCH_1):PAGE27_I172@CHPSET_LIB.SKX_EXT_B(CHIPS)':
 'DDR4_DQS_DP'<10>: CDS_PINID='DDR4_DQS_DP(10)';
NODE_NAME     J4A2 18
 '@BASEBOARD_FAB2_LIB.BASEBOARD_FAB2(SCH_1):PAGE51_I66@MSTR_SCONN.SCONN288_H44441004(CHIPS)':
 'DQS10P': CDS_PINID='DQS10P';
NODE_NAME     J6L2 18
 '@BASEBOARD_FAB2_LIB.BASEBOARD_FAB2(SCH_1):PAGE52_I100@MSTR_SCONN.SCONN288_H44441003(CHIPS)':
 'DQS10P': CDS_PINID='DQS10P';
NET_NAME
'M_E_DQS_DP<11>'
 '@BASEBOARD_FAB2_LIB.BASEBOARD_FAB2(SCH_1):M_E_DQS_DP'<11>:
 C_SIGNAL='@baseboard_fab2_lib.baseboard_fab2(sch_1):m_e_dqs_dp(11)';
NODE_NAME     U5D1 DV79
 '@BASEBOARD_FAB2_LIB.BASEBOARD_FAB2(SCH_1):PAGE27_I172@CHPSET_LIB.SKX_EXT_B(CHIPS)':
 'DDR4_DQS_DP'<11>: CDS_PINID='DDR4_DQS_DP(11)';
NODE_NAME     J4A2 29
 '@BASEBOARD_FAB2_LIB.BASEBOARD_FAB2(SCH_1):PAGE51_I66@MSTR_SCONN.SCONN288_H44441004(CHIPS)':
 'DQS11P': CDS_PINID='DQS11P';
NODE_NAME     J6L2 29
 '@BASEBOARD_FAB2_LIB.BASEBOARD_FAB2(SCH_1):PAGE52_I100@MSTR_SCONN.SCONN288_H44441003(CHIPS)':
 'DQS11P': CDS_PINID='DQS11P';
NET_NAME
'M_E_DQS_DP<12>'
 '@BASEBOARD_FAB2_LIB.BASEBOARD_FAB2(SCH_1):M_E_DQS_DP'<12>:
 C_SIGNAL='@baseboard_fab2_lib.baseboard_fab2(sch_1):m_e_dqs_dp(12)';
NODE_NAME     U5D1 DY73
 '@BASEBOARD_FAB2_LIB.BASEBOARD_FAB2(SCH_1):PAGE27_I172@CHPSET_LIB.SKX_EXT_B(CHIPS)':
 'DDR4_DQS_DP'<12>: CDS_PINID='DDR4_DQS_DP(12)';
NODE_NAME     J4A2 40
 '@BASEBOARD_FAB2_LIB.BASEBOARD_FAB2(SCH_1):PAGE51_I66@MSTR_SCONN.SCONN288_H44441004(CHIPS)':
 'DQS12P': CDS_PINID='DQS12P';
NODE_NAME     J6L2 40
 '@BASEBOARD_FAB2_LIB.BASEBOARD_FAB2(SCH_1):PAGE52_I100@MSTR_SCONN.SCONN288_H44441003(CHIPS)':
 'DQS12P': CDS_PINID='DQS12P';
NET_NAME
'M_E_DQS_DP<13>'
 '@BASEBOARD_FAB2_LIB.BASEBOARD_FAB2(SCH_1):M_E_DQS_DP'<13>:
 C_SIGNAL='@baseboard_fab2_lib.baseboard_fab2(sch_1):m_e_dqs_dp(13)';
NODE_NAME     U5D1 DM41
 '@BASEBOARD_FAB2_LIB.BASEBOARD_FAB2(SCH_1):PAGE27_I172@CHPSET_LIB.SKX_EXT_B(CHIPS)':
 'DDR4_DQS_DP'<13>: CDS_PINID='DDR4_DQS_DP(13)';
NODE_NAME     J4A2 99
 '@BASEBOARD_FAB2_LIB.BASEBOARD_FAB2(SCH_1):PAGE51_I66@MSTR_SCONN.SCONN288_H44441004(CHIPS)':
 'DQS13P': CDS_PINID='DQS13P';
NODE_NAME     J6L2 99
 '@BASEBOARD_FAB2_LIB.BASEBOARD_FAB2(SCH_1):PAGE52_I100@MSTR_SCONN.SCONN288_H44441003(CHIPS)':
 'DQS13P': CDS_PINID='DQS13P';
NET_NAME
'M_E_DQS_DP<14>'
 '@BASEBOARD_FAB2_LIB.BASEBOARD_FAB2(SCH_1):M_E_DQS_DP'<14>:
 C_SIGNAL='@baseboard_fab2_lib.baseboard_fab2(sch_1):m_e_dqs_dp(14)';
NODE_NAME     U5D1 DW32
 '@BASEBOARD_FAB2_LIB.BASEBOARD_FAB2(SCH_1):PAGE27_I172@CHPSET_LIB.SKX_EXT_B(CHIPS)':
 'DDR4_DQS_DP'<14>: CDS_PINID='DDR4_DQS_DP(14)';
NODE_NAME     J4A2 110
 '@BASEBOARD_FAB2_LIB.BASEBOARD_FAB2(SCH_1):PAGE51_I66@MSTR_SCONN.SCONN288_H44441004(CHIPS)':
 'DQS14P': CDS_PINID='DQS14P';
NODE_NAME     J6L2 110
 '@BASEBOARD_FAB2_LIB.BASEBOARD_FAB2(SCH_1):PAGE52_I100@MSTR_SCONN.SCONN288_H44441003(CHIPS)':
 'DQS14P': CDS_PINID='DQS14P';
NET_NAME
'M_E_DQS_DP<15>'
 '@BASEBOARD_FAB2_LIB.BASEBOARD_FAB2(SCH_1):M_E_DQS_DP'<15>:
 C_SIGNAL='@baseboard_fab2_lib.baseboard_fab2(sch_1):m_e_dqs_dp(15)';
NODE_NAME     U5D1 DW26
 '@BASEBOARD_FAB2_LIB.BASEBOARD_FAB2(SCH_1):PAGE27_I172@CHPSET_LIB.SKX_EXT_B(CHIPS)':
 'DDR4_DQS_DP'<15>: CDS_PINID='DDR4_DQS_DP(15)';
NODE_NAME     J4A2 121
 '@BASEBOARD_FAB2_LIB.BASEBOARD_FAB2(SCH_1):PAGE51_I66@MSTR_SCONN.SCONN288_H44441004(CHIPS)':
 'DQS15P': CDS_PINID='DQS15P';
NODE_NAME     J6L2 121
 '@BASEBOARD_FAB2_LIB.BASEBOARD_FAB2(SCH_1):PAGE52_I100@MSTR_SCONN.SCONN288_H44441003(CHIPS)':
 'DQS15P': CDS_PINID='DQS15P';
NET_NAME
'M_E_DQS_DP<16>'
 '@BASEBOARD_FAB2_LIB.BASEBOARD_FAB2(SCH_1):M_E_DQS_DP'<16>:
 C_SIGNAL='@baseboard_fab2_lib.baseboard_fab2(sch_1):m_e_dqs_dp(16)';
NODE_NAME     U5D1 DE26
 '@BASEBOARD_FAB2_LIB.BASEBOARD_FAB2(SCH_1):PAGE27_I172@CHPSET_LIB.SKX_EXT_B(CHIPS)':
 'DDR4_DQS_DP'<16>: CDS_PINID='DDR4_DQS_DP(16)';
NODE_NAME     J4A2 132
 '@BASEBOARD_FAB2_LIB.BASEBOARD_FAB2(SCH_1):PAGE51_I66@MSTR_SCONN.SCONN288_H44441004(CHIPS)':
 'DQS16P': CDS_PINID='DQS16P';
NODE_NAME     J6L2 132
 '@BASEBOARD_FAB2_LIB.BASEBOARD_FAB2(SCH_1):PAGE52_I100@MSTR_SCONN.SCONN288_H44441003(CHIPS)':
 'DQS16P': CDS_PINID='DQS16P';
NET_NAME
'M_E_DQS_DP<17>'
 '@BASEBOARD_FAB2_LIB.BASEBOARD_FAB2(SCH_1):M_E_DQS_DP'<17>:
 C_SIGNAL='@baseboard_fab2_lib.baseboard_fab2(sch_1):m_e_dqs_dp(17)';
NODE_NAME     U5D1 DT67
 '@BASEBOARD_FAB2_LIB.BASEBOARD_FAB2(SCH_1):PAGE27_I172@CHPSET_LIB.SKX_EXT_B(CHIPS)':
 'DDR4_DQS_DP'<17>: CDS_PINID='DDR4_DQS_DP(17)';
NODE_NAME     J4A2 51
 '@BASEBOARD_FAB2_LIB.BASEBOARD_FAB2(SCH_1):PAGE51_I66@MSTR_SCONN.SCONN288_H44441004(CHIPS)':
 'DQS17P': CDS_PINID='DQS17P';
NODE_NAME     J6L2 51
 '@BASEBOARD_FAB2_LIB.BASEBOARD_FAB2(SCH_1):PAGE52_I100@MSTR_SCONN.SCONN288_H44441003(CHIPS)':
 'DQS17P': CDS_PINID='DQS17P';
NET_NAME
'M_E_DQS_DP<1>'
 '@BASEBOARD_FAB2_LIB.BASEBOARD_FAB2(SCH_1):M_E_DQS_DP'<1>:
 C_SIGNAL='@baseboard_fab2_lib.baseboard_fab2(sch_1):m_e_dqs_dp(1)';
NODE_NAME     U5D1 DB81
 '@BASEBOARD_FAB2_LIB.BASEBOARD_FAB2(SCH_1):PAGE27_I172@CHPSET_LIB.SKX_EXT_B(CHIPS)':
 'DDR4_DQS_DP'<1>: CDS_PINID='DDR4_DQS_DP(1)';
NODE_NAME     J4A2 164
 '@BASEBOARD_FAB2_LIB.BASEBOARD_FAB2(SCH_1):PAGE51_I66@MSTR_SCONN.SCONN288_H44441004(CHIPS)':
 'DQS1P': CDS_PINID='DQS1P';
NODE_NAME     J6L2 164
 '@BASEBOARD_FAB2_LIB.BASEBOARD_FAB2(SCH_1):PAGE52_I100@MSTR_SCONN.SCONN288_H44441003(CHIPS)':
 'DQS1P': CDS_PINID='DQS1P';
NET_NAME
'M_E_DQS_DP<2>'
 '@BASEBOARD_FAB2_LIB.BASEBOARD_FAB2(SCH_1):M_E_DQS_DP'<2>:
 C_SIGNAL='@baseboard_fab2_lib.baseboard_fab2(sch_1):m_e_dqs_dp(2)';
NODE_NAME     U5D1 EB79
 '@BASEBOARD_FAB2_LIB.BASEBOARD_FAB2(SCH_1):PAGE27_I172@CHPSET_LIB.SKX_EXT_B(CHIPS)':
 'DDR4_DQS_DP'<2>: CDS_PINID='DDR4_DQS_DP(2)';
NODE_NAME     J4A2 175
 '@BASEBOARD_FAB2_LIB.BASEBOARD_FAB2(SCH_1):PAGE51_I66@MSTR_SCONN.SCONN288_H44441004(CHIPS)':
 'DQS2P': CDS_PINID='DQS2P';
NODE_NAME     J6L2 175
 '@BASEBOARD_FAB2_LIB.BASEBOARD_FAB2(SCH_1):PAGE52_I100@MSTR_SCONN.SCONN288_H44441003(CHIPS)':
 'DQS2P': CDS_PINID='DQS2P';
NET_NAME
'M_E_DQS_DP<3>'
 '@BASEBOARD_FAB2_LIB.BASEBOARD_FAB2(SCH_1):M_E_DQS_DP'<3>:
 C_SIGNAL='@baseboard_fab2_lib.baseboard_fab2(sch_1):m_e_dqs_dp(3)';
NODE_NAME     U5D1 ED73
 '@BASEBOARD_FAB2_LIB.BASEBOARD_FAB2(SCH_1):PAGE27_I172@CHPSET_LIB.SKX_EXT_B(CHIPS)':
 'DDR4_DQS_DP'<3>: CDS_PINID='DDR4_DQS_DP(3)';
NODE_NAME     J4A2 186
 '@BASEBOARD_FAB2_LIB.BASEBOARD_FAB2(SCH_1):PAGE51_I66@MSTR_SCONN.SCONN288_H44441004(CHIPS)':
 'DQS3P': CDS_PINID='DQS3P';
NODE_NAME     J6L2 186
 '@BASEBOARD_FAB2_LIB.BASEBOARD_FAB2(SCH_1):PAGE52_I100@MSTR_SCONN.SCONN288_H44441003(CHIPS)':
 'DQS3P': CDS_PINID='DQS3P';
NET_NAME
'M_E_DQS_DP<4>'
 '@BASEBOARD_FAB2_LIB.BASEBOARD_FAB2(SCH_1):M_E_DQS_DP'<4>:
 C_SIGNAL='@baseboard_fab2_lib.baseboard_fab2(sch_1):m_e_dqs_dp(4)';
NODE_NAME     U5D1 DT41
 '@BASEBOARD_FAB2_LIB.BASEBOARD_FAB2(SCH_1):PAGE27_I172@CHPSET_LIB.SKX_EXT_B(CHIPS)':
 'DDR4_DQS_DP'<4>: CDS_PINID='DDR4_DQS_DP(4)';
NODE_NAME     J4A2 245
 '@BASEBOARD_FAB2_LIB.BASEBOARD_FAB2(SCH_1):PAGE51_I66@MSTR_SCONN.SCONN288_H44441004(CHIPS)':
 'DQS4P': CDS_PINID='DQS4P';
NODE_NAME     J6L2 245
 '@BASEBOARD_FAB2_LIB.BASEBOARD_FAB2(SCH_1):PAGE52_I100@MSTR_SCONN.SCONN288_H44441003(CHIPS)':
 'DQS4P': CDS_PINID='DQS4P';
NET_NAME
'M_E_DQS_DP<5>'
 '@BASEBOARD_FAB2_LIB.BASEBOARD_FAB2(SCH_1):M_E_DQS_DP'<5>:
 C_SIGNAL='@baseboard_fab2_lib.baseboard_fab2(sch_1):m_e_dqs_dp(5)';
NODE_NAME     U5D1 EC32
 '@BASEBOARD_FAB2_LIB.BASEBOARD_FAB2(SCH_1):PAGE27_I172@CHPSET_LIB.SKX_EXT_B(CHIPS)':
 'DDR4_DQS_DP'<5>: CDS_PINID='DDR4_DQS_DP(5)';
NODE_NAME     J4A2 256
 '@BASEBOARD_FAB2_LIB.BASEBOARD_FAB2(SCH_1):PAGE51_I66@MSTR_SCONN.SCONN288_H44441004(CHIPS)':
 'DQS5P': CDS_PINID='DQS5P';
NODE_NAME     J6L2 256
 '@BASEBOARD_FAB2_LIB.BASEBOARD_FAB2(SCH_1):PAGE52_I100@MSTR_SCONN.SCONN288_H44441003(CHIPS)':
 'DQS5P': CDS_PINID='DQS5P';
NET_NAME
'M_E_DQS_DP<6>'
 '@BASEBOARD_FAB2_LIB.BASEBOARD_FAB2(SCH_1):M_E_DQS_DP'<6>:
 C_SIGNAL='@baseboard_fab2_lib.baseboard_fab2(sch_1):m_e_dqs_dp(6)';
NODE_NAME     U5D1 EC26
 '@BASEBOARD_FAB2_LIB.BASEBOARD_FAB2(SCH_1):PAGE27_I172@CHPSET_LIB.SKX_EXT_B(CHIPS)':
 'DDR4_DQS_DP'<6>: CDS_PINID='DDR4_DQS_DP(6)';
NODE_NAME     J4A2 267
 '@BASEBOARD_FAB2_LIB.BASEBOARD_FAB2(SCH_1):PAGE51_I66@MSTR_SCONN.SCONN288_H44441004(CHIPS)':
 'DQS6P': CDS_PINID='DQS6P';
NODE_NAME     J6L2 267
 '@BASEBOARD_FAB2_LIB.BASEBOARD_FAB2(SCH_1):PAGE52_I100@MSTR_SCONN.SCONN288_H44441003(CHIPS)':
 'DQS6P': CDS_PINID='DQS6P';
NET_NAME
'M_E_DQS_DP<7>'
 '@BASEBOARD_FAB2_LIB.BASEBOARD_FAB2(SCH_1):M_E_DQS_DP'<7>:
 C_SIGNAL='@baseboard_fab2_lib.baseboard_fab2(sch_1):m_e_dqs_dp(7)';
NODE_NAME     U5D1 DJ26
 '@BASEBOARD_FAB2_LIB.BASEBOARD_FAB2(SCH_1):PAGE27_I172@CHPSET_LIB.SKX_EXT_B(CHIPS)':
 'DDR4_DQS_DP'<7>: CDS_PINID='DDR4_DQS_DP(7)';
NODE_NAME     J4A2 278
 '@BASEBOARD_FAB2_LIB.BASEBOARD_FAB2(SCH_1):PAGE51_I66@MSTR_SCONN.SCONN288_H44441004(CHIPS)':
 'DQS7P': CDS_PINID='DQS7P';
NODE_NAME     J6L2 278
 '@BASEBOARD_FAB2_LIB.BASEBOARD_FAB2(SCH_1):PAGE52_I100@MSTR_SCONN.SCONN288_H44441003(CHIPS)':
 'DQS7P': CDS_PINID='DQS7P';
NET_NAME
'M_E_DQS_DP<8>'
 '@BASEBOARD_FAB2_LIB.BASEBOARD_FAB2(SCH_1):M_E_DQS_DP'<8>:
 C_SIGNAL='@baseboard_fab2_lib.baseboard_fab2(sch_1):m_e_dqs_dp(8)';
NODE_NAME     U5D1 DY67
 '@BASEBOARD_FAB2_LIB.BASEBOARD_FAB2(SCH_1):PAGE27_I172@CHPSET_LIB.SKX_EXT_B(CHIPS)':
 'DDR4_DQS_DP'<8>: CDS_PINID='DDR4_DQS_DP(8)';
NODE_NAME     J4A2 197
 '@BASEBOARD_FAB2_LIB.BASEBOARD_FAB2(SCH_1):PAGE51_I66@MSTR_SCONN.SCONN288_H44441004(CHIPS)':
 'DQS8P': CDS_PINID='DQS8P';
NODE_NAME     J6L2 197
 '@BASEBOARD_FAB2_LIB.BASEBOARD_FAB2(SCH_1):PAGE52_I100@MSTR_SCONN.SCONN288_H44441003(CHIPS)':
 'DQS8P': CDS_PINID='DQS8P';
NET_NAME
'M_E_DQS_DP<9>'
 '@BASEBOARD_FAB2_LIB.BASEBOARD_FAB2(SCH_1):M_E_DQS_DP'<9>:
 C_SIGNAL='@baseboard_fab2_lib.baseboard_fab2(sch_1):m_e_dqs_dp(9)';
NODE_NAME     U5D1 CP79
 '@BASEBOARD_FAB2_LIB.BASEBOARD_FAB2(SCH_1):PAGE27_I172@CHPSET_LIB.SKX_EXT_B(CHIPS)':
 'DDR4_DQS_DP'<9>: CDS_PINID='DDR4_DQS_DP(9)';
NODE_NAME     J4A2 7
 '@BASEBOARD_FAB2_LIB.BASEBOARD_FAB2(SCH_1):PAGE51_I66@MSTR_SCONN.SCONN288_H44441004(CHIPS)':
 'DQS9P': CDS_PINID='DQS9P';
NODE_NAME     J6L2 7
 '@BASEBOARD_FAB2_LIB.BASEBOARD_FAB2(SCH_1):PAGE52_I100@MSTR_SCONN.SCONN288_H44441003(CHIPS)':
 'DQS9P': CDS_PINID='DQS9P';
NET_NAME
'M_E_ECC<0>'
 '@BASEBOARD_FAB2_LIB.BASEBOARD_FAB2(SCH_1):M_E_ECC'<0>:
 C_SIGNAL='@baseboard_fab2_lib.baseboard_fab2(sch_1):m_e_ecc(0)';
NODE_NAME     U5D1 DY69
 '@BASEBOARD_FAB2_LIB.BASEBOARD_FAB2(SCH_1):PAGE27_I172@CHPSET_LIB.SKX_EXT_B(CHIPS)':
 'DDR4_ECC'<0>: CDS_PINID='DDR4_ECC(0)';
NODE_NAME     J4A2 194
 '@BASEBOARD_FAB2_LIB.BASEBOARD_FAB2(SCH_1):PAGE51_I111@MSTR_SCONN.SCONN288_H44441004(CHIPS)':
 'CB'<1>: CDS_PINID='CB(1)';
NODE_NAME     J6L2 49
 '@BASEBOARD_FAB2_LIB.BASEBOARD_FAB2(SCH_1):PAGE52_I12@MSTR_SCONN.SCONN288_H44441003(CHIPS)':
 'CB'<0>: CDS_PINID='CB(0)';
NET_NAME
'M_E_ECC<1>'
 '@BASEBOARD_FAB2_LIB.BASEBOARD_FAB2(SCH_1):M_E_ECC'<1>:
 C_SIGNAL='@baseboard_fab2_lib.baseboard_fab2(sch_1):m_e_ecc(1)';
NODE_NAME     U5D1 EA68
 '@BASEBOARD_FAB2_LIB.BASEBOARD_FAB2(SCH_1):PAGE27_I172@CHPSET_LIB.SKX_EXT_B(CHIPS)':
 'DDR4_ECC'<1>: CDS_PINID='DDR4_ECC(1)';
NODE_NAME     J4A2 49
 '@BASEBOARD_FAB2_LIB.BASEBOARD_FAB2(SCH_1):PAGE51_I111@MSTR_SCONN.SCONN288_H44441004(CHIPS)':
 'CB'<0>: CDS_PINID='CB(0)';
NODE_NAME     J6L2 194
 '@BASEBOARD_FAB2_LIB.BASEBOARD_FAB2(SCH_1):PAGE52_I12@MSTR_SCONN.SCONN288_H44441003(CHIPS)':
 'CB'<1>: CDS_PINID='CB(1)';
NET_NAME
'M_E_ECC<2>'
 '@BASEBOARD_FAB2_LIB.BASEBOARD_FAB2(SCH_1):M_E_ECC'<2>:
 C_SIGNAL='@baseboard_fab2_lib.baseboard_fab2(sch_1):m_e_ecc(2)';
NODE_NAME     U5D1 DV65
 '@BASEBOARD_FAB2_LIB.BASEBOARD_FAB2(SCH_1):PAGE27_I172@CHPSET_LIB.SKX_EXT_B(CHIPS)':
 'DDR4_ECC'<2>: CDS_PINID='DDR4_ECC(2)';
NODE_NAME     J4A2 201
 '@BASEBOARD_FAB2_LIB.BASEBOARD_FAB2(SCH_1):PAGE51_I111@MSTR_SCONN.SCONN288_H44441004(CHIPS)':
 'CB'<3>: CDS_PINID='CB(3)';
NODE_NAME     J6L2 56
 '@BASEBOARD_FAB2_LIB.BASEBOARD_FAB2(SCH_1):PAGE52_I12@MSTR_SCONN.SCONN288_H44441003(CHIPS)':
 'CB'<2>: CDS_PINID='CB(2)';
NET_NAME
'M_E_ECC<3>'
 '@BASEBOARD_FAB2_LIB.BASEBOARD_FAB2(SCH_1):M_E_ECC'<3>:
 C_SIGNAL='@baseboard_fab2_lib.baseboard_fab2(sch_1):m_e_ecc(3)';
NODE_NAME     U5D1 DY65
 '@BASEBOARD_FAB2_LIB.BASEBOARD_FAB2(SCH_1):PAGE27_I172@CHPSET_LIB.SKX_EXT_B(CHIPS)':
 'DDR4_ECC'<3>: CDS_PINID='DDR4_ECC(3)';
NODE_NAME     J4A2 56
 '@BASEBOARD_FAB2_LIB.BASEBOARD_FAB2(SCH_1):PAGE51_I111@MSTR_SCONN.SCONN288_H44441004(CHIPS)':
 'CB'<2>: CDS_PINID='CB(2)';
NODE_NAME     J6L2 201
 '@BASEBOARD_FAB2_LIB.BASEBOARD_FAB2(SCH_1):PAGE52_I12@MSTR_SCONN.SCONN288_H44441003(CHIPS)':
 'CB'<3>: CDS_PINID='CB(3)';
NET_NAME
'M_E_ECC<4>'
 '@BASEBOARD_FAB2_LIB.BASEBOARD_FAB2(SCH_1):M_E_ECC'<4>:
 C_SIGNAL='@baseboard_fab2_lib.baseboard_fab2(sch_1):m_e_ecc(4)';
NODE_NAME     U5D1 DU68
 '@BASEBOARD_FAB2_LIB.BASEBOARD_FAB2(SCH_1):PAGE27_I172@CHPSET_LIB.SKX_EXT_B(CHIPS)':
 'DDR4_ECC'<4>: CDS_PINID='DDR4_ECC(4)';
NODE_NAME     J4A2 192
 '@BASEBOARD_FAB2_LIB.BASEBOARD_FAB2(SCH_1):PAGE51_I111@MSTR_SCONN.SCONN288_H44441004(CHIPS)':
 'CB'<5>: CDS_PINID='CB(5)';
NODE_NAME     J6L2 47
 '@BASEBOARD_FAB2_LIB.BASEBOARD_FAB2(SCH_1):PAGE52_I12@MSTR_SCONN.SCONN288_H44441003(CHIPS)':
 'CB'<4>: CDS_PINID='CB(4)';
NET_NAME
'M_E_ECC<5>'
 '@BASEBOARD_FAB2_LIB.BASEBOARD_FAB2(SCH_1):M_E_ECC'<5>:
 C_SIGNAL='@baseboard_fab2_lib.baseboard_fab2(sch_1):m_e_ecc(5)';
NODE_NAME     U5D1 DV69
 '@BASEBOARD_FAB2_LIB.BASEBOARD_FAB2(SCH_1):PAGE27_I172@CHPSET_LIB.SKX_EXT_B(CHIPS)':
 'DDR4_ECC'<5>: CDS_PINID='DDR4_ECC(5)';
NODE_NAME     J4A2 47
 '@BASEBOARD_FAB2_LIB.BASEBOARD_FAB2(SCH_1):PAGE51_I111@MSTR_SCONN.SCONN288_H44441004(CHIPS)':
 'CB'<4>: CDS_PINID='CB(4)';
NODE_NAME     J6L2 192
 '@BASEBOARD_FAB2_LIB.BASEBOARD_FAB2(SCH_1):PAGE52_I12@MSTR_SCONN.SCONN288_H44441003(CHIPS)':
 'CB'<5>: CDS_PINID='CB(5)';
NET_NAME
'M_E_ECC<6>'
 '@BASEBOARD_FAB2_LIB.BASEBOARD_FAB2(SCH_1):M_E_ECC'<6>:
 C_SIGNAL='@baseboard_fab2_lib.baseboard_fab2(sch_1):m_e_ecc(6)';
NODE_NAME     U5D1 DU66
 '@BASEBOARD_FAB2_LIB.BASEBOARD_FAB2(SCH_1):PAGE27_I172@CHPSET_LIB.SKX_EXT_B(CHIPS)':
 'DDR4_ECC'<6>: CDS_PINID='DDR4_ECC(6)';
NODE_NAME     J4A2 199
 '@BASEBOARD_FAB2_LIB.BASEBOARD_FAB2(SCH_1):PAGE51_I111@MSTR_SCONN.SCONN288_H44441004(CHIPS)':
 'CB'<7>: CDS_PINID='CB(7)';
NODE_NAME     J6L2 54
 '@BASEBOARD_FAB2_LIB.BASEBOARD_FAB2(SCH_1):PAGE52_I12@MSTR_SCONN.SCONN288_H44441003(CHIPS)':
 'CB'<6>: CDS_PINID='CB(6)';
NET_NAME
'M_E_ECC<7>'
 '@BASEBOARD_FAB2_LIB.BASEBOARD_FAB2(SCH_1):M_E_ECC'<7>:
 C_SIGNAL='@baseboard_fab2_lib.baseboard_fab2(sch_1):m_e_ecc(7)';
NODE_NAME     U5D1 EA66
 '@BASEBOARD_FAB2_LIB.BASEBOARD_FAB2(SCH_1):PAGE27_I172@CHPSET_LIB.SKX_EXT_B(CHIPS)':
 'DDR4_ECC'<7>: CDS_PINID='DDR4_ECC(7)';
NODE_NAME     J4A2 54
 '@BASEBOARD_FAB2_LIB.BASEBOARD_FAB2(SCH_1):PAGE51_I111@MSTR_SCONN.SCONN288_H44441004(CHIPS)':
 'CB'<6>: CDS_PINID='CB(6)';
NODE_NAME     J6L2 199
 '@BASEBOARD_FAB2_LIB.BASEBOARD_FAB2(SCH_1):PAGE52_I12@MSTR_SCONN.SCONN288_H44441003(CHIPS)':
 'CB'<7>: CDS_PINID='CB(7)';
NET_NAME
'M_E_MA<0>'
 '@BASEBOARD_FAB2_LIB.BASEBOARD_FAB2(SCH_1):M_E_MA'<0>:
 C_SIGNAL='@baseboard_fab2_lib.baseboard_fab2(sch_1):m_e_ma(0)';
NODE_NAME     U5D1 DW52
 '@BASEBOARD_FAB2_LIB.BASEBOARD_FAB2(SCH_1):PAGE27_I172@CHPSET_LIB.SKX_EXT_B(CHIPS)':
 'DDR4_MA'<0>: CDS_PINID='DDR4_MA(0)';
NODE_NAME     J4A2 79
 '@BASEBOARD_FAB2_LIB.BASEBOARD_FAB2(SCH_1):PAGE51_I111@MSTR_SCONN.SCONN288_H44441004(CHIPS)':
 'A0': CDS_PINID='A0';
NODE_NAME     J6L2 79
 '@BASEBOARD_FAB2_LIB.BASEBOARD_FAB2(SCH_1):PAGE52_I12@MSTR_SCONN.SCONN288_H44441003(CHIPS)':
 'A0': CDS_PINID='A0';
NET_NAME
'M_E_MA<10>'
 '@BASEBOARD_FAB2_LIB.BASEBOARD_FAB2(SCH_1):M_E_MA'<10>:
 C_SIGNAL='@baseboard_fab2_lib.baseboard_fab2(sch_1):m_e_ma(10)';
NODE_NAME     U5D1 DT55
 '@BASEBOARD_FAB2_LIB.BASEBOARD_FAB2(SCH_1):PAGE27_I172@CHPSET_LIB.SKX_EXT_B(CHIPS)':
 'DDR4_MA'<10>: CDS_PINID='DDR4_MA(10)';
NODE_NAME     J4A2 225
 '@BASEBOARD_FAB2_LIB.BASEBOARD_FAB2(SCH_1):PAGE51_I111@MSTR_SCONN.SCONN288_H44441004(CHIPS)':
 'A10': CDS_PINID='A10';
NODE_NAME     J6L2 225
 '@BASEBOARD_FAB2_LIB.BASEBOARD_FAB2(SCH_1):PAGE52_I12@MSTR_SCONN.SCONN288_H44441003(CHIPS)':
 'A10': CDS_PINID='A10';
NET_NAME
'M_E_MA<11>'
 '@BASEBOARD_FAB2_LIB.BASEBOARD_FAB2(SCH_1):M_E_MA'<11>:
 C_SIGNAL='@baseboard_fab2_lib.baseboard_fab2(sch_1):m_e_ma(11)';
NODE_NAME     U5D1 DR60
 '@BASEBOARD_FAB2_LIB.BASEBOARD_FAB2(SCH_1):PAGE27_I172@CHPSET_LIB.SKX_EXT_B(CHIPS)':
 'DDR4_MA'<11>: CDS_PINID='DDR4_MA(11)';
NODE_NAME     J4A2 210
 '@BASEBOARD_FAB2_LIB.BASEBOARD_FAB2(SCH_1):PAGE51_I111@MSTR_SCONN.SCONN288_H44441004(CHIPS)':
 'A11': CDS_PINID='A11';
NODE_NAME     J6L2 210
 '@BASEBOARD_FAB2_LIB.BASEBOARD_FAB2(SCH_1):PAGE52_I12@MSTR_SCONN.SCONN288_H44441003(CHIPS)':
 'A11': CDS_PINID='A11';
NET_NAME
'M_E_MA<12>'
 '@BASEBOARD_FAB2_LIB.BASEBOARD_FAB2(SCH_1):M_E_MA'<12>:
 C_SIGNAL='@baseboard_fab2_lib.baseboard_fab2(sch_1):m_e_ma(12)';
NODE_NAME     U5D1 DN60
 '@BASEBOARD_FAB2_LIB.BASEBOARD_FAB2(SCH_1):PAGE27_I172@CHPSET_LIB.SKX_EXT_B(CHIPS)':
 'DDR4_MA'<12>: CDS_PINID='DDR4_MA(12)';
NODE_NAME     J4A2 65
 '@BASEBOARD_FAB2_LIB.BASEBOARD_FAB2(SCH_1):PAGE51_I111@MSTR_SCONN.SCONN288_H44441004(CHIPS)':
 'A12': CDS_PINID='A12';
NODE_NAME     J6L2 65
 '@BASEBOARD_FAB2_LIB.BASEBOARD_FAB2(SCH_1):PAGE52_I12@MSTR_SCONN.SCONN288_H44441003(CHIPS)':
 'A12': CDS_PINID='A12';
NET_NAME
'M_E_MA<13>'
 '@BASEBOARD_FAB2_LIB.BASEBOARD_FAB2(SCH_1):M_E_MA'<13>:
 C_SIGNAL='@baseboard_fab2_lib.baseboard_fab2(sch_1):m_e_ma(13)';
NODE_NAME     U5D1 DT51
 '@BASEBOARD_FAB2_LIB.BASEBOARD_FAB2(SCH_1):PAGE27_I172@CHPSET_LIB.SKX_EXT_B(CHIPS)':
 'DDR4_MA'<13>: CDS_PINID='DDR4_MA(13)';
NODE_NAME     J4A2 232
 '@BASEBOARD_FAB2_LIB.BASEBOARD_FAB2(SCH_1):PAGE51_I111@MSTR_SCONN.SCONN288_H44441004(CHIPS)':
 'A13': CDS_PINID='A13';
NODE_NAME     J6L2 232
 '@BASEBOARD_FAB2_LIB.BASEBOARD_FAB2(SCH_1):PAGE52_I12@MSTR_SCONN.SCONN288_H44441003(CHIPS)':
 'A13': CDS_PINID='A13';
NET_NAME
'M_E_MA<14>'
 '@BASEBOARD_FAB2_LIB.BASEBOARD_FAB2(SCH_1):M_E_MA'<14>:
 C_SIGNAL='@baseboard_fab2_lib.baseboard_fab2(sch_1):m_e_ma(14)';
NODE_NAME     U5D1 DM51
 '@BASEBOARD_FAB2_LIB.BASEBOARD_FAB2(SCH_1):PAGE27_I172@CHPSET_LIB.SKX_EXT_B(CHIPS)':
 'DDR4_MA'<14>: CDS_PINID='DDR4_MA(14)';
NODE_NAME     J4A2 228
 '@BASEBOARD_FAB2_LIB.BASEBOARD_FAB2(SCH_1):PAGE51_I111@MSTR_SCONN.SCONN288_H44441004(CHIPS)':
 'A14_WE_N': CDS_PINID='A14_WE_N';
NODE_NAME     J6L2 228
 '@BASEBOARD_FAB2_LIB.BASEBOARD_FAB2(SCH_1):PAGE52_I12@MSTR_SCONN.SCONN288_H44441003(CHIPS)':
 'A14_WE_N': CDS_PINID='A14_WE_N';
NET_NAME
'M_E_MA<15>'
 '@BASEBOARD_FAB2_LIB.BASEBOARD_FAB2(SCH_1):M_E_MA'<15>:
 C_SIGNAL='@baseboard_fab2_lib.baseboard_fab2(sch_1):m_e_ma(15)';
NODE_NAME     U5D1 DR52
 '@BASEBOARD_FAB2_LIB.BASEBOARD_FAB2(SCH_1):PAGE27_I172@CHPSET_LIB.SKX_EXT_B(CHIPS)':
 'DDR4_MA'<15>: CDS_PINID='DDR4_MA(15)';
NODE_NAME     J4A2 86
 '@BASEBOARD_FAB2_LIB.BASEBOARD_FAB2(SCH_1):PAGE51_I111@MSTR_SCONN.SCONN288_H44441004(CHIPS)':
 'A15_CAS_N': CDS_PINID='A15_CAS_N';
NODE_NAME     J6L2 86
 '@BASEBOARD_FAB2_LIB.BASEBOARD_FAB2(SCH_1):PAGE52_I12@MSTR_SCONN.SCONN288_H44441003(CHIPS)':
 'A15_CAS_N': CDS_PINID='A15_CAS_N';
NET_NAME
'M_E_MA<16>'
 '@BASEBOARD_FAB2_LIB.BASEBOARD_FAB2(SCH_1):M_E_MA'<16>:
 C_SIGNAL='@baseboard_fab2_lib.baseboard_fab2(sch_1):m_e_ma(16)';
NODE_NAME     U5D1 DN52
 '@BASEBOARD_FAB2_LIB.BASEBOARD_FAB2(SCH_1):PAGE27_I172@CHPSET_LIB.SKX_EXT_B(CHIPS)':
 'DDR4_MA'<16>: CDS_PINID='DDR4_MA(16)';
NODE_NAME     J4A2 82
 '@BASEBOARD_FAB2_LIB.BASEBOARD_FAB2(SCH_1):PAGE51_I111@MSTR_SCONN.SCONN288_H44441004(CHIPS)':
 'A16_RAS_N': CDS_PINID='A16_RAS_N';
NODE_NAME     J6L2 82
 '@BASEBOARD_FAB2_LIB.BASEBOARD_FAB2(SCH_1):PAGE52_I12@MSTR_SCONN.SCONN288_H44441003(CHIPS)':
 'A16_RAS_N': CDS_PINID='A16_RAS_N';
NET_NAME
'M_E_MA<17>'
 '@BASEBOARD_FAB2_LIB.BASEBOARD_FAB2(SCH_1):M_E_MA'<17>:
 C_SIGNAL='@baseboard_fab2_lib.baseboard_fab2(sch_1):m_e_ma(17)';
NODE_NAME     U5D1 DR48
 '@BASEBOARD_FAB2_LIB.BASEBOARD_FAB2(SCH_1):PAGE27_I172@CHPSET_LIB.SKX_EXT_B(CHIPS)':
 'DDR4_MA'<17>: CDS_PINID='DDR4_MA(17)';
NODE_NAME     J4A2 234
 '@BASEBOARD_FAB2_LIB.BASEBOARD_FAB2(SCH_1):PAGE51_I111@MSTR_SCONN.SCONN288_H44441004(CHIPS)':
 'A17': CDS_PINID='A17';
NODE_NAME     J6L2 234
 '@BASEBOARD_FAB2_LIB.BASEBOARD_FAB2(SCH_1):PAGE52_I12@MSTR_SCONN.SCONN288_H44441003(CHIPS)':
 'A17': CDS_PINID='A17';
NET_NAME
'M_E_MA<1>'
 '@BASEBOARD_FAB2_LIB.BASEBOARD_FAB2(SCH_1):M_E_MA'<1>:
 C_SIGNAL='@baseboard_fab2_lib.baseboard_fab2(sch_1):m_e_ma(1)';
NODE_NAME     U5D1 DW58
 '@BASEBOARD_FAB2_LIB.BASEBOARD_FAB2(SCH_1):PAGE27_I172@CHPSET_LIB.SKX_EXT_B(CHIPS)':
 'DDR4_MA'<1>: CDS_PINID='DDR4_MA(1)';
NODE_NAME     J4A2 72
 '@BASEBOARD_FAB2_LIB.BASEBOARD_FAB2(SCH_1):PAGE51_I111@MSTR_SCONN.SCONN288_H44441004(CHIPS)':
 'A1': CDS_PINID='A1';
NODE_NAME     J6L2 72
 '@BASEBOARD_FAB2_LIB.BASEBOARD_FAB2(SCH_1):PAGE52_I12@MSTR_SCONN.SCONN288_H44441003(CHIPS)':
 'A1': CDS_PINID='A1';
NET_NAME
'M_E_MA<2>'
 '@BASEBOARD_FAB2_LIB.BASEBOARD_FAB2(SCH_1):M_E_MA'<2>:
 C_SIGNAL='@baseboard_fab2_lib.baseboard_fab2(sch_1):m_e_ma(2)';
NODE_NAME     U5D1 DV57
 '@BASEBOARD_FAB2_LIB.BASEBOARD_FAB2(SCH_1):PAGE27_I172@CHPSET_LIB.SKX_EXT_B(CHIPS)':
 'DDR4_MA'<2>: CDS_PINID='DDR4_MA(2)';
NODE_NAME     J4A2 216
 '@BASEBOARD_FAB2_LIB.BASEBOARD_FAB2(SCH_1):PAGE51_I111@MSTR_SCONN.SCONN288_H44441004(CHIPS)':
 'A2': CDS_PINID='A2';
NODE_NAME     J6L2 216
 '@BASEBOARD_FAB2_LIB.BASEBOARD_FAB2(SCH_1):PAGE52_I12@MSTR_SCONN.SCONN288_H44441003(CHIPS)':
 'A2': CDS_PINID='A2';
NET_NAME
'M_E_MA<3>'
 '@BASEBOARD_FAB2_LIB.BASEBOARD_FAB2(SCH_1):M_E_MA'<3>:
 C_SIGNAL='@baseboard_fab2_lib.baseboard_fab2(sch_1):m_e_ma(3)';
NODE_NAME     U5D1 DR58
 '@BASEBOARD_FAB2_LIB.BASEBOARD_FAB2(SCH_1):PAGE27_I172@CHPSET_LIB.SKX_EXT_B(CHIPS)':
 'DDR4_MA'<3>: CDS_PINID='DDR4_MA(3)';
NODE_NAME     J4A2 71
 '@BASEBOARD_FAB2_LIB.BASEBOARD_FAB2(SCH_1):PAGE51_I111@MSTR_SCONN.SCONN288_H44441004(CHIPS)':
 'A3': CDS_PINID='A3';
NODE_NAME     J6L2 71
 '@BASEBOARD_FAB2_LIB.BASEBOARD_FAB2(SCH_1):PAGE52_I12@MSTR_SCONN.SCONN288_H44441003(CHIPS)':
 'A3': CDS_PINID='A3';
NET_NAME
'M_E_MA<4>'
 '@BASEBOARD_FAB2_LIB.BASEBOARD_FAB2(SCH_1):M_E_MA'<4>:
 C_SIGNAL='@baseboard_fab2_lib.baseboard_fab2(sch_1):m_e_ma(4)';
NODE_NAME     U5D1 DT59
 '@BASEBOARD_FAB2_LIB.BASEBOARD_FAB2(SCH_1):PAGE27_I172@CHPSET_LIB.SKX_EXT_B(CHIPS)':
 'DDR4_MA'<4>: CDS_PINID='DDR4_MA(4)';
NODE_NAME     J4A2 214
 '@BASEBOARD_FAB2_LIB.BASEBOARD_FAB2(SCH_1):PAGE51_I111@MSTR_SCONN.SCONN288_H44441004(CHIPS)':
 'A4': CDS_PINID='A4';
NODE_NAME     J6L2 214
 '@BASEBOARD_FAB2_LIB.BASEBOARD_FAB2(SCH_1):PAGE52_I12@MSTR_SCONN.SCONN288_H44441003(CHIPS)':
 'A4': CDS_PINID='A4';
NET_NAME
'M_E_MA<5>'
 '@BASEBOARD_FAB2_LIB.BASEBOARD_FAB2(SCH_1):M_E_MA'<5>:
 C_SIGNAL='@baseboard_fab2_lib.baseboard_fab2(sch_1):m_e_ma(5)';
NODE_NAME     U5D1 DN58
 '@BASEBOARD_FAB2_LIB.BASEBOARD_FAB2(SCH_1):PAGE27_I172@CHPSET_LIB.SKX_EXT_B(CHIPS)':
 'DDR4_MA'<5>: CDS_PINID='DDR4_MA(5)';
NODE_NAME     J4A2 213
 '@BASEBOARD_FAB2_LIB.BASEBOARD_FAB2(SCH_1):PAGE51_I111@MSTR_SCONN.SCONN288_H44441004(CHIPS)':
 'A5': CDS_PINID='A5';
NODE_NAME     J6L2 213
 '@BASEBOARD_FAB2_LIB.BASEBOARD_FAB2(SCH_1):PAGE52_I12@MSTR_SCONN.SCONN288_H44441003(CHIPS)':
 'A5': CDS_PINID='A5';
NET_NAME
'M_E_MA<6>'
 '@BASEBOARD_FAB2_LIB.BASEBOARD_FAB2(SCH_1):M_E_MA'<6>:
 C_SIGNAL='@baseboard_fab2_lib.baseboard_fab2(sch_1):m_e_ma(6)';
NODE_NAME     U5D1 DM59
 '@BASEBOARD_FAB2_LIB.BASEBOARD_FAB2(SCH_1):PAGE27_I172@CHPSET_LIB.SKX_EXT_B(CHIPS)':
 'DDR4_MA'<6>: CDS_PINID='DDR4_MA(6)';
NODE_NAME     J4A2 69
 '@BASEBOARD_FAB2_LIB.BASEBOARD_FAB2(SCH_1):PAGE51_I111@MSTR_SCONN.SCONN288_H44441004(CHIPS)':
 'A6': CDS_PINID='A6';
NODE_NAME     J6L2 69
 '@BASEBOARD_FAB2_LIB.BASEBOARD_FAB2(SCH_1):PAGE52_I12@MSTR_SCONN.SCONN288_H44441003(CHIPS)':
 'A6': CDS_PINID='A6';
NET_NAME
'M_E_MA<7>'
 '@BASEBOARD_FAB2_LIB.BASEBOARD_FAB2(SCH_1):M_E_MA'<7>:
 C_SIGNAL='@baseboard_fab2_lib.baseboard_fab2(sch_1):m_e_ma(7)';
NODE_NAME     U5D1 DK61
 '@BASEBOARD_FAB2_LIB.BASEBOARD_FAB2(SCH_1):PAGE27_I172@CHPSET_LIB.SKX_EXT_B(CHIPS)':
 'DDR4_MA'<7>: CDS_PINID='DDR4_MA(7)';
NODE_NAME     J4A2 211
 '@BASEBOARD_FAB2_LIB.BASEBOARD_FAB2(SCH_1):PAGE51_I111@MSTR_SCONN.SCONN288_H44441004(CHIPS)':
 'A7': CDS_PINID='A7';
NODE_NAME     J6L2 211
 '@BASEBOARD_FAB2_LIB.BASEBOARD_FAB2(SCH_1):PAGE52_I12@MSTR_SCONN.SCONN288_H44441003(CHIPS)':
 'A7': CDS_PINID='A7';
NET_NAME
'M_E_MA<8>'
 '@BASEBOARD_FAB2_LIB.BASEBOARD_FAB2(SCH_1):M_E_MA'<8>:
 C_SIGNAL='@baseboard_fab2_lib.baseboard_fab2(sch_1):m_e_ma(8)';
NODE_NAME     U5D1 DJ60
 '@BASEBOARD_FAB2_LIB.BASEBOARD_FAB2(SCH_1):PAGE27_I172@CHPSET_LIB.SKX_EXT_B(CHIPS)':
 'DDR4_MA'<8>: CDS_PINID='DDR4_MA(8)';
NODE_NAME     J4A2 68
 '@BASEBOARD_FAB2_LIB.BASEBOARD_FAB2(SCH_1):PAGE51_I111@MSTR_SCONN.SCONN288_H44441004(CHIPS)':
 'A8': CDS_PINID='A8';
NODE_NAME     J6L2 68
 '@BASEBOARD_FAB2_LIB.BASEBOARD_FAB2(SCH_1):PAGE52_I12@MSTR_SCONN.SCONN288_H44441003(CHIPS)':
 'A8': CDS_PINID='A8';
NET_NAME
'M_E_MA<9>'
 '@BASEBOARD_FAB2_LIB.BASEBOARD_FAB2(SCH_1):M_E_MA'<9>:
 C_SIGNAL='@baseboard_fab2_lib.baseboard_fab2(sch_1):m_e_ma(9)';
NODE_NAME     U5D1 DV59
 '@BASEBOARD_FAB2_LIB.BASEBOARD_FAB2(SCH_1):PAGE27_I172@CHPSET_LIB.SKX_EXT_B(CHIPS)':
 'DDR4_MA'<9>: CDS_PINID='DDR4_MA(9)';
NODE_NAME     J4A2 66
 '@BASEBOARD_FAB2_LIB.BASEBOARD_FAB2(SCH_1):PAGE51_I111@MSTR_SCONN.SCONN288_H44441004(CHIPS)':
 'A9': CDS_PINID='A9';
NODE_NAME     J6L2 66
 '@BASEBOARD_FAB2_LIB.BASEBOARD_FAB2(SCH_1):PAGE52_I12@MSTR_SCONN.SCONN288_H44441003(CHIPS)':
 'A9': CDS_PINID='A9';
NET_NAME
'M_E_ODT<0>'
 '@BASEBOARD_FAB2_LIB.BASEBOARD_FAB2(SCH_1):M_E_ODT'<0>:
 C_SIGNAL='@baseboard_fab2_lib.baseboard_fab2(sch_1):m_e_odt(0)';
NODE_NAME     U5D1 DR50
 '@BASEBOARD_FAB2_LIB.BASEBOARD_FAB2(SCH_1):PAGE27_I172@CHPSET_LIB.SKX_EXT_B(CHIPS)':
 'DDR4_ODT'<0>: CDS_PINID='DDR4_ODT(0)';
NODE_NAME     J4A2 87
 '@BASEBOARD_FAB2_LIB.BASEBOARD_FAB2(SCH_1):PAGE51_I111@MSTR_SCONN.SCONN288_H44441004(CHIPS)':
 'ODT'<0>: CDS_PINID='ODT(0)';
NET_NAME
'M_E_ODT<1>'
 '@BASEBOARD_FAB2_LIB.BASEBOARD_FAB2(SCH_1):M_E_ODT'<1>:
 C_SIGNAL='@baseboard_fab2_lib.baseboard_fab2(sch_1):m_e_odt(1)';
NODE_NAME     U5D1 DN48
 '@BASEBOARD_FAB2_LIB.BASEBOARD_FAB2(SCH_1):PAGE27_I172@CHPSET_LIB.SKX_EXT_B(CHIPS)':
 'DDR4_ODT'<1>: CDS_PINID='DDR4_ODT(1)';
NODE_NAME     J4A2 91
 '@BASEBOARD_FAB2_LIB.BASEBOARD_FAB2(SCH_1):PAGE51_I111@MSTR_SCONN.SCONN288_H44441004(CHIPS)':
 'ODT'<1>: CDS_PINID='ODT(1)';
NET_NAME
'M_E_ODT<2>'
 '@BASEBOARD_FAB2_LIB.BASEBOARD_FAB2(SCH_1):M_E_ODT'<2>:
 C_SIGNAL='@baseboard_fab2_lib.baseboard_fab2(sch_1):m_e_odt(2)';
NODE_NAME     U5D1 DT49
 '@BASEBOARD_FAB2_LIB.BASEBOARD_FAB2(SCH_1):PAGE27_I172@CHPSET_LIB.SKX_EXT_B(CHIPS)':
 'DDR4_ODT'<2>: CDS_PINID='DDR4_ODT(2)';
NODE_NAME     J6L2 87
 '@BASEBOARD_FAB2_LIB.BASEBOARD_FAB2(SCH_1):PAGE52_I12@MSTR_SCONN.SCONN288_H44441003(CHIPS)':
 'ODT'<0>: CDS_PINID='ODT(0)';
NET_NAME
'M_E_ODT<3>'
 '@BASEBOARD_FAB2_LIB.BASEBOARD_FAB2(SCH_1):M_E_ODT'<3>:
 C_SIGNAL='@baseboard_fab2_lib.baseboard_fab2(sch_1):m_e_odt(3)';
NODE_NAME     U5D1 DM47
 '@BASEBOARD_FAB2_LIB.BASEBOARD_FAB2(SCH_1):PAGE27_I172@CHPSET_LIB.SKX_EXT_B(CHIPS)':
 'DDR4_ODT'<3>: CDS_PINID='DDR4_ODT(3)';
NODE_NAME     J6L2 91
 '@BASEBOARD_FAB2_LIB.BASEBOARD_FAB2(SCH_1):PAGE52_I12@MSTR_SCONN.SCONN288_H44441003(CHIPS)':
 'ODT'<1>: CDS_PINID='ODT(1)';
NET_NAME
'M_E_PAR'
 '@BASEBOARD_FAB2_LIB.BASEBOARD_FAB2(SCH_1):M_E_PAR':
 C_SIGNAL='@baseboard_fab2_lib.baseboard_fab2(sch_1):m_e_par';
NODE_NAME     U5D1 DV53
 '@BASEBOARD_FAB2_LIB.BASEBOARD_FAB2(SCH_1):PAGE27_I172@CHPSET_LIB.SKX_EXT_B(CHIPS)':
 'DDR4_PAR': CDS_PINID='DDR4_PAR';
NODE_NAME     J4A2 222
 '@BASEBOARD_FAB2_LIB.BASEBOARD_FAB2(SCH_1):PAGE51_I111@MSTR_SCONN.SCONN288_H44441004(CHIPS)':
 'PAR': CDS_PINID='PAR';
NODE_NAME     J6L2 222
 '@BASEBOARD_FAB2_LIB.BASEBOARD_FAB2(SCH_1):PAGE52_I12@MSTR_SCONN.SCONN288_H44441003(CHIPS)':
 'PAR': CDS_PINID='PAR';
NET_NAME
'M_E_VREF'
 '@BASEBOARD_FAB2_LIB.BASEBOARD_FAB2(SCH_1):M_E_VREF':
 C_SIGNAL='@baseboard_fab2_lib.baseboard_fab2(sch_1):m_e_vref';
NODE_NAME     J4A2 146
 '@BASEBOARD_FAB2_LIB.BASEBOARD_FAB2(SCH_1):PAGE51_I111@MSTR_SCONN.SCONN288_H44441004(CHIPS)':
 'VREFCA': CDS_PINID='VREFCA';
NODE_NAME     C6L6 1
 '@BASEBOARD_FAB2_LIB.BASEBOARD_FAB2(SCH_1):PAGE51_I175@DEV_DISCRETE.CAP_A(CHIPS)':
 'A': CDS_PINID='A';
NODE_NAME     C4A18 1
 '@BASEBOARD_FAB2_LIB.BASEBOARD_FAB2(SCH_1):PAGE52_I3@DEV_DISCRETE.CAP_A(CHIPS)':
 'A': CDS_PINID='A';
NODE_NAME     J6L2 146
 '@BASEBOARD_FAB2_LIB.BASEBOARD_FAB2(SCH_1):PAGE52_I12@MSTR_SCONN.SCONN288_H44441003(CHIPS)':
 'VREFCA': CDS_PINID='VREFCA';
NODE_NAME     R6L13 2
 '@BASEBOARD_FAB2_LIB.BASEBOARD_FAB2(SCH_1):PAGE98_I54@MSTR_DISCRETE.RES(CHIPS)':
 'B': CDS_PINID='B';
NODE_NAME     R6L12 1
 '@BASEBOARD_FAB2_LIB.BASEBOARD_FAB2(SCH_1):PAGE98_I56@MSTR_DISCRETE.RES(CHIPS)':
 'A': CDS_PINID='A';
NODE_NAME     R6L14 2
 '@BASEBOARD_FAB2_LIB.BASEBOARD_FAB2(SCH_1):PAGE98_I58@MSTR_DISCRETE.RES(CHIPS)':
 'B': CDS_PINID='B';
NET_NAME
'M_F_ACT_N'
 '@BASEBOARD_FAB2_LIB.BASEBOARD_FAB2(SCH_1):M_F_ACT_N':
 C_SIGNAL='@baseboard_fab2_lib.baseboard_fab2(sch_1):m_f_act_n';
NODE_NAME     U5D1 DC62
 '@BASEBOARD_FAB2_LIB.BASEBOARD_FAB2(SCH_1):PAGE28_I172@CHPSET_LIB.SKX_EXT_B(CHIPS)':
 'DDR5_ACT_N': CDS_PINID='DDR5_ACT_N';
NODE_NAME     J4A1 62
 '@BASEBOARD_FAB2_LIB.BASEBOARD_FAB2(SCH_1):PAGE53_I111@MSTR_SCONN.SCONN288_H44441004(CHIPS)':
 'ACT_N': CDS_PINID='ACT_N';
NODE_NAME     J6L1 62
 '@BASEBOARD_FAB2_LIB.BASEBOARD_FAB2(SCH_1):PAGE54_I111@MSTR_SCONN.SCONN288_H44441003(CHIPS)':
 'ACT_N': CDS_PINID='ACT_N';
NET_NAME
'M_F_ALERT_N'
 '@BASEBOARD_FAB2_LIB.BASEBOARD_FAB2(SCH_1):M_F_ALERT_N':
 C_SIGNAL='@baseboard_fab2_lib.baseboard_fab2(sch_1):m_f_alert_n';
NODE_NAME     U5D1 DD61
 '@BASEBOARD_FAB2_LIB.BASEBOARD_FAB2(SCH_1):PAGE28_I172@CHPSET_LIB.SKX_EXT_B(CHIPS)':
 'DDR5_ALERT_N': CDS_PINID='DDR5_ALERT_N';
NODE_NAME     J4A1 208
 '@BASEBOARD_FAB2_LIB.BASEBOARD_FAB2(SCH_1):PAGE53_I111@MSTR_SCONN.SCONN288_H44441004(CHIPS)':
 'ALERT_N': CDS_PINID='ALERT_N';
NODE_NAME     J6L1 208
 '@BASEBOARD_FAB2_LIB.BASEBOARD_FAB2(SCH_1):PAGE54_I111@MSTR_SCONN.SCONN288_H44441003(CHIPS)':
 'ALERT_N': CDS_PINID='ALERT_N';
NET_NAME
'M_F_BA<0>'
 '@BASEBOARD_FAB2_LIB.BASEBOARD_FAB2(SCH_1):M_F_BA'<0>:
 C_SIGNAL='@baseboard_fab2_lib.baseboard_fab2(sch_1):m_f_ba(0)';
NODE_NAME     U5D1 DJ52
 '@BASEBOARD_FAB2_LIB.BASEBOARD_FAB2(SCH_1):PAGE28_I172@CHPSET_LIB.SKX_EXT_B(CHIPS)':
 'DDR5_BA'<0>: CDS_PINID='DDR5_BA(0)';
NODE_NAME     J4A1 81
 '@BASEBOARD_FAB2_LIB.BASEBOARD_FAB2(SCH_1):PAGE53_I111@MSTR_SCONN.SCONN288_H44441004(CHIPS)':
 'BA'<0>: CDS_PINID='BA(0)';
NODE_NAME     J6L1 81
 '@BASEBOARD_FAB2_LIB.BASEBOARD_FAB2(SCH_1):PAGE54_I111@MSTR_SCONN.SCONN288_H44441003(CHIPS)':
 'BA'<0>: CDS_PINID='BA(0)';
NET_NAME
'M_F_BA<1>'
 '@BASEBOARD_FAB2_LIB.BASEBOARD_FAB2(SCH_1):M_F_BA'<1>:
 C_SIGNAL='@baseboard_fab2_lib.baseboard_fab2(sch_1):m_f_ba(1)';
NODE_NAME     U5D1 DC56
 '@BASEBOARD_FAB2_LIB.BASEBOARD_FAB2(SCH_1):PAGE28_I172@CHPSET_LIB.SKX_EXT_B(CHIPS)':
 'DDR5_BA'<1>: CDS_PINID='DDR5_BA(1)';
NODE_NAME     J4A1 224
 '@BASEBOARD_FAB2_LIB.BASEBOARD_FAB2(SCH_1):PAGE53_I111@MSTR_SCONN.SCONN288_H44441004(CHIPS)':
 'BA'<1>: CDS_PINID='BA(1)';
NODE_NAME     J6L1 224
 '@BASEBOARD_FAB2_LIB.BASEBOARD_FAB2(SCH_1):PAGE54_I111@MSTR_SCONN.SCONN288_H44441003(CHIPS)':
 'BA'<1>: CDS_PINID='BA(1)';
NET_NAME
'M_F_BG<0>'
 '@BASEBOARD_FAB2_LIB.BASEBOARD_FAB2(SCH_1):M_F_BG'<0>:
 C_SIGNAL='@baseboard_fab2_lib.baseboard_fab2(sch_1):m_f_bg(0)';
NODE_NAME     U5D1 DA62
 '@BASEBOARD_FAB2_LIB.BASEBOARD_FAB2(SCH_1):PAGE28_I172@CHPSET_LIB.SKX_EXT_B(CHIPS)':
 'DDR5_BG'<0>: CDS_PINID='DDR5_BG(0)';
NODE_NAME     J4A1 63
 '@BASEBOARD_FAB2_LIB.BASEBOARD_FAB2(SCH_1):PAGE53_I111@MSTR_SCONN.SCONN288_H44441004(CHIPS)':
 'BG'<0>: CDS_PINID='BG(0)';
NODE_NAME     J6L1 63
 '@BASEBOARD_FAB2_LIB.BASEBOARD_FAB2(SCH_1):PAGE54_I111@MSTR_SCONN.SCONN288_H44441003(CHIPS)':
 'BG'<0>: CDS_PINID='BG(0)';
NET_NAME
'M_F_BG<1>'
 '@BASEBOARD_FAB2_LIB.BASEBOARD_FAB2(SCH_1):M_F_BG'<1>:
 C_SIGNAL='@baseboard_fab2_lib.baseboard_fab2(sch_1):m_f_bg(1)';
NODE_NAME     U5D1 DF61
 '@BASEBOARD_FAB2_LIB.BASEBOARD_FAB2(SCH_1):PAGE28_I172@CHPSET_LIB.SKX_EXT_B(CHIPS)':
 'DDR5_BG'<1>: CDS_PINID='DDR5_BG(1)';
NODE_NAME     J4A1 207
 '@BASEBOARD_FAB2_LIB.BASEBOARD_FAB2(SCH_1):PAGE53_I111@MSTR_SCONN.SCONN288_H44441004(CHIPS)':
 'BG'<1>: CDS_PINID='BG(1)';
NODE_NAME     J6L1 207
 '@BASEBOARD_FAB2_LIB.BASEBOARD_FAB2(SCH_1):PAGE54_I111@MSTR_SCONN.SCONN288_H44441003(CHIPS)':
 'BG'<1>: CDS_PINID='BG(1)';
NET_NAME
'M_F_C<2>'
 '@BASEBOARD_FAB2_LIB.BASEBOARD_FAB2(SCH_1):M_F_C'<2>:
 C_SIGNAL='@baseboard_fab2_lib.baseboard_fab2(sch_1):m_f_c(2)';
NODE_NAME     U5D1 DF45
 '@BASEBOARD_FAB2_LIB.BASEBOARD_FAB2(SCH_1):PAGE28_I172@CHPSET_LIB.SKX_EXT_B(CHIPS)':
 'DDR5_CID'<2>: CDS_PINID='DDR5_CID(2)';
NODE_NAME     J4A1 235
 '@BASEBOARD_FAB2_LIB.BASEBOARD_FAB2(SCH_1):PAGE53_I111@MSTR_SCONN.SCONN288_H44441004(CHIPS)':
 'C'<2>: CDS_PINID='C(2)';
NODE_NAME     J6L1 235
 '@BASEBOARD_FAB2_LIB.BASEBOARD_FAB2(SCH_1):PAGE54_I111@MSTR_SCONN.SCONN288_H44441003(CHIPS)':
 'C'<2>: CDS_PINID='C(2)';
NET_NAME
'M_F_CKE<0>'
 '@BASEBOARD_FAB2_LIB.BASEBOARD_FAB2(SCH_1):M_F_CKE'<0>:
 C_SIGNAL='@baseboard_fab2_lib.baseboard_fab2(sch_1):m_f_cke(0)';
NODE_NAME     U5D1 DG62
 '@BASEBOARD_FAB2_LIB.BASEBOARD_FAB2(SCH_1):PAGE28_I172@CHPSET_LIB.SKX_EXT_B(CHIPS)':
 'DDR5_CKE'<0>: CDS_PINID='DDR5_CKE(0)';
NODE_NAME     J4A1 60
 '@BASEBOARD_FAB2_LIB.BASEBOARD_FAB2(SCH_1):PAGE53_I111@MSTR_SCONN.SCONN288_H44441004(CHIPS)':
 'CKE'<0>: CDS_PINID='CKE(0)';
NET_NAME
'M_F_CKE<1>'
 '@BASEBOARD_FAB2_LIB.BASEBOARD_FAB2(SCH_1):M_F_CKE'<1>:
 C_SIGNAL='@baseboard_fab2_lib.baseboard_fab2(sch_1):m_f_cke(1)';
NODE_NAME     U5D1 DD63
 '@BASEBOARD_FAB2_LIB.BASEBOARD_FAB2(SCH_1):PAGE28_I172@CHPSET_LIB.SKX_EXT_B(CHIPS)':
 'DDR5_CKE'<1>: CDS_PINID='DDR5_CKE(1)';
NODE_NAME     J4A1 203
 '@BASEBOARD_FAB2_LIB.BASEBOARD_FAB2(SCH_1):PAGE53_I111@MSTR_SCONN.SCONN288_H44441004(CHIPS)':
 'CKE'<1>: CDS_PINID='CKE(1)';
NET_NAME
'M_F_CKE<2>'
 '@BASEBOARD_FAB2_LIB.BASEBOARD_FAB2(SCH_1):M_F_CKE'<2>:
 C_SIGNAL='@baseboard_fab2_lib.baseboard_fab2(sch_1):m_f_cke(2)';
NODE_NAME     U5D1 DK63
 '@BASEBOARD_FAB2_LIB.BASEBOARD_FAB2(SCH_1):PAGE28_I172@CHPSET_LIB.SKX_EXT_B(CHIPS)':
 'DDR5_CKE'<2>: CDS_PINID='DDR5_CKE(2)';
NODE_NAME     J6L1 60
 '@BASEBOARD_FAB2_LIB.BASEBOARD_FAB2(SCH_1):PAGE54_I111@MSTR_SCONN.SCONN288_H44441003(CHIPS)':
 'CKE'<0>: CDS_PINID='CKE(0)';
NET_NAME
'M_F_CKE<3>'
 '@BASEBOARD_FAB2_LIB.BASEBOARD_FAB2(SCH_1):M_F_CKE'<3>:
 C_SIGNAL='@baseboard_fab2_lib.baseboard_fab2(sch_1):m_f_cke(3)';
NODE_NAME     U5D1 DF63
 '@BASEBOARD_FAB2_LIB.BASEBOARD_FAB2(SCH_1):PAGE28_I172@CHPSET_LIB.SKX_EXT_B(CHIPS)':
 'DDR5_CKE'<3>: CDS_PINID='DDR5_CKE(3)';
NODE_NAME     J6L1 203
 '@BASEBOARD_FAB2_LIB.BASEBOARD_FAB2(SCH_1):PAGE54_I111@MSTR_SCONN.SCONN288_H44441003(CHIPS)':
 'CKE'<1>: CDS_PINID='CKE(1)';
NET_NAME
'M_F_CLK_DN<0>'
 '@BASEBOARD_FAB2_LIB.BASEBOARD_FAB2(SCH_1):M_F_CLK_DN'<0>:
 C_SIGNAL='@baseboard_fab2_lib.baseboard_fab2(sch_1):m_f_clk_dn(0)';
NODE_NAME     U5D1 DK55
 '@BASEBOARD_FAB2_LIB.BASEBOARD_FAB2(SCH_1):PAGE28_I172@CHPSET_LIB.SKX_EXT_B(CHIPS)':
 'DDR5_CLK_DN'<0>: CDS_PINID='DDR5_CLK_DN(0)';
NODE_NAME     J4A1 75
 '@BASEBOARD_FAB2_LIB.BASEBOARD_FAB2(SCH_1):PAGE53_I111@MSTR_SCONN.SCONN288_H44441004(CHIPS)':
 'CK0N': CDS_PINID='CK0N';
NET_NAME
'M_F_CLK_DN<1>'
 '@BASEBOARD_FAB2_LIB.BASEBOARD_FAB2(SCH_1):M_F_CLK_DN'<1>:
 C_SIGNAL='@baseboard_fab2_lib.baseboard_fab2(sch_1):m_f_clk_dn(1)';
NODE_NAME     U5D1 DF55
 '@BASEBOARD_FAB2_LIB.BASEBOARD_FAB2(SCH_1):PAGE28_I172@CHPSET_LIB.SKX_EXT_B(CHIPS)':
 'DDR5_CLK_DN'<1>: CDS_PINID='DDR5_CLK_DN(1)';
NODE_NAME     J4A1 219
 '@BASEBOARD_FAB2_LIB.BASEBOARD_FAB2(SCH_1):PAGE53_I111@MSTR_SCONN.SCONN288_H44441004(CHIPS)':
 'CK1N': CDS_PINID='CK1N';
NET_NAME
'M_F_CLK_DN<2>'
 '@BASEBOARD_FAB2_LIB.BASEBOARD_FAB2(SCH_1):M_F_CLK_DN'<2>:
 C_SIGNAL='@baseboard_fab2_lib.baseboard_fab2(sch_1):m_f_clk_dn(2)';
NODE_NAME     U5D1 DK57
 '@BASEBOARD_FAB2_LIB.BASEBOARD_FAB2(SCH_1):PAGE28_I172@CHPSET_LIB.SKX_EXT_B(CHIPS)':
 'DDR5_CLK_DN'<2>: CDS_PINID='DDR5_CLK_DN(2)';
NODE_NAME     J6L1 75
 '@BASEBOARD_FAB2_LIB.BASEBOARD_FAB2(SCH_1):PAGE54_I111@MSTR_SCONN.SCONN288_H44441003(CHIPS)':
 'CK0N': CDS_PINID='CK0N';
NET_NAME
'M_F_CLK_DN<3>'
 '@BASEBOARD_FAB2_LIB.BASEBOARD_FAB2(SCH_1):M_F_CLK_DN'<3>:
 C_SIGNAL='@baseboard_fab2_lib.baseboard_fab2(sch_1):m_f_clk_dn(3)';
NODE_NAME     U5D1 DF57
 '@BASEBOARD_FAB2_LIB.BASEBOARD_FAB2(SCH_1):PAGE28_I172@CHPSET_LIB.SKX_EXT_B(CHIPS)':
 'DDR5_CLK_DN'<3>: CDS_PINID='DDR5_CLK_DN(3)';
NODE_NAME     J6L1 219
 '@BASEBOARD_FAB2_LIB.BASEBOARD_FAB2(SCH_1):PAGE54_I111@MSTR_SCONN.SCONN288_H44441003(CHIPS)':
 'CK1N': CDS_PINID='CK1N';
NET_NAME
'M_F_CLK_DP<0>'
 '@BASEBOARD_FAB2_LIB.BASEBOARD_FAB2(SCH_1):M_F_CLK_DP'<0>:
 C_SIGNAL='@baseboard_fab2_lib.baseboard_fab2(sch_1):m_f_clk_dp(0)';
NODE_NAME     U5D1 DJ54
 '@BASEBOARD_FAB2_LIB.BASEBOARD_FAB2(SCH_1):PAGE28_I172@CHPSET_LIB.SKX_EXT_B(CHIPS)':
 'DDR5_CLK_DP'<0>: CDS_PINID='DDR5_CLK_DP(0)';
NODE_NAME     J4A1 74
 '@BASEBOARD_FAB2_LIB.BASEBOARD_FAB2(SCH_1):PAGE53_I111@MSTR_SCONN.SCONN288_H44441004(CHIPS)':
 'CK0P': CDS_PINID='CK0P';
NET_NAME
'M_F_CLK_DP<1>'
 '@BASEBOARD_FAB2_LIB.BASEBOARD_FAB2(SCH_1):M_F_CLK_DP'<1>:
 C_SIGNAL='@baseboard_fab2_lib.baseboard_fab2(sch_1):m_f_clk_dp(1)';
NODE_NAME     U5D1 DG54
 '@BASEBOARD_FAB2_LIB.BASEBOARD_FAB2(SCH_1):PAGE28_I172@CHPSET_LIB.SKX_EXT_B(CHIPS)':
 'DDR5_CLK_DP'<1>: CDS_PINID='DDR5_CLK_DP(1)';
NODE_NAME     J4A1 218
 '@BASEBOARD_FAB2_LIB.BASEBOARD_FAB2(SCH_1):PAGE53_I111@MSTR_SCONN.SCONN288_H44441004(CHIPS)':
 'CK1P': CDS_PINID='CK1P';
NET_NAME
'M_F_CLK_DP<2>'
 '@BASEBOARD_FAB2_LIB.BASEBOARD_FAB2(SCH_1):M_F_CLK_DP'<2>:
 C_SIGNAL='@baseboard_fab2_lib.baseboard_fab2(sch_1):m_f_clk_dp(2)';
NODE_NAME     U5D1 DJ56
 '@BASEBOARD_FAB2_LIB.BASEBOARD_FAB2(SCH_1):PAGE28_I172@CHPSET_LIB.SKX_EXT_B(CHIPS)':
 'DDR5_CLK_DP'<2>: CDS_PINID='DDR5_CLK_DP(2)';
NODE_NAME     J6L1 74
 '@BASEBOARD_FAB2_LIB.BASEBOARD_FAB2(SCH_1):PAGE54_I111@MSTR_SCONN.SCONN288_H44441003(CHIPS)':
 'CK0P': CDS_PINID='CK0P';
NET_NAME
'M_F_CLK_DP<3>'
 '@BASEBOARD_FAB2_LIB.BASEBOARD_FAB2(SCH_1):M_F_CLK_DP'<3>:
 C_SIGNAL='@baseboard_fab2_lib.baseboard_fab2(sch_1):m_f_clk_dp(3)';
NODE_NAME     U5D1 DG56
 '@BASEBOARD_FAB2_LIB.BASEBOARD_FAB2(SCH_1):PAGE28_I172@CHPSET_LIB.SKX_EXT_B(CHIPS)':
 'DDR5_CLK_DP'<3>: CDS_PINID='DDR5_CLK_DP(3)';
NODE_NAME     J6L1 218
 '@BASEBOARD_FAB2_LIB.BASEBOARD_FAB2(SCH_1):PAGE54_I111@MSTR_SCONN.SCONN288_H44441003(CHIPS)':
 'CK1P': CDS_PINID='CK1P';
NET_NAME
'M_F_CPU_VREF'
 '@BASEBOARD_FAB2_LIB.BASEBOARD_FAB2(SCH_1):M_F_CPU_VREF':
 C_SIGNAL='@baseboard_fab2_lib.baseboard_fab2(sch_1):m_f_cpu_vref';
NODE_NAME     U5D1 CV61
 '@BASEBOARD_FAB2_LIB.BASEBOARD_FAB2(SCH_1):PAGE21_I259@CHPSET_LIB.SKX_EXT_B(CHIPS)':
 'DDR5_CAVREF': CDS_PINID='DDR5_CAVREF';
NODE_NAME     R6L3 1
 '@BASEBOARD_FAB2_LIB.BASEBOARD_FAB2(SCH_1):PAGE98_I66@MSTR_DISCRETE.RES(CHIPS)':
 'A': CDS_PINID='A';
NODE_NAME     C6L2 1
 '@BASEBOARD_FAB2_LIB.BASEBOARD_FAB2(SCH_1):PAGE98_I67@DEV_DISCRETE.CAP_A(CHIPS)':
 'A': CDS_PINID='A';
NET_NAME
'M_F_CS_N<0>'
 '@BASEBOARD_FAB2_LIB.BASEBOARD_FAB2(SCH_1):M_F_CS_N'<0>:
 C_SIGNAL='@baseboard_fab2_lib.baseboard_fab2(sch_1):m_f_cs_n(0)';
NODE_NAME     U5D1 DK51
 '@BASEBOARD_FAB2_LIB.BASEBOARD_FAB2(SCH_1):PAGE28_I172@CHPSET_LIB.SKX_EXT_B(CHIPS)':
 'DDR5_CS_N'<0>: CDS_PINID='DDR5_CS_N(0)';
NODE_NAME     J4A1 84
 '@BASEBOARD_FAB2_LIB.BASEBOARD_FAB2(SCH_1):PAGE53_I111@MSTR_SCONN.SCONN288_H44441004(CHIPS)':
 'S0_N': CDS_PINID='S0_N';
NET_NAME
'M_F_CS_N<1>'
 '@BASEBOARD_FAB2_LIB.BASEBOARD_FAB2(SCH_1):M_F_CS_N'<1>:
 C_SIGNAL='@baseboard_fab2_lib.baseboard_fab2(sch_1):m_f_cs_n(1)';
NODE_NAME     U5D1 DF49
 '@BASEBOARD_FAB2_LIB.BASEBOARD_FAB2(SCH_1):PAGE28_I172@CHPSET_LIB.SKX_EXT_B(CHIPS)':
 'DDR5_CS_N'<1>: CDS_PINID='DDR5_CS_N(1)';
NODE_NAME     J4A1 89
 '@BASEBOARD_FAB2_LIB.BASEBOARD_FAB2(SCH_1):PAGE53_I111@MSTR_SCONN.SCONN288_H44441004(CHIPS)':
 'S1_N': CDS_PINID='S1_N';
NET_NAME
'M_F_CS_N<2>'
 '@BASEBOARD_FAB2_LIB.BASEBOARD_FAB2(SCH_1):M_F_CS_N'<2>:
 C_SIGNAL='@baseboard_fab2_lib.baseboard_fab2(sch_1):m_f_cs_n(2)';
NODE_NAME     U5D1 DJ46
 '@BASEBOARD_FAB2_LIB.BASEBOARD_FAB2(SCH_1):PAGE28_I172@CHPSET_LIB.SKX_EXT_B(CHIPS)':
 'DDR5_CS_N'<2>: CDS_PINID='DDR5_CS_N(2)';
NODE_NAME     J4A1 93
 '@BASEBOARD_FAB2_LIB.BASEBOARD_FAB2(SCH_1):PAGE53_I111@MSTR_SCONN.SCONN288_H44441004(CHIPS)':
 'S2_N_C'<0>: CDS_PINID='S2_N_C(0)';
NET_NAME
'M_F_CS_N<3>'
 '@BASEBOARD_FAB2_LIB.BASEBOARD_FAB2(SCH_1):M_F_CS_N'<3>:
 C_SIGNAL='@baseboard_fab2_lib.baseboard_fab2(sch_1):m_f_cs_n(3)';
NODE_NAME     U5D1 DG46
 '@BASEBOARD_FAB2_LIB.BASEBOARD_FAB2(SCH_1):PAGE28_I172@CHPSET_LIB.SKX_EXT_B(CHIPS)':
 'DDR5_CS_N'<3>: CDS_PINID='DDR5_CS_N(3)';
NODE_NAME     J4A1 237
 '@BASEBOARD_FAB2_LIB.BASEBOARD_FAB2(SCH_1):PAGE53_I111@MSTR_SCONN.SCONN288_H44441004(CHIPS)':
 'S3_N_C'<1>: CDS_PINID='S3_N_C(1)';
NET_NAME
'M_F_CS_N<4>'
 '@BASEBOARD_FAB2_LIB.BASEBOARD_FAB2(SCH_1):M_F_CS_N'<4>:
 C_SIGNAL='@baseboard_fab2_lib.baseboard_fab2(sch_1):m_f_cs_n(4)';
NODE_NAME     U5D1 DF51
 '@BASEBOARD_FAB2_LIB.BASEBOARD_FAB2(SCH_1):PAGE28_I172@CHPSET_LIB.SKX_EXT_B(CHIPS)':
 'DDR5_CS_N'<4>: CDS_PINID='DDR5_CS_N(4)';
NODE_NAME     J6L1 84
 '@BASEBOARD_FAB2_LIB.BASEBOARD_FAB2(SCH_1):PAGE54_I111@MSTR_SCONN.SCONN288_H44441003(CHIPS)':
 'S0_N': CDS_PINID='S0_N';
NET_NAME
'M_F_CS_N<5>'
 '@BASEBOARD_FAB2_LIB.BASEBOARD_FAB2(SCH_1):M_F_CS_N'<5>:
 C_SIGNAL='@baseboard_fab2_lib.baseboard_fab2(sch_1):m_f_cs_n(5)';
NODE_NAME     U5D1 DJ48
 '@BASEBOARD_FAB2_LIB.BASEBOARD_FAB2(SCH_1):PAGE28_I172@CHPSET_LIB.SKX_EXT_B(CHIPS)':
 'DDR5_CS_N'<5>: CDS_PINID='DDR5_CS_N(5)';
NODE_NAME     J6L1 89
 '@BASEBOARD_FAB2_LIB.BASEBOARD_FAB2(SCH_1):PAGE54_I111@MSTR_SCONN.SCONN288_H44441003(CHIPS)':
 'S1_N': CDS_PINID='S1_N';
NET_NAME
'M_F_CS_N<6>'
 '@BASEBOARD_FAB2_LIB.BASEBOARD_FAB2(SCH_1):M_F_CS_N'<6>:
 C_SIGNAL='@baseboard_fab2_lib.baseboard_fab2(sch_1):m_f_cs_n(6)';
NODE_NAME     U5D1 DM45
 '@BASEBOARD_FAB2_LIB.BASEBOARD_FAB2(SCH_1):PAGE28_I172@CHPSET_LIB.SKX_EXT_B(CHIPS)':
 'DDR5_CS_N'<6>: CDS_PINID='DDR5_CS_N(6)';
NODE_NAME     J6L1 93
 '@BASEBOARD_FAB2_LIB.BASEBOARD_FAB2(SCH_1):PAGE54_I111@MSTR_SCONN.SCONN288_H44441003(CHIPS)':
 'S2_N_C'<0>: CDS_PINID='S2_N_C(0)';
NET_NAME
'M_F_CS_N<7>'
 '@BASEBOARD_FAB2_LIB.BASEBOARD_FAB2(SCH_1):M_F_CS_N'<7>:
 C_SIGNAL='@baseboard_fab2_lib.baseboard_fab2(sch_1):m_f_cs_n(7)';
NODE_NAME     U5D1 DK45
 '@BASEBOARD_FAB2_LIB.BASEBOARD_FAB2(SCH_1):PAGE28_I172@CHPSET_LIB.SKX_EXT_B(CHIPS)':
 'DDR5_CS_N'<7>: CDS_PINID='DDR5_CS_N(7)';
NODE_NAME     J6L1 237
 '@BASEBOARD_FAB2_LIB.BASEBOARD_FAB2(SCH_1):PAGE54_I111@MSTR_SCONN.SCONN288_H44441003(CHIPS)':
 'S3_N_C'<1>: CDS_PINID='S3_N_C(1)';
NET_NAME
'M_F_DQ<0>'
 '@BASEBOARD_FAB2_LIB.BASEBOARD_FAB2(SCH_1):M_F_DQ'<0>:
 C_SIGNAL='@baseboard_fab2_lib.baseboard_fab2(sch_1):m_f_dq(0)';
NODE_NAME     U5D1 CR74
 '@BASEBOARD_FAB2_LIB.BASEBOARD_FAB2(SCH_1):PAGE28_I172@CHPSET_LIB.SKX_EXT_B(CHIPS)':
 'DDR5_DQ'<0>: CDS_PINID='DDR5_DQ(0)';
NODE_NAME     J4A1 150
 '@BASEBOARD_FAB2_LIB.BASEBOARD_FAB2(SCH_1):PAGE53_I111@MSTR_SCONN.SCONN288_H44441004(CHIPS)':
 'DQ'<1>: CDS_PINID='DQ(1)';
NODE_NAME     J6L1 5
 '@BASEBOARD_FAB2_LIB.BASEBOARD_FAB2(SCH_1):PAGE54_I111@MSTR_SCONN.SCONN288_H44441003(CHIPS)':
 'DQ'<0>: CDS_PINID='DQ(0)';
NET_NAME
'M_F_DQ<10>'
 '@BASEBOARD_FAB2_LIB.BASEBOARD_FAB2(SCH_1):M_F_DQ'<10>:
 C_SIGNAL='@baseboard_fab2_lib.baseboard_fab2(sch_1):m_f_dq(10)';
NODE_NAME     U5D1 DH75
 '@BASEBOARD_FAB2_LIB.BASEBOARD_FAB2(SCH_1):PAGE28_I172@CHPSET_LIB.SKX_EXT_B(CHIPS)':
 'DDR5_DQ'<10>: CDS_PINID='DDR5_DQ(10)';
NODE_NAME     J4A1 168
 '@BASEBOARD_FAB2_LIB.BASEBOARD_FAB2(SCH_1):PAGE53_I111@MSTR_SCONN.SCONN288_H44441004(CHIPS)':
 'DQ'<11>: CDS_PINID='DQ(11)';
NODE_NAME     J6L1 23
 '@BASEBOARD_FAB2_LIB.BASEBOARD_FAB2(SCH_1):PAGE54_I111@MSTR_SCONN.SCONN288_H44441003(CHIPS)':
 'DQ'<10>: CDS_PINID='DQ(10)';
NET_NAME
'M_F_DQ<11>'
 '@BASEBOARD_FAB2_LIB.BASEBOARD_FAB2(SCH_1):M_F_DQ'<11>:
 C_SIGNAL='@baseboard_fab2_lib.baseboard_fab2(sch_1):m_f_dq(11)';
NODE_NAME     U5D1 DJ76
 '@BASEBOARD_FAB2_LIB.BASEBOARD_FAB2(SCH_1):PAGE28_I172@CHPSET_LIB.SKX_EXT_B(CHIPS)':
 'DDR5_DQ'<11>: CDS_PINID='DDR5_DQ(11)';
NODE_NAME     J4A1 23
 '@BASEBOARD_FAB2_LIB.BASEBOARD_FAB2(SCH_1):PAGE53_I111@MSTR_SCONN.SCONN288_H44441004(CHIPS)':
 'DQ'<10>: CDS_PINID='DQ(10)';
NODE_NAME     J6L1 168
 '@BASEBOARD_FAB2_LIB.BASEBOARD_FAB2(SCH_1):PAGE54_I111@MSTR_SCONN.SCONN288_H44441003(CHIPS)':
 'DQ'<11>: CDS_PINID='DQ(11)';
NET_NAME
'M_F_DQ<12>'
 '@BASEBOARD_FAB2_LIB.BASEBOARD_FAB2(SCH_1):M_F_DQ'<12>:
 C_SIGNAL='@baseboard_fab2_lib.baseboard_fab2(sch_1):m_f_dq(12)';
NODE_NAME     U5D1 DC74
 '@BASEBOARD_FAB2_LIB.BASEBOARD_FAB2(SCH_1):PAGE28_I172@CHPSET_LIB.SKX_EXT_B(CHIPS)':
 'DDR5_DQ'<12>: CDS_PINID='DDR5_DQ(12)';
NODE_NAME     J4A1 159
 '@BASEBOARD_FAB2_LIB.BASEBOARD_FAB2(SCH_1):PAGE53_I111@MSTR_SCONN.SCONN288_H44441004(CHIPS)':
 'DQ'<13>: CDS_PINID='DQ(13)';
NODE_NAME     J6L1 14
 '@BASEBOARD_FAB2_LIB.BASEBOARD_FAB2(SCH_1):PAGE54_I111@MSTR_SCONN.SCONN288_H44441003(CHIPS)':
 'DQ'<12>: CDS_PINID='DQ(12)';
NET_NAME
'M_F_DQ<13>'
 '@BASEBOARD_FAB2_LIB.BASEBOARD_FAB2(SCH_1):M_F_DQ'<13>:
 C_SIGNAL='@baseboard_fab2_lib.baseboard_fab2(sch_1):m_f_dq(13)';
NODE_NAME     U5D1 DB75
 '@BASEBOARD_FAB2_LIB.BASEBOARD_FAB2(SCH_1):PAGE28_I172@CHPSET_LIB.SKX_EXT_B(CHIPS)':
 'DDR5_DQ'<13>: CDS_PINID='DDR5_DQ(13)';
NODE_NAME     J4A1 14
 '@BASEBOARD_FAB2_LIB.BASEBOARD_FAB2(SCH_1):PAGE53_I111@MSTR_SCONN.SCONN288_H44441004(CHIPS)':
 'DQ'<12>: CDS_PINID='DQ(12)';
NODE_NAME     J6L1 159
 '@BASEBOARD_FAB2_LIB.BASEBOARD_FAB2(SCH_1):PAGE54_I111@MSTR_SCONN.SCONN288_H44441003(CHIPS)':
 'DQ'<13>: CDS_PINID='DQ(13)';
NET_NAME
'M_F_DQ<14>'
 '@BASEBOARD_FAB2_LIB.BASEBOARD_FAB2(SCH_1):M_F_DQ'<14>:
 C_SIGNAL='@baseboard_fab2_lib.baseboard_fab2(sch_1):m_f_dq(14)';
NODE_NAME     U5D1 DF77
 '@BASEBOARD_FAB2_LIB.BASEBOARD_FAB2(SCH_1):PAGE28_I172@CHPSET_LIB.SKX_EXT_B(CHIPS)':
 'DDR5_DQ'<14>: CDS_PINID='DDR5_DQ(14)';
NODE_NAME     J4A1 166
 '@BASEBOARD_FAB2_LIB.BASEBOARD_FAB2(SCH_1):PAGE53_I111@MSTR_SCONN.SCONN288_H44441004(CHIPS)':
 'DQ'<15>: CDS_PINID='DQ(15)';
NODE_NAME     J6L1 21
 '@BASEBOARD_FAB2_LIB.BASEBOARD_FAB2(SCH_1):PAGE54_I111@MSTR_SCONN.SCONN288_H44441003(CHIPS)':
 'DQ'<14>: CDS_PINID='DQ(14)';
NET_NAME
'M_F_DQ<15>'
 '@BASEBOARD_FAB2_LIB.BASEBOARD_FAB2(SCH_1):M_F_DQ'<15>:
 C_SIGNAL='@baseboard_fab2_lib.baseboard_fab2(sch_1):m_f_dq(15)';
NODE_NAME     U5D1 DH77
 '@BASEBOARD_FAB2_LIB.BASEBOARD_FAB2(SCH_1):PAGE28_I172@CHPSET_LIB.SKX_EXT_B(CHIPS)':
 'DDR5_DQ'<15>: CDS_PINID='DDR5_DQ(15)';
NODE_NAME     J4A1 21
 '@BASEBOARD_FAB2_LIB.BASEBOARD_FAB2(SCH_1):PAGE53_I111@MSTR_SCONN.SCONN288_H44441004(CHIPS)':
 'DQ'<14>: CDS_PINID='DQ(14)';
NODE_NAME     J6L1 166
 '@BASEBOARD_FAB2_LIB.BASEBOARD_FAB2(SCH_1):PAGE54_I111@MSTR_SCONN.SCONN288_H44441003(CHIPS)':
 'DQ'<15>: CDS_PINID='DQ(15)';
NET_NAME
'M_F_DQ<16>'
 '@BASEBOARD_FAB2_LIB.BASEBOARD_FAB2(SCH_1):M_F_DQ'<16>:
 C_SIGNAL='@baseboard_fab2_lib.baseboard_fab2(sch_1):m_f_dq(16)';
NODE_NAME     U5D1 DG70
 '@BASEBOARD_FAB2_LIB.BASEBOARD_FAB2(SCH_1):PAGE28_I172@CHPSET_LIB.SKX_EXT_B(CHIPS)':
 'DDR5_DQ'<16>: CDS_PINID='DDR5_DQ(16)';
NODE_NAME     J4A1 172
 '@BASEBOARD_FAB2_LIB.BASEBOARD_FAB2(SCH_1):PAGE53_I111@MSTR_SCONN.SCONN288_H44441004(CHIPS)':
 'DQ'<17>: CDS_PINID='DQ(17)';
NODE_NAME     J6L1 27
 '@BASEBOARD_FAB2_LIB.BASEBOARD_FAB2(SCH_1):PAGE54_I111@MSTR_SCONN.SCONN288_H44441003(CHIPS)':
 'DQ'<16>: CDS_PINID='DQ(16)';
NET_NAME
'M_F_DQ<17>'
 '@BASEBOARD_FAB2_LIB.BASEBOARD_FAB2(SCH_1):M_F_DQ'<17>:
 C_SIGNAL='@baseboard_fab2_lib.baseboard_fab2(sch_1):m_f_dq(17)';
NODE_NAME     U5D1 DJ72
 '@BASEBOARD_FAB2_LIB.BASEBOARD_FAB2(SCH_1):PAGE28_I172@CHPSET_LIB.SKX_EXT_B(CHIPS)':
 'DDR5_DQ'<17>: CDS_PINID='DDR5_DQ(17)';
NODE_NAME     J4A1 27
 '@BASEBOARD_FAB2_LIB.BASEBOARD_FAB2(SCH_1):PAGE53_I111@MSTR_SCONN.SCONN288_H44441004(CHIPS)':
 'DQ'<16>: CDS_PINID='DQ(16)';
NODE_NAME     J6L1 172
 '@BASEBOARD_FAB2_LIB.BASEBOARD_FAB2(SCH_1):PAGE54_I111@MSTR_SCONN.SCONN288_H44441003(CHIPS)':
 'DQ'<17>: CDS_PINID='DQ(17)';
NET_NAME
'M_F_DQ<18>'
 '@BASEBOARD_FAB2_LIB.BASEBOARD_FAB2(SCH_1):M_F_DQ'<18>:
 C_SIGNAL='@baseboard_fab2_lib.baseboard_fab2(sch_1):m_f_dq(18)';
NODE_NAME     U5D1 DM69
 '@BASEBOARD_FAB2_LIB.BASEBOARD_FAB2(SCH_1):PAGE28_I172@CHPSET_LIB.SKX_EXT_B(CHIPS)':
 'DDR5_DQ'<18>: CDS_PINID='DDR5_DQ(18)';
NODE_NAME     J4A1 179
 '@BASEBOARD_FAB2_LIB.BASEBOARD_FAB2(SCH_1):PAGE53_I111@MSTR_SCONN.SCONN288_H44441004(CHIPS)':
 'DQ'<19>: CDS_PINID='DQ(19)';
NODE_NAME     J6L1 34
 '@BASEBOARD_FAB2_LIB.BASEBOARD_FAB2(SCH_1):PAGE54_I111@MSTR_SCONN.SCONN288_H44441003(CHIPS)':
 'DQ'<18>: CDS_PINID='DQ(18)';
NET_NAME
'M_F_DQ<19>'
 '@BASEBOARD_FAB2_LIB.BASEBOARD_FAB2(SCH_1):M_F_DQ'<19>:
 C_SIGNAL='@baseboard_fab2_lib.baseboard_fab2(sch_1):m_f_dq(19)';
NODE_NAME     U5D1 DN70
 '@BASEBOARD_FAB2_LIB.BASEBOARD_FAB2(SCH_1):PAGE28_I172@CHPSET_LIB.SKX_EXT_B(CHIPS)':
 'DDR5_DQ'<19>: CDS_PINID='DDR5_DQ(19)';
NODE_NAME     J4A1 34
 '@BASEBOARD_FAB2_LIB.BASEBOARD_FAB2(SCH_1):PAGE53_I111@MSTR_SCONN.SCONN288_H44441004(CHIPS)':
 'DQ'<18>: CDS_PINID='DQ(18)';
NODE_NAME     J6L1 179
 '@BASEBOARD_FAB2_LIB.BASEBOARD_FAB2(SCH_1):PAGE54_I111@MSTR_SCONN.SCONN288_H44441003(CHIPS)':
 'DQ'<19>: CDS_PINID='DQ(19)';
NET_NAME
'M_F_DQ<1>'
 '@BASEBOARD_FAB2_LIB.BASEBOARD_FAB2(SCH_1):M_F_DQ'<1>:
 C_SIGNAL='@baseboard_fab2_lib.baseboard_fab2(sch_1):m_f_dq(1)';
NODE_NAME     U5D1 CN76
 '@BASEBOARD_FAB2_LIB.BASEBOARD_FAB2(SCH_1):PAGE28_I172@CHPSET_LIB.SKX_EXT_B(CHIPS)':
 'DDR5_DQ'<1>: CDS_PINID='DDR5_DQ(1)';
NODE_NAME     J4A1 5
 '@BASEBOARD_FAB2_LIB.BASEBOARD_FAB2(SCH_1):PAGE53_I111@MSTR_SCONN.SCONN288_H44441004(CHIPS)':
 'DQ'<0>: CDS_PINID='DQ(0)';
NODE_NAME     J6L1 150
 '@BASEBOARD_FAB2_LIB.BASEBOARD_FAB2(SCH_1):PAGE54_I111@MSTR_SCONN.SCONN288_H44441003(CHIPS)':
 'DQ'<1>: CDS_PINID='DQ(1)';
NET_NAME
'M_F_DQ<20>'
 '@BASEBOARD_FAB2_LIB.BASEBOARD_FAB2(SCH_1):M_F_DQ'<20>:
 C_SIGNAL='@baseboard_fab2_lib.baseboard_fab2(sch_1):m_f_dq(20)';
NODE_NAME     U5D1 DF71
 '@BASEBOARD_FAB2_LIB.BASEBOARD_FAB2(SCH_1):PAGE28_I172@CHPSET_LIB.SKX_EXT_B(CHIPS)':
 'DDR5_DQ'<20>: CDS_PINID='DDR5_DQ(20)';
NODE_NAME     J4A1 170
 '@BASEBOARD_FAB2_LIB.BASEBOARD_FAB2(SCH_1):PAGE53_I111@MSTR_SCONN.SCONN288_H44441004(CHIPS)':
 'DQ'<21>: CDS_PINID='DQ(21)';
NODE_NAME     J6L1 25
 '@BASEBOARD_FAB2_LIB.BASEBOARD_FAB2(SCH_1):PAGE54_I111@MSTR_SCONN.SCONN288_H44441003(CHIPS)':
 'DQ'<20>: CDS_PINID='DQ(20)';
NET_NAME
'M_F_DQ<21>'
 '@BASEBOARD_FAB2_LIB.BASEBOARD_FAB2(SCH_1):M_F_DQ'<21>:
 C_SIGNAL='@baseboard_fab2_lib.baseboard_fab2(sch_1):m_f_dq(21)';
NODE_NAME     U5D1 DG72
 '@BASEBOARD_FAB2_LIB.BASEBOARD_FAB2(SCH_1):PAGE28_I172@CHPSET_LIB.SKX_EXT_B(CHIPS)':
 'DDR5_DQ'<21>: CDS_PINID='DDR5_DQ(21)';
NODE_NAME     J4A1 25
 '@BASEBOARD_FAB2_LIB.BASEBOARD_FAB2(SCH_1):PAGE53_I111@MSTR_SCONN.SCONN288_H44441004(CHIPS)':
 'DQ'<20>: CDS_PINID='DQ(20)';
NODE_NAME     J6L1 170
 '@BASEBOARD_FAB2_LIB.BASEBOARD_FAB2(SCH_1):PAGE54_I111@MSTR_SCONN.SCONN288_H44441003(CHIPS)':
 'DQ'<21>: CDS_PINID='DQ(21)';
NET_NAME
'M_F_DQ<22>'
 '@BASEBOARD_FAB2_LIB.BASEBOARD_FAB2(SCH_1):M_F_DQ'<22>:
 C_SIGNAL='@baseboard_fab2_lib.baseboard_fab2(sch_1):m_f_dq(22)';
NODE_NAME     U5D1 DK69
 '@BASEBOARD_FAB2_LIB.BASEBOARD_FAB2(SCH_1):PAGE28_I172@CHPSET_LIB.SKX_EXT_B(CHIPS)':
 'DDR5_DQ'<22>: CDS_PINID='DDR5_DQ(22)';
NODE_NAME     J4A1 177
 '@BASEBOARD_FAB2_LIB.BASEBOARD_FAB2(SCH_1):PAGE53_I111@MSTR_SCONN.SCONN288_H44441004(CHIPS)':
 'DQ'<23>: CDS_PINID='DQ(23)';
NODE_NAME     J6L1 32
 '@BASEBOARD_FAB2_LIB.BASEBOARD_FAB2(SCH_1):PAGE54_I111@MSTR_SCONN.SCONN288_H44441003(CHIPS)':
 'DQ'<22>: CDS_PINID='DQ(22)';
NET_NAME
'M_F_DQ<23>'
 '@BASEBOARD_FAB2_LIB.BASEBOARD_FAB2(SCH_1):M_F_DQ'<23>:
 C_SIGNAL='@baseboard_fab2_lib.baseboard_fab2(sch_1):m_f_dq(23)';
NODE_NAME     U5D1 DM71
 '@BASEBOARD_FAB2_LIB.BASEBOARD_FAB2(SCH_1):PAGE28_I172@CHPSET_LIB.SKX_EXT_B(CHIPS)':
 'DDR5_DQ'<23>: CDS_PINID='DDR5_DQ(23)';
NODE_NAME     J4A1 32
 '@BASEBOARD_FAB2_LIB.BASEBOARD_FAB2(SCH_1):PAGE53_I111@MSTR_SCONN.SCONN288_H44441004(CHIPS)':
 'DQ'<22>: CDS_PINID='DQ(22)';
NODE_NAME     J6L1 177
 '@BASEBOARD_FAB2_LIB.BASEBOARD_FAB2(SCH_1):PAGE54_I111@MSTR_SCONN.SCONN288_H44441003(CHIPS)':
 'DQ'<23>: CDS_PINID='DQ(23)';
NET_NAME
'M_F_DQ<24>'
 '@BASEBOARD_FAB2_LIB.BASEBOARD_FAB2(SCH_1):M_F_DQ'<24>:
 C_SIGNAL='@baseboard_fab2_lib.baseboard_fab2(sch_1):m_f_dq(24)';
NODE_NAME     U5D1 CN66
 '@BASEBOARD_FAB2_LIB.BASEBOARD_FAB2(SCH_1):PAGE28_I172@CHPSET_LIB.SKX_EXT_B(CHIPS)':
 'DDR5_DQ'<24>: CDS_PINID='DDR5_DQ(24)';
NODE_NAME     J4A1 183
 '@BASEBOARD_FAB2_LIB.BASEBOARD_FAB2(SCH_1):PAGE53_I111@MSTR_SCONN.SCONN288_H44441004(CHIPS)':
 'DQ'<25>: CDS_PINID='DQ(25)';
NODE_NAME     J6L1 38
 '@BASEBOARD_FAB2_LIB.BASEBOARD_FAB2(SCH_1):PAGE54_I111@MSTR_SCONN.SCONN288_H44441003(CHIPS)':
 'DQ'<24>: CDS_PINID='DQ(24)';
NET_NAME
'M_F_DQ<25>'
 '@BASEBOARD_FAB2_LIB.BASEBOARD_FAB2(SCH_1):M_F_DQ'<25>:
 C_SIGNAL='@baseboard_fab2_lib.baseboard_fab2(sch_1):m_f_dq(25)';
NODE_NAME     U5D1 CU66
 '@BASEBOARD_FAB2_LIB.BASEBOARD_FAB2(SCH_1):PAGE28_I172@CHPSET_LIB.SKX_EXT_B(CHIPS)':
 'DDR5_DQ'<25>: CDS_PINID='DDR5_DQ(25)';
NODE_NAME     J4A1 38
 '@BASEBOARD_FAB2_LIB.BASEBOARD_FAB2(SCH_1):PAGE53_I111@MSTR_SCONN.SCONN288_H44441004(CHIPS)':
 'DQ'<24>: CDS_PINID='DQ(24)';
NODE_NAME     J6L1 183
 '@BASEBOARD_FAB2_LIB.BASEBOARD_FAB2(SCH_1):PAGE54_I111@MSTR_SCONN.SCONN288_H44441003(CHIPS)':
 'DQ'<25>: CDS_PINID='DQ(25)';
NET_NAME
'M_F_DQ<26>'
 '@BASEBOARD_FAB2_LIB.BASEBOARD_FAB2(SCH_1):M_F_DQ'<26>:
 C_SIGNAL='@baseboard_fab2_lib.baseboard_fab2(sch_1):m_f_dq(26)';
NODE_NAME     U5D1 CP63
 '@BASEBOARD_FAB2_LIB.BASEBOARD_FAB2(SCH_1):PAGE28_I172@CHPSET_LIB.SKX_EXT_B(CHIPS)':
 'DDR5_DQ'<26>: CDS_PINID='DDR5_DQ(26)';
NODE_NAME     J4A1 190
 '@BASEBOARD_FAB2_LIB.BASEBOARD_FAB2(SCH_1):PAGE53_I111@MSTR_SCONN.SCONN288_H44441004(CHIPS)':
 'DQ'<27>: CDS_PINID='DQ(27)';
NODE_NAME     J6L1 45
 '@BASEBOARD_FAB2_LIB.BASEBOARD_FAB2(SCH_1):PAGE54_I111@MSTR_SCONN.SCONN288_H44441003(CHIPS)':
 'DQ'<26>: CDS_PINID='DQ(26)';
NET_NAME
'M_F_DQ<27>'
 '@BASEBOARD_FAB2_LIB.BASEBOARD_FAB2(SCH_1):M_F_DQ'<27>:
 C_SIGNAL='@baseboard_fab2_lib.baseboard_fab2(sch_1):m_f_dq(27)';
NODE_NAME     U5D1 CT63
 '@BASEBOARD_FAB2_LIB.BASEBOARD_FAB2(SCH_1):PAGE28_I172@CHPSET_LIB.SKX_EXT_B(CHIPS)':
 'DDR5_DQ'<27>: CDS_PINID='DDR5_DQ(27)';
NODE_NAME     J4A1 45
 '@BASEBOARD_FAB2_LIB.BASEBOARD_FAB2(SCH_1):PAGE53_I111@MSTR_SCONN.SCONN288_H44441004(CHIPS)':
 'DQ'<26>: CDS_PINID='DQ(26)';
NODE_NAME     J6L1 190
 '@BASEBOARD_FAB2_LIB.BASEBOARD_FAB2(SCH_1):PAGE54_I111@MSTR_SCONN.SCONN288_H44441003(CHIPS)':
 'DQ'<27>: CDS_PINID='DQ(27)';
NET_NAME
'M_F_DQ<28>'
 '@BASEBOARD_FAB2_LIB.BASEBOARD_FAB2(SCH_1):M_F_DQ'<28>:
 C_SIGNAL='@baseboard_fab2_lib.baseboard_fab2(sch_1):m_f_dq(28)';
NODE_NAME     U5D1 CP67
 '@BASEBOARD_FAB2_LIB.BASEBOARD_FAB2(SCH_1):PAGE28_I172@CHPSET_LIB.SKX_EXT_B(CHIPS)':
 'DDR5_DQ'<28>: CDS_PINID='DDR5_DQ(28)';
NODE_NAME     J4A1 181
 '@BASEBOARD_FAB2_LIB.BASEBOARD_FAB2(SCH_1):PAGE53_I111@MSTR_SCONN.SCONN288_H44441004(CHIPS)':
 'DQ'<29>: CDS_PINID='DQ(29)';
NODE_NAME     J6L1 36
 '@BASEBOARD_FAB2_LIB.BASEBOARD_FAB2(SCH_1):PAGE54_I111@MSTR_SCONN.SCONN288_H44441003(CHIPS)':
 'DQ'<28>: CDS_PINID='DQ(28)';
NET_NAME
'M_F_DQ<29>'
 '@BASEBOARD_FAB2_LIB.BASEBOARD_FAB2(SCH_1):M_F_DQ'<29>:
 C_SIGNAL='@baseboard_fab2_lib.baseboard_fab2(sch_1):m_f_dq(29)';
NODE_NAME     U5D1 CT67
 '@BASEBOARD_FAB2_LIB.BASEBOARD_FAB2(SCH_1):PAGE28_I172@CHPSET_LIB.SKX_EXT_B(CHIPS)':
 'DDR5_DQ'<29>: CDS_PINID='DDR5_DQ(29)';
NODE_NAME     J4A1 36
 '@BASEBOARD_FAB2_LIB.BASEBOARD_FAB2(SCH_1):PAGE53_I111@MSTR_SCONN.SCONN288_H44441004(CHIPS)':
 'DQ'<28>: CDS_PINID='DQ(28)';
NODE_NAME     J6L1 181
 '@BASEBOARD_FAB2_LIB.BASEBOARD_FAB2(SCH_1):PAGE54_I111@MSTR_SCONN.SCONN288_H44441003(CHIPS)':
 'DQ'<29>: CDS_PINID='DQ(29)';
NET_NAME
'M_F_DQ<2>'
 '@BASEBOARD_FAB2_LIB.BASEBOARD_FAB2(SCH_1):M_F_DQ'<2>:
 C_SIGNAL='@baseboard_fab2_lib.baseboard_fab2(sch_1):m_f_dq(2)';
NODE_NAME     U5D1 CW76
 '@BASEBOARD_FAB2_LIB.BASEBOARD_FAB2(SCH_1):PAGE28_I172@CHPSET_LIB.SKX_EXT_B(CHIPS)':
 'DDR5_DQ'<2>: CDS_PINID='DDR5_DQ(2)';
NODE_NAME     J4A1 157
 '@BASEBOARD_FAB2_LIB.BASEBOARD_FAB2(SCH_1):PAGE53_I111@MSTR_SCONN.SCONN288_H44441004(CHIPS)':
 'DQ'<3>: CDS_PINID='DQ(3)';
NODE_NAME     J6L1 12
 '@BASEBOARD_FAB2_LIB.BASEBOARD_FAB2(SCH_1):PAGE54_I111@MSTR_SCONN.SCONN288_H44441003(CHIPS)':
 'DQ'<2>: CDS_PINID='DQ(2)';
NET_NAME
'M_F_DQ<30>'
 '@BASEBOARD_FAB2_LIB.BASEBOARD_FAB2(SCH_1):M_F_DQ'<30>:
 C_SIGNAL='@baseboard_fab2_lib.baseboard_fab2(sch_1):m_f_dq(30)';
NODE_NAME     U5D1 CN64
 '@BASEBOARD_FAB2_LIB.BASEBOARD_FAB2(SCH_1):PAGE28_I172@CHPSET_LIB.SKX_EXT_B(CHIPS)':
 'DDR5_DQ'<30>: CDS_PINID='DDR5_DQ(30)';
NODE_NAME     J4A1 188
 '@BASEBOARD_FAB2_LIB.BASEBOARD_FAB2(SCH_1):PAGE53_I111@MSTR_SCONN.SCONN288_H44441004(CHIPS)':
 'DQ'<31>: CDS_PINID='DQ(31)';
NODE_NAME     J6L1 43
 '@BASEBOARD_FAB2_LIB.BASEBOARD_FAB2(SCH_1):PAGE54_I111@MSTR_SCONN.SCONN288_H44441003(CHIPS)':
 'DQ'<30>: CDS_PINID='DQ(30)';
NET_NAME
'M_F_DQ<31>'
 '@BASEBOARD_FAB2_LIB.BASEBOARD_FAB2(SCH_1):M_F_DQ'<31>:
 C_SIGNAL='@baseboard_fab2_lib.baseboard_fab2(sch_1):m_f_dq(31)';
NODE_NAME     U5D1 CU64
 '@BASEBOARD_FAB2_LIB.BASEBOARD_FAB2(SCH_1):PAGE28_I172@CHPSET_LIB.SKX_EXT_B(CHIPS)':
 'DDR5_DQ'<31>: CDS_PINID='DDR5_DQ(31)';
NODE_NAME     J4A1 43
 '@BASEBOARD_FAB2_LIB.BASEBOARD_FAB2(SCH_1):PAGE53_I111@MSTR_SCONN.SCONN288_H44441004(CHIPS)':
 'DQ'<30>: CDS_PINID='DQ(30)';
NODE_NAME     J6L1 188
 '@BASEBOARD_FAB2_LIB.BASEBOARD_FAB2(SCH_1):PAGE54_I111@MSTR_SCONN.SCONN288_H44441003(CHIPS)':
 'DQ'<31>: CDS_PINID='DQ(31)';
NET_NAME
'M_F_DQ<32>'
 '@BASEBOARD_FAB2_LIB.BASEBOARD_FAB2(SCH_1):M_F_DQ'<32>:
 C_SIGNAL='@baseboard_fab2_lib.baseboard_fab2(sch_1):m_f_dq(32)';
NODE_NAME     U5D1 DD41
 '@BASEBOARD_FAB2_LIB.BASEBOARD_FAB2(SCH_1):PAGE28_I172@CHPSET_LIB.SKX_EXT_B(CHIPS)':
 'DDR5_DQ'<32>: CDS_PINID='DDR5_DQ(32)';
NODE_NAME     J4A1 242
 '@BASEBOARD_FAB2_LIB.BASEBOARD_FAB2(SCH_1):PAGE53_I111@MSTR_SCONN.SCONN288_H44441004(CHIPS)':
 'DQ'<33>: CDS_PINID='DQ(33)';
NODE_NAME     J6L1 97
 '@BASEBOARD_FAB2_LIB.BASEBOARD_FAB2(SCH_1):PAGE54_I111@MSTR_SCONN.SCONN288_H44441003(CHIPS)':
 'DQ'<32>: CDS_PINID='DQ(32)';
NET_NAME
'M_F_DQ<33>'
 '@BASEBOARD_FAB2_LIB.BASEBOARD_FAB2(SCH_1):M_F_DQ'<33>:
 C_SIGNAL='@baseboard_fab2_lib.baseboard_fab2(sch_1):m_f_dq(33)';
NODE_NAME     U5D1 DG42
 '@BASEBOARD_FAB2_LIB.BASEBOARD_FAB2(SCH_1):PAGE28_I172@CHPSET_LIB.SKX_EXT_B(CHIPS)':
 'DDR5_DQ'<33>: CDS_PINID='DDR5_DQ(33)';
NODE_NAME     J4A1 97
 '@BASEBOARD_FAB2_LIB.BASEBOARD_FAB2(SCH_1):PAGE53_I111@MSTR_SCONN.SCONN288_H44441004(CHIPS)':
 'DQ'<32>: CDS_PINID='DQ(32)';
NODE_NAME     J6L1 242
 '@BASEBOARD_FAB2_LIB.BASEBOARD_FAB2(SCH_1):PAGE54_I111@MSTR_SCONN.SCONN288_H44441003(CHIPS)':
 'DQ'<33>: CDS_PINID='DQ(33)';
NET_NAME
'M_F_DQ<34>'
 '@BASEBOARD_FAB2_LIB.BASEBOARD_FAB2(SCH_1):M_F_DQ'<34>:
 C_SIGNAL='@baseboard_fab2_lib.baseboard_fab2(sch_1):m_f_dq(34)';
NODE_NAME     U5D1 DE38
 '@BASEBOARD_FAB2_LIB.BASEBOARD_FAB2(SCH_1):PAGE28_I172@CHPSET_LIB.SKX_EXT_B(CHIPS)':
 'DDR5_DQ'<34>: CDS_PINID='DDR5_DQ(34)';
NODE_NAME     J4A1 249
 '@BASEBOARD_FAB2_LIB.BASEBOARD_FAB2(SCH_1):PAGE53_I111@MSTR_SCONN.SCONN288_H44441004(CHIPS)':
 'DQ'<35>: CDS_PINID='DQ(35)';
NODE_NAME     J6L1 104
 '@BASEBOARD_FAB2_LIB.BASEBOARD_FAB2(SCH_1):PAGE54_I111@MSTR_SCONN.SCONN288_H44441003(CHIPS)':
 'DQ'<34>: CDS_PINID='DQ(34)';
NET_NAME
'M_F_DQ<35>'
 '@BASEBOARD_FAB2_LIB.BASEBOARD_FAB2(SCH_1):M_F_DQ'<35>:
 C_SIGNAL='@baseboard_fab2_lib.baseboard_fab2(sch_1):m_f_dq(35)';
NODE_NAME     U5D1 DG38
 '@BASEBOARD_FAB2_LIB.BASEBOARD_FAB2(SCH_1):PAGE28_I172@CHPSET_LIB.SKX_EXT_B(CHIPS)':
 'DDR5_DQ'<35>: CDS_PINID='DDR5_DQ(35)';
NODE_NAME     J4A1 104
 '@BASEBOARD_FAB2_LIB.BASEBOARD_FAB2(SCH_1):PAGE53_I111@MSTR_SCONN.SCONN288_H44441004(CHIPS)':
 'DQ'<34>: CDS_PINID='DQ(34)';
NODE_NAME     J6L1 249
 '@BASEBOARD_FAB2_LIB.BASEBOARD_FAB2(SCH_1):PAGE54_I111@MSTR_SCONN.SCONN288_H44441003(CHIPS)':
 'DQ'<35>: CDS_PINID='DQ(35)';
NET_NAME
'M_F_DQ<36>'
 '@BASEBOARD_FAB2_LIB.BASEBOARD_FAB2(SCH_1):M_F_DQ'<36>:
 C_SIGNAL='@baseboard_fab2_lib.baseboard_fab2(sch_1):m_f_dq(36)';
NODE_NAME     U5D1 DA42
 '@BASEBOARD_FAB2_LIB.BASEBOARD_FAB2(SCH_1):PAGE28_I172@CHPSET_LIB.SKX_EXT_B(CHIPS)':
 'DDR5_DQ'<36>: CDS_PINID='DDR5_DQ(36)';
NODE_NAME     J4A1 240
 '@BASEBOARD_FAB2_LIB.BASEBOARD_FAB2(SCH_1):PAGE53_I111@MSTR_SCONN.SCONN288_H44441004(CHIPS)':
 'DQ'<37>: CDS_PINID='DQ(37)';
NODE_NAME     J6L1 95
 '@BASEBOARD_FAB2_LIB.BASEBOARD_FAB2(SCH_1):PAGE54_I111@MSTR_SCONN.SCONN288_H44441003(CHIPS)':
 'DQ'<36>: CDS_PINID='DQ(36)';
NET_NAME
'M_F_DQ<37>'
 '@BASEBOARD_FAB2_LIB.BASEBOARD_FAB2(SCH_1):M_F_DQ'<37>:
 C_SIGNAL='@baseboard_fab2_lib.baseboard_fab2(sch_1):m_f_dq(37)';
NODE_NAME     U5D1 DE42
 '@BASEBOARD_FAB2_LIB.BASEBOARD_FAB2(SCH_1):PAGE28_I172@CHPSET_LIB.SKX_EXT_B(CHIPS)':
 'DDR5_DQ'<37>: CDS_PINID='DDR5_DQ(37)';
NODE_NAME     J4A1 95
 '@BASEBOARD_FAB2_LIB.BASEBOARD_FAB2(SCH_1):PAGE53_I111@MSTR_SCONN.SCONN288_H44441004(CHIPS)':
 'DQ'<36>: CDS_PINID='DQ(36)';
NODE_NAME     J6L1 240
 '@BASEBOARD_FAB2_LIB.BASEBOARD_FAB2(SCH_1):PAGE54_I111@MSTR_SCONN.SCONN288_H44441003(CHIPS)':
 'DQ'<37>: CDS_PINID='DQ(37)';
NET_NAME
'M_F_DQ<38>'
 '@BASEBOARD_FAB2_LIB.BASEBOARD_FAB2(SCH_1):M_F_DQ'<38>:
 C_SIGNAL='@baseboard_fab2_lib.baseboard_fab2(sch_1):m_f_dq(38)';
NODE_NAME     U5D1 DD39
 '@BASEBOARD_FAB2_LIB.BASEBOARD_FAB2(SCH_1):PAGE28_I172@CHPSET_LIB.SKX_EXT_B(CHIPS)':
 'DDR5_DQ'<38>: CDS_PINID='DDR5_DQ(38)';
NODE_NAME     J4A1 247
 '@BASEBOARD_FAB2_LIB.BASEBOARD_FAB2(SCH_1):PAGE53_I111@MSTR_SCONN.SCONN288_H44441004(CHIPS)':
 'DQ'<39>: CDS_PINID='DQ(39)';
NODE_NAME     J6L1 102
 '@BASEBOARD_FAB2_LIB.BASEBOARD_FAB2(SCH_1):PAGE54_I111@MSTR_SCONN.SCONN288_H44441003(CHIPS)':
 'DQ'<38>: CDS_PINID='DQ(38)';
NET_NAME
'M_F_DQ<39>'
 '@BASEBOARD_FAB2_LIB.BASEBOARD_FAB2(SCH_1):M_F_DQ'<39>:
 C_SIGNAL='@baseboard_fab2_lib.baseboard_fab2(sch_1):m_f_dq(39)';
NODE_NAME     U5D1 DH39
 '@BASEBOARD_FAB2_LIB.BASEBOARD_FAB2(SCH_1):PAGE28_I172@CHPSET_LIB.SKX_EXT_B(CHIPS)':
 'DDR5_DQ'<39>: CDS_PINID='DDR5_DQ(39)';
NODE_NAME     J4A1 102
 '@BASEBOARD_FAB2_LIB.BASEBOARD_FAB2(SCH_1):PAGE53_I111@MSTR_SCONN.SCONN288_H44441004(CHIPS)':
 'DQ'<38>: CDS_PINID='DQ(38)';
NODE_NAME     J6L1 247
 '@BASEBOARD_FAB2_LIB.BASEBOARD_FAB2(SCH_1):PAGE54_I111@MSTR_SCONN.SCONN288_H44441003(CHIPS)':
 'DQ'<39>: CDS_PINID='DQ(39)';
NET_NAME
'M_F_DQ<3>'
 '@BASEBOARD_FAB2_LIB.BASEBOARD_FAB2(SCH_1):M_F_DQ'<3>:
 C_SIGNAL='@baseboard_fab2_lib.baseboard_fab2(sch_1):m_f_dq(3)';
NODE_NAME     U5D1 CV77
 '@BASEBOARD_FAB2_LIB.BASEBOARD_FAB2(SCH_1):PAGE28_I172@CHPSET_LIB.SKX_EXT_B(CHIPS)':
 'DDR5_DQ'<3>: CDS_PINID='DDR5_DQ(3)';
NODE_NAME     J4A1 12
 '@BASEBOARD_FAB2_LIB.BASEBOARD_FAB2(SCH_1):PAGE53_I111@MSTR_SCONN.SCONN288_H44441004(CHIPS)':
 'DQ'<2>: CDS_PINID='DQ(2)';
NODE_NAME     J6L1 157
 '@BASEBOARD_FAB2_LIB.BASEBOARD_FAB2(SCH_1):PAGE54_I111@MSTR_SCONN.SCONN288_H44441003(CHIPS)':
 'DQ'<3>: CDS_PINID='DQ(3)';
NET_NAME
'M_F_DQ<40>'
 '@BASEBOARD_FAB2_LIB.BASEBOARD_FAB2(SCH_1):M_F_DQ'<40>:
 C_SIGNAL='@baseboard_fab2_lib.baseboard_fab2(sch_1):m_f_dq(40)';
NODE_NAME     U5D1 DF33
 '@BASEBOARD_FAB2_LIB.BASEBOARD_FAB2(SCH_1):PAGE28_I172@CHPSET_LIB.SKX_EXT_B(CHIPS)':
 'DDR5_DQ'<40>: CDS_PINID='DDR5_DQ(40)';
NODE_NAME     J4A1 253
 '@BASEBOARD_FAB2_LIB.BASEBOARD_FAB2(SCH_1):PAGE53_I111@MSTR_SCONN.SCONN288_H44441004(CHIPS)':
 'DQ'<41>: CDS_PINID='DQ(41)';
NODE_NAME     J6L1 108
 '@BASEBOARD_FAB2_LIB.BASEBOARD_FAB2(SCH_1):PAGE54_I111@MSTR_SCONN.SCONN288_H44441003(CHIPS)':
 'DQ'<40>: CDS_PINID='DQ(40)';
NET_NAME
'M_F_DQ<41>'
 '@BASEBOARD_FAB2_LIB.BASEBOARD_FAB2(SCH_1):M_F_DQ'<41>:
 C_SIGNAL='@baseboard_fab2_lib.baseboard_fab2(sch_1):m_f_dq(41)';
NODE_NAME     U5D1 DK33
 '@BASEBOARD_FAB2_LIB.BASEBOARD_FAB2(SCH_1):PAGE28_I172@CHPSET_LIB.SKX_EXT_B(CHIPS)':
 'DDR5_DQ'<41>: CDS_PINID='DDR5_DQ(41)';
NODE_NAME     J4A1 108
 '@BASEBOARD_FAB2_LIB.BASEBOARD_FAB2(SCH_1):PAGE53_I111@MSTR_SCONN.SCONN288_H44441004(CHIPS)':
 'DQ'<40>: CDS_PINID='DQ(40)';
NODE_NAME     J6L1 253
 '@BASEBOARD_FAB2_LIB.BASEBOARD_FAB2(SCH_1):PAGE54_I111@MSTR_SCONN.SCONN288_H44441003(CHIPS)':
 'DQ'<41>: CDS_PINID='DQ(41)';
NET_NAME
'M_F_DQ<42>'
 '@BASEBOARD_FAB2_LIB.BASEBOARD_FAB2(SCH_1):M_F_DQ'<42>:
 C_SIGNAL='@baseboard_fab2_lib.baseboard_fab2(sch_1):m_f_dq(42)';
NODE_NAME     U5D1 DG30
 '@BASEBOARD_FAB2_LIB.BASEBOARD_FAB2(SCH_1):PAGE28_I172@CHPSET_LIB.SKX_EXT_B(CHIPS)':
 'DDR5_DQ'<42>: CDS_PINID='DDR5_DQ(42)';
NODE_NAME     J4A1 260
 '@BASEBOARD_FAB2_LIB.BASEBOARD_FAB2(SCH_1):PAGE53_I111@MSTR_SCONN.SCONN288_H44441004(CHIPS)':
 'DQ'<43>: CDS_PINID='DQ(43)';
NODE_NAME     J6L1 115
 '@BASEBOARD_FAB2_LIB.BASEBOARD_FAB2(SCH_1):PAGE54_I111@MSTR_SCONN.SCONN288_H44441003(CHIPS)':
 'DQ'<42>: CDS_PINID='DQ(42)';
NET_NAME
'M_F_DQ<43>'
 '@BASEBOARD_FAB2_LIB.BASEBOARD_FAB2(SCH_1):M_F_DQ'<43>:
 C_SIGNAL='@baseboard_fab2_lib.baseboard_fab2(sch_1):m_f_dq(43)';
NODE_NAME     U5D1 DJ30
 '@BASEBOARD_FAB2_LIB.BASEBOARD_FAB2(SCH_1):PAGE28_I172@CHPSET_LIB.SKX_EXT_B(CHIPS)':
 'DDR5_DQ'<43>: CDS_PINID='DDR5_DQ(43)';
NODE_NAME     J4A1 115
 '@BASEBOARD_FAB2_LIB.BASEBOARD_FAB2(SCH_1):PAGE53_I111@MSTR_SCONN.SCONN288_H44441004(CHIPS)':
 'DQ'<42>: CDS_PINID='DQ(42)';
NODE_NAME     J6L1 260
 '@BASEBOARD_FAB2_LIB.BASEBOARD_FAB2(SCH_1):PAGE54_I111@MSTR_SCONN.SCONN288_H44441003(CHIPS)':
 'DQ'<43>: CDS_PINID='DQ(43)';
NET_NAME
'M_F_DQ<44>'
 '@BASEBOARD_FAB2_LIB.BASEBOARD_FAB2(SCH_1):M_F_DQ'<44>:
 C_SIGNAL='@baseboard_fab2_lib.baseboard_fab2(sch_1):m_f_dq(44)';
NODE_NAME     U5D1 DG34
 '@BASEBOARD_FAB2_LIB.BASEBOARD_FAB2(SCH_1):PAGE28_I172@CHPSET_LIB.SKX_EXT_B(CHIPS)':
 'DDR5_DQ'<44>: CDS_PINID='DDR5_DQ(44)';
NODE_NAME     J4A1 251
 '@BASEBOARD_FAB2_LIB.BASEBOARD_FAB2(SCH_1):PAGE53_I111@MSTR_SCONN.SCONN288_H44441004(CHIPS)':
 'DQ'<45>: CDS_PINID='DQ(45)';
NODE_NAME     J6L1 106
 '@BASEBOARD_FAB2_LIB.BASEBOARD_FAB2(SCH_1):PAGE54_I111@MSTR_SCONN.SCONN288_H44441003(CHIPS)':
 'DQ'<44>: CDS_PINID='DQ(44)';
NET_NAME
'M_F_DQ<45>'
 '@BASEBOARD_FAB2_LIB.BASEBOARD_FAB2(SCH_1):M_F_DQ'<45>:
 C_SIGNAL='@baseboard_fab2_lib.baseboard_fab2(sch_1):m_f_dq(45)';
NODE_NAME     U5D1 DJ34
 '@BASEBOARD_FAB2_LIB.BASEBOARD_FAB2(SCH_1):PAGE28_I172@CHPSET_LIB.SKX_EXT_B(CHIPS)':
 'DDR5_DQ'<45>: CDS_PINID='DDR5_DQ(45)';
NODE_NAME     J4A1 106
 '@BASEBOARD_FAB2_LIB.BASEBOARD_FAB2(SCH_1):PAGE53_I111@MSTR_SCONN.SCONN288_H44441004(CHIPS)':
 'DQ'<44>: CDS_PINID='DQ(44)';
NODE_NAME     J6L1 251
 '@BASEBOARD_FAB2_LIB.BASEBOARD_FAB2(SCH_1):PAGE54_I111@MSTR_SCONN.SCONN288_H44441003(CHIPS)':
 'DQ'<45>: CDS_PINID='DQ(45)';
NET_NAME
'M_F_DQ<46>'
 '@BASEBOARD_FAB2_LIB.BASEBOARD_FAB2(SCH_1):M_F_DQ'<46>:
 C_SIGNAL='@baseboard_fab2_lib.baseboard_fab2(sch_1):m_f_dq(46)';
NODE_NAME     U5D1 DF31
 '@BASEBOARD_FAB2_LIB.BASEBOARD_FAB2(SCH_1):PAGE28_I172@CHPSET_LIB.SKX_EXT_B(CHIPS)':
 'DDR5_DQ'<46>: CDS_PINID='DDR5_DQ(46)';
NODE_NAME     J4A1 258
 '@BASEBOARD_FAB2_LIB.BASEBOARD_FAB2(SCH_1):PAGE53_I111@MSTR_SCONN.SCONN288_H44441004(CHIPS)':
 'DQ'<47>: CDS_PINID='DQ(47)';
NODE_NAME     J6L1 113
 '@BASEBOARD_FAB2_LIB.BASEBOARD_FAB2(SCH_1):PAGE54_I111@MSTR_SCONN.SCONN288_H44441003(CHIPS)':
 'DQ'<46>: CDS_PINID='DQ(46)';
NET_NAME
'M_F_DQ<47>'
 '@BASEBOARD_FAB2_LIB.BASEBOARD_FAB2(SCH_1):M_F_DQ'<47>:
 C_SIGNAL='@baseboard_fab2_lib.baseboard_fab2(sch_1):m_f_dq(47)';
NODE_NAME     U5D1 DK31
 '@BASEBOARD_FAB2_LIB.BASEBOARD_FAB2(SCH_1):PAGE28_I172@CHPSET_LIB.SKX_EXT_B(CHIPS)':
 'DDR5_DQ'<47>: CDS_PINID='DDR5_DQ(47)';
NODE_NAME     J4A1 113
 '@BASEBOARD_FAB2_LIB.BASEBOARD_FAB2(SCH_1):PAGE53_I111@MSTR_SCONN.SCONN288_H44441004(CHIPS)':
 'DQ'<46>: CDS_PINID='DQ(46)';
NODE_NAME     J6L1 258
 '@BASEBOARD_FAB2_LIB.BASEBOARD_FAB2(SCH_1):PAGE54_I111@MSTR_SCONN.SCONN288_H44441003(CHIPS)':
 'DQ'<47>: CDS_PINID='DQ(47)';
NET_NAME
'M_F_DQ<48>'
 '@BASEBOARD_FAB2_LIB.BASEBOARD_FAB2(SCH_1):M_F_DQ'<48>:
 C_SIGNAL='@baseboard_fab2_lib.baseboard_fab2(sch_1):m_f_dq(48)';
NODE_NAME     U5D1 CW36
 '@BASEBOARD_FAB2_LIB.BASEBOARD_FAB2(SCH_1):PAGE28_I172@CHPSET_LIB.SKX_EXT_B(CHIPS)':
 'DDR5_DQ'<48>: CDS_PINID='DDR5_DQ(48)';
NODE_NAME     J4A1 264
 '@BASEBOARD_FAB2_LIB.BASEBOARD_FAB2(SCH_1):PAGE53_I111@MSTR_SCONN.SCONN288_H44441004(CHIPS)':
 'DQ'<49>: CDS_PINID='DQ(49)';
NODE_NAME     J6L1 119
 '@BASEBOARD_FAB2_LIB.BASEBOARD_FAB2(SCH_1):PAGE54_I111@MSTR_SCONN.SCONN288_H44441003(CHIPS)':
 'DQ'<48>: CDS_PINID='DQ(48)';
NET_NAME
'M_F_DQ<49>'
 '@BASEBOARD_FAB2_LIB.BASEBOARD_FAB2(SCH_1):M_F_DQ'<49>:
 C_SIGNAL='@baseboard_fab2_lib.baseboard_fab2(sch_1):m_f_dq(49)';
NODE_NAME     U5D1 DC36
 '@BASEBOARD_FAB2_LIB.BASEBOARD_FAB2(SCH_1):PAGE28_I172@CHPSET_LIB.SKX_EXT_B(CHIPS)':
 'DDR5_DQ'<49>: CDS_PINID='DDR5_DQ(49)';
NODE_NAME     J4A1 119
 '@BASEBOARD_FAB2_LIB.BASEBOARD_FAB2(SCH_1):PAGE53_I111@MSTR_SCONN.SCONN288_H44441004(CHIPS)':
 'DQ'<48>: CDS_PINID='DQ(48)';
NODE_NAME     J6L1 264
 '@BASEBOARD_FAB2_LIB.BASEBOARD_FAB2(SCH_1):PAGE54_I111@MSTR_SCONN.SCONN288_H44441003(CHIPS)':
 'DQ'<49>: CDS_PINID='DQ(49)';
NET_NAME
'M_F_DQ<4>'
 '@BASEBOARD_FAB2_LIB.BASEBOARD_FAB2(SCH_1):M_F_DQ'<4>:
 C_SIGNAL='@baseboard_fab2_lib.baseboard_fab2(sch_1):m_f_dq(4)';
NODE_NAME     U5D1 CN74
 '@BASEBOARD_FAB2_LIB.BASEBOARD_FAB2(SCH_1):PAGE28_I172@CHPSET_LIB.SKX_EXT_B(CHIPS)':
 'DDR5_DQ'<4>: CDS_PINID='DDR5_DQ(4)';
NODE_NAME     J4A1 148
 '@BASEBOARD_FAB2_LIB.BASEBOARD_FAB2(SCH_1):PAGE53_I111@MSTR_SCONN.SCONN288_H44441004(CHIPS)':
 'DQ'<5>: CDS_PINID='DQ(5)';
NODE_NAME     J6L1 3
 '@BASEBOARD_FAB2_LIB.BASEBOARD_FAB2(SCH_1):PAGE54_I111@MSTR_SCONN.SCONN288_H44441003(CHIPS)':
 'DQ'<4>: CDS_PINID='DQ(4)';
NET_NAME
'M_F_DQ<50>'
 '@BASEBOARD_FAB2_LIB.BASEBOARD_FAB2(SCH_1):M_F_DQ'<50>:
 C_SIGNAL='@baseboard_fab2_lib.baseboard_fab2(sch_1):m_f_dq(50)';
NODE_NAME     U5D1 CY33
 '@BASEBOARD_FAB2_LIB.BASEBOARD_FAB2(SCH_1):PAGE28_I172@CHPSET_LIB.SKX_EXT_B(CHIPS)':
 'DDR5_DQ'<50>: CDS_PINID='DDR5_DQ(50)';
NODE_NAME     J4A1 271
 '@BASEBOARD_FAB2_LIB.BASEBOARD_FAB2(SCH_1):PAGE53_I111@MSTR_SCONN.SCONN288_H44441004(CHIPS)':
 'DQ'<51>: CDS_PINID='DQ(51)';
NODE_NAME     J6L1 126
 '@BASEBOARD_FAB2_LIB.BASEBOARD_FAB2(SCH_1):PAGE54_I111@MSTR_SCONN.SCONN288_H44441003(CHIPS)':
 'DQ'<50>: CDS_PINID='DQ(50)';
NET_NAME
'M_F_DQ<51>'
 '@BASEBOARD_FAB2_LIB.BASEBOARD_FAB2(SCH_1):M_F_DQ'<51>:
 C_SIGNAL='@baseboard_fab2_lib.baseboard_fab2(sch_1):m_f_dq(51)';
NODE_NAME     U5D1 DB33
 '@BASEBOARD_FAB2_LIB.BASEBOARD_FAB2(SCH_1):PAGE28_I172@CHPSET_LIB.SKX_EXT_B(CHIPS)':
 'DDR5_DQ'<51>: CDS_PINID='DDR5_DQ(51)';
NODE_NAME     J4A1 126
 '@BASEBOARD_FAB2_LIB.BASEBOARD_FAB2(SCH_1):PAGE53_I111@MSTR_SCONN.SCONN288_H44441004(CHIPS)':
 'DQ'<50>: CDS_PINID='DQ(50)';
NODE_NAME     J6L1 271
 '@BASEBOARD_FAB2_LIB.BASEBOARD_FAB2(SCH_1):PAGE54_I111@MSTR_SCONN.SCONN288_H44441003(CHIPS)':
 'DQ'<51>: CDS_PINID='DQ(51)';
NET_NAME
'M_F_DQ<52>'
 '@BASEBOARD_FAB2_LIB.BASEBOARD_FAB2(SCH_1):M_F_DQ'<52>:
 C_SIGNAL='@baseboard_fab2_lib.baseboard_fab2(sch_1):m_f_dq(52)';
NODE_NAME     U5D1 CY37
 '@BASEBOARD_FAB2_LIB.BASEBOARD_FAB2(SCH_1):PAGE28_I172@CHPSET_LIB.SKX_EXT_B(CHIPS)':
 'DDR5_DQ'<52>: CDS_PINID='DDR5_DQ(52)';
NODE_NAME     J4A1 262
 '@BASEBOARD_FAB2_LIB.BASEBOARD_FAB2(SCH_1):PAGE53_I111@MSTR_SCONN.SCONN288_H44441004(CHIPS)':
 'DQ'<53>: CDS_PINID='DQ(53)';
NODE_NAME     J6L1 117
 '@BASEBOARD_FAB2_LIB.BASEBOARD_FAB2(SCH_1):PAGE54_I111@MSTR_SCONN.SCONN288_H44441003(CHIPS)':
 'DQ'<52>: CDS_PINID='DQ(52)';
NET_NAME
'M_F_DQ<53>'
 '@BASEBOARD_FAB2_LIB.BASEBOARD_FAB2(SCH_1):M_F_DQ'<53>:
 C_SIGNAL='@baseboard_fab2_lib.baseboard_fab2(sch_1):m_f_dq(53)';
NODE_NAME     U5D1 DB37
 '@BASEBOARD_FAB2_LIB.BASEBOARD_FAB2(SCH_1):PAGE28_I172@CHPSET_LIB.SKX_EXT_B(CHIPS)':
 'DDR5_DQ'<53>: CDS_PINID='DDR5_DQ(53)';
NODE_NAME     J4A1 117
 '@BASEBOARD_FAB2_LIB.BASEBOARD_FAB2(SCH_1):PAGE53_I111@MSTR_SCONN.SCONN288_H44441004(CHIPS)':
 'DQ'<52>: CDS_PINID='DQ(52)';
NODE_NAME     J6L1 262
 '@BASEBOARD_FAB2_LIB.BASEBOARD_FAB2(SCH_1):PAGE54_I111@MSTR_SCONN.SCONN288_H44441003(CHIPS)':
 'DQ'<53>: CDS_PINID='DQ(53)';
NET_NAME
'M_F_DQ<54>'
 '@BASEBOARD_FAB2_LIB.BASEBOARD_FAB2(SCH_1):M_F_DQ'<54>:
 C_SIGNAL='@baseboard_fab2_lib.baseboard_fab2(sch_1):m_f_dq(54)';
NODE_NAME     U5D1 CW34
 '@BASEBOARD_FAB2_LIB.BASEBOARD_FAB2(SCH_1):PAGE28_I172@CHPSET_LIB.SKX_EXT_B(CHIPS)':
 'DDR5_DQ'<54>: CDS_PINID='DDR5_DQ(54)';
NODE_NAME     J4A1 269
 '@BASEBOARD_FAB2_LIB.BASEBOARD_FAB2(SCH_1):PAGE53_I111@MSTR_SCONN.SCONN288_H44441004(CHIPS)':
 'DQ'<55>: CDS_PINID='DQ(55)';
NODE_NAME     J6L1 124
 '@BASEBOARD_FAB2_LIB.BASEBOARD_FAB2(SCH_1):PAGE54_I111@MSTR_SCONN.SCONN288_H44441003(CHIPS)':
 'DQ'<54>: CDS_PINID='DQ(54)';
NET_NAME
'M_F_DQ<55>'
 '@BASEBOARD_FAB2_LIB.BASEBOARD_FAB2(SCH_1):M_F_DQ'<55>:
 C_SIGNAL='@baseboard_fab2_lib.baseboard_fab2(sch_1):m_f_dq(55)';
NODE_NAME     U5D1 DC34
 '@BASEBOARD_FAB2_LIB.BASEBOARD_FAB2(SCH_1):PAGE28_I172@CHPSET_LIB.SKX_EXT_B(CHIPS)':
 'DDR5_DQ'<55>: CDS_PINID='DDR5_DQ(55)';
NODE_NAME     J4A1 124
 '@BASEBOARD_FAB2_LIB.BASEBOARD_FAB2(SCH_1):PAGE53_I111@MSTR_SCONN.SCONN288_H44441004(CHIPS)':
 'DQ'<54>: CDS_PINID='DQ(54)';
NODE_NAME     J6L1 269
 '@BASEBOARD_FAB2_LIB.BASEBOARD_FAB2(SCH_1):PAGE54_I111@MSTR_SCONN.SCONN288_H44441003(CHIPS)':
 'DQ'<55>: CDS_PINID='DQ(55)';
NET_NAME
'M_F_DQ<56>'
 '@BASEBOARD_FAB2_LIB.BASEBOARD_FAB2(SCH_1):M_F_DQ'<56>:
 C_SIGNAL='@baseboard_fab2_lib.baseboard_fab2(sch_1):m_f_dq(56)';
NODE_NAME     U5D1 CW30
 '@BASEBOARD_FAB2_LIB.BASEBOARD_FAB2(SCH_1):PAGE28_I172@CHPSET_LIB.SKX_EXT_B(CHIPS)':
 'DDR5_DQ'<56>: CDS_PINID='DDR5_DQ(56)';
NODE_NAME     J4A1 275
 '@BASEBOARD_FAB2_LIB.BASEBOARD_FAB2(SCH_1):PAGE53_I111@MSTR_SCONN.SCONN288_H44441004(CHIPS)':
 'DQ'<57>: CDS_PINID='DQ(57)';
NODE_NAME     J6L1 130
 '@BASEBOARD_FAB2_LIB.BASEBOARD_FAB2(SCH_1):PAGE54_I111@MSTR_SCONN.SCONN288_H44441003(CHIPS)':
 'DQ'<56>: CDS_PINID='DQ(56)';
NET_NAME
'M_F_DQ<57>'
 '@BASEBOARD_FAB2_LIB.BASEBOARD_FAB2(SCH_1):M_F_DQ'<57>:
 C_SIGNAL='@baseboard_fab2_lib.baseboard_fab2(sch_1):m_f_dq(57)';
NODE_NAME     U5D1 DC30
 '@BASEBOARD_FAB2_LIB.BASEBOARD_FAB2(SCH_1):PAGE28_I172@CHPSET_LIB.SKX_EXT_B(CHIPS)':
 'DDR5_DQ'<57>: CDS_PINID='DDR5_DQ(57)';
NODE_NAME     J4A1 130
 '@BASEBOARD_FAB2_LIB.BASEBOARD_FAB2(SCH_1):PAGE53_I111@MSTR_SCONN.SCONN288_H44441004(CHIPS)':
 'DQ'<56>: CDS_PINID='DQ(56)';
NODE_NAME     J6L1 275
 '@BASEBOARD_FAB2_LIB.BASEBOARD_FAB2(SCH_1):PAGE54_I111@MSTR_SCONN.SCONN288_H44441003(CHIPS)':
 'DQ'<57>: CDS_PINID='DQ(57)';
NET_NAME
'M_F_DQ<58>'
 '@BASEBOARD_FAB2_LIB.BASEBOARD_FAB2(SCH_1):M_F_DQ'<58>:
 C_SIGNAL='@baseboard_fab2_lib.baseboard_fab2(sch_1):m_f_dq(58)';
NODE_NAME     U5D1 CY27
 '@BASEBOARD_FAB2_LIB.BASEBOARD_FAB2(SCH_1):PAGE28_I172@CHPSET_LIB.SKX_EXT_B(CHIPS)':
 'DDR5_DQ'<58>: CDS_PINID='DDR5_DQ(58)';
NODE_NAME     J4A1 282
 '@BASEBOARD_FAB2_LIB.BASEBOARD_FAB2(SCH_1):PAGE53_I111@MSTR_SCONN.SCONN288_H44441004(CHIPS)':
 'DQ'<59>: CDS_PINID='DQ(59)';
NODE_NAME     J6L1 137
 '@BASEBOARD_FAB2_LIB.BASEBOARD_FAB2(SCH_1):PAGE54_I111@MSTR_SCONN.SCONN288_H44441003(CHIPS)':
 'DQ'<58>: CDS_PINID='DQ(58)';
NET_NAME
'M_F_DQ<59>'
 '@BASEBOARD_FAB2_LIB.BASEBOARD_FAB2(SCH_1):M_F_DQ'<59>:
 C_SIGNAL='@baseboard_fab2_lib.baseboard_fab2(sch_1):m_f_dq(59)';
NODE_NAME     U5D1 DB27
 '@BASEBOARD_FAB2_LIB.BASEBOARD_FAB2(SCH_1):PAGE28_I172@CHPSET_LIB.SKX_EXT_B(CHIPS)':
 'DDR5_DQ'<59>: CDS_PINID='DDR5_DQ(59)';
NODE_NAME     J4A1 137
 '@BASEBOARD_FAB2_LIB.BASEBOARD_FAB2(SCH_1):PAGE53_I111@MSTR_SCONN.SCONN288_H44441004(CHIPS)':
 'DQ'<58>: CDS_PINID='DQ(58)';
NODE_NAME     J6L1 282
 '@BASEBOARD_FAB2_LIB.BASEBOARD_FAB2(SCH_1):PAGE54_I111@MSTR_SCONN.SCONN288_H44441003(CHIPS)':
 'DQ'<59>: CDS_PINID='DQ(59)';
NET_NAME
'M_F_DQ<5>'
 '@BASEBOARD_FAB2_LIB.BASEBOARD_FAB2(SCH_1):M_F_DQ'<5>:
 C_SIGNAL='@baseboard_fab2_lib.baseboard_fab2(sch_1):m_f_dq(5)';
NODE_NAME     U5D1 CM75
 '@BASEBOARD_FAB2_LIB.BASEBOARD_FAB2(SCH_1):PAGE28_I172@CHPSET_LIB.SKX_EXT_B(CHIPS)':
 'DDR5_DQ'<5>: CDS_PINID='DDR5_DQ(5)';
NODE_NAME     J4A1 3
 '@BASEBOARD_FAB2_LIB.BASEBOARD_FAB2(SCH_1):PAGE53_I111@MSTR_SCONN.SCONN288_H44441004(CHIPS)':
 'DQ'<4>: CDS_PINID='DQ(4)';
NODE_NAME     J6L1 148
 '@BASEBOARD_FAB2_LIB.BASEBOARD_FAB2(SCH_1):PAGE54_I111@MSTR_SCONN.SCONN288_H44441003(CHIPS)':
 'DQ'<5>: CDS_PINID='DQ(5)';
NET_NAME
'M_F_DQ<60>'
 '@BASEBOARD_FAB2_LIB.BASEBOARD_FAB2(SCH_1):M_F_DQ'<60>:
 C_SIGNAL='@baseboard_fab2_lib.baseboard_fab2(sch_1):m_f_dq(60)';
NODE_NAME     U5D1 CY31
 '@BASEBOARD_FAB2_LIB.BASEBOARD_FAB2(SCH_1):PAGE28_I172@CHPSET_LIB.SKX_EXT_B(CHIPS)':
 'DDR5_DQ'<60>: CDS_PINID='DDR5_DQ(60)';
NODE_NAME     J4A1 273
 '@BASEBOARD_FAB2_LIB.BASEBOARD_FAB2(SCH_1):PAGE53_I111@MSTR_SCONN.SCONN288_H44441004(CHIPS)':
 'DQ'<61>: CDS_PINID='DQ(61)';
NODE_NAME     J6L1 128
 '@BASEBOARD_FAB2_LIB.BASEBOARD_FAB2(SCH_1):PAGE54_I111@MSTR_SCONN.SCONN288_H44441003(CHIPS)':
 'DQ'<60>: CDS_PINID='DQ(60)';
NET_NAME
'M_F_DQ<61>'
 '@BASEBOARD_FAB2_LIB.BASEBOARD_FAB2(SCH_1):M_F_DQ'<61>:
 C_SIGNAL='@baseboard_fab2_lib.baseboard_fab2(sch_1):m_f_dq(61)';
NODE_NAME     U5D1 DB31
 '@BASEBOARD_FAB2_LIB.BASEBOARD_FAB2(SCH_1):PAGE28_I172@CHPSET_LIB.SKX_EXT_B(CHIPS)':
 'DDR5_DQ'<61>: CDS_PINID='DDR5_DQ(61)';
NODE_NAME     J4A1 128
 '@BASEBOARD_FAB2_LIB.BASEBOARD_FAB2(SCH_1):PAGE53_I111@MSTR_SCONN.SCONN288_H44441004(CHIPS)':
 'DQ'<60>: CDS_PINID='DQ(60)';
NODE_NAME     J6L1 273
 '@BASEBOARD_FAB2_LIB.BASEBOARD_FAB2(SCH_1):PAGE54_I111@MSTR_SCONN.SCONN288_H44441003(CHIPS)':
 'DQ'<61>: CDS_PINID='DQ(61)';
NET_NAME
'M_F_DQ<62>'
 '@BASEBOARD_FAB2_LIB.BASEBOARD_FAB2(SCH_1):M_F_DQ'<62>:
 C_SIGNAL='@baseboard_fab2_lib.baseboard_fab2(sch_1):m_f_dq(62)';
NODE_NAME     U5D1 CW28
 '@BASEBOARD_FAB2_LIB.BASEBOARD_FAB2(SCH_1):PAGE28_I172@CHPSET_LIB.SKX_EXT_B(CHIPS)':
 'DDR5_DQ'<62>: CDS_PINID='DDR5_DQ(62)';
NODE_NAME     J4A1 280
 '@BASEBOARD_FAB2_LIB.BASEBOARD_FAB2(SCH_1):PAGE53_I111@MSTR_SCONN.SCONN288_H44441004(CHIPS)':
 'DQ'<63>: CDS_PINID='DQ(63)';
NODE_NAME     J6L1 135
 '@BASEBOARD_FAB2_LIB.BASEBOARD_FAB2(SCH_1):PAGE54_I111@MSTR_SCONN.SCONN288_H44441003(CHIPS)':
 'DQ'<62>: CDS_PINID='DQ(62)';
NET_NAME
'M_F_DQ<63>'
 '@BASEBOARD_FAB2_LIB.BASEBOARD_FAB2(SCH_1):M_F_DQ'<63>:
 C_SIGNAL='@baseboard_fab2_lib.baseboard_fab2(sch_1):m_f_dq(63)';
NODE_NAME     U5D1 DC28
 '@BASEBOARD_FAB2_LIB.BASEBOARD_FAB2(SCH_1):PAGE28_I172@CHPSET_LIB.SKX_EXT_B(CHIPS)':
 'DDR5_DQ'<63>: CDS_PINID='DDR5_DQ(63)';
NODE_NAME     J4A1 135
 '@BASEBOARD_FAB2_LIB.BASEBOARD_FAB2(SCH_1):PAGE53_I111@MSTR_SCONN.SCONN288_H44441004(CHIPS)':
 'DQ'<62>: CDS_PINID='DQ(62)';
NODE_NAME     J6L1 280
 '@BASEBOARD_FAB2_LIB.BASEBOARD_FAB2(SCH_1):PAGE54_I111@MSTR_SCONN.SCONN288_H44441003(CHIPS)':
 'DQ'<63>: CDS_PINID='DQ(63)';
NET_NAME
'M_F_DQ<6>'
 '@BASEBOARD_FAB2_LIB.BASEBOARD_FAB2(SCH_1):M_F_DQ'<6>:
 C_SIGNAL='@baseboard_fab2_lib.baseboard_fab2(sch_1):m_f_dq(6)';
NODE_NAME     U5D1 CV75
 '@BASEBOARD_FAB2_LIB.BASEBOARD_FAB2(SCH_1):PAGE28_I172@CHPSET_LIB.SKX_EXT_B(CHIPS)':
 'DDR5_DQ'<6>: CDS_PINID='DDR5_DQ(6)';
NODE_NAME     J4A1 155
 '@BASEBOARD_FAB2_LIB.BASEBOARD_FAB2(SCH_1):PAGE53_I111@MSTR_SCONN.SCONN288_H44441004(CHIPS)':
 'DQ'<7>: CDS_PINID='DQ(7)';
NODE_NAME     J6L1 10
 '@BASEBOARD_FAB2_LIB.BASEBOARD_FAB2(SCH_1):PAGE54_I111@MSTR_SCONN.SCONN288_H44441003(CHIPS)':
 'DQ'<6>: CDS_PINID='DQ(6)';
NET_NAME
'M_F_DQ<7>'
 '@BASEBOARD_FAB2_LIB.BASEBOARD_FAB2(SCH_1):M_F_DQ'<7>:
 C_SIGNAL='@baseboard_fab2_lib.baseboard_fab2(sch_1):m_f_dq(7)';
NODE_NAME     U5D1 CT77
 '@BASEBOARD_FAB2_LIB.BASEBOARD_FAB2(SCH_1):PAGE28_I172@CHPSET_LIB.SKX_EXT_B(CHIPS)':
 'DDR5_DQ'<7>: CDS_PINID='DDR5_DQ(7)';
NODE_NAME     J4A1 10
 '@BASEBOARD_FAB2_LIB.BASEBOARD_FAB2(SCH_1):PAGE53_I111@MSTR_SCONN.SCONN288_H44441004(CHIPS)':
 'DQ'<6>: CDS_PINID='DQ(6)';
NODE_NAME     J6L1 155
 '@BASEBOARD_FAB2_LIB.BASEBOARD_FAB2(SCH_1):PAGE54_I111@MSTR_SCONN.SCONN288_H44441003(CHIPS)':
 'DQ'<7>: CDS_PINID='DQ(7)';
NET_NAME
'M_F_DQ<8>'
 '@BASEBOARD_FAB2_LIB.BASEBOARD_FAB2(SCH_1):M_F_DQ'<8>:
 C_SIGNAL='@baseboard_fab2_lib.baseboard_fab2(sch_1):m_f_dq(8)';
NODE_NAME     U5D1 DE74
 '@BASEBOARD_FAB2_LIB.BASEBOARD_FAB2(SCH_1):PAGE28_I172@CHPSET_LIB.SKX_EXT_B(CHIPS)':
 'DDR5_DQ'<8>: CDS_PINID='DDR5_DQ(8)';
NODE_NAME     J4A1 161
 '@BASEBOARD_FAB2_LIB.BASEBOARD_FAB2(SCH_1):PAGE53_I111@MSTR_SCONN.SCONN288_H44441004(CHIPS)':
 'DQ'<9>: CDS_PINID='DQ(9)';
NODE_NAME     J6L1 16
 '@BASEBOARD_FAB2_LIB.BASEBOARD_FAB2(SCH_1):PAGE54_I111@MSTR_SCONN.SCONN288_H44441003(CHIPS)':
 'DQ'<8>: CDS_PINID='DQ(8)';
NET_NAME
'M_F_DQ<9>'
 '@BASEBOARD_FAB2_LIB.BASEBOARD_FAB2(SCH_1):M_F_DQ'<9>:
 C_SIGNAL='@baseboard_fab2_lib.baseboard_fab2(sch_1):m_f_dq(9)';
NODE_NAME     U5D1 DC76
 '@BASEBOARD_FAB2_LIB.BASEBOARD_FAB2(SCH_1):PAGE28_I172@CHPSET_LIB.SKX_EXT_B(CHIPS)':
 'DDR5_DQ'<9>: CDS_PINID='DDR5_DQ(9)';
NODE_NAME     J4A1 16
 '@BASEBOARD_FAB2_LIB.BASEBOARD_FAB2(SCH_1):PAGE53_I111@MSTR_SCONN.SCONN288_H44441004(CHIPS)':
 'DQ'<8>: CDS_PINID='DQ(8)';
NODE_NAME     J6L1 161
 '@BASEBOARD_FAB2_LIB.BASEBOARD_FAB2(SCH_1):PAGE54_I111@MSTR_SCONN.SCONN288_H44441003(CHIPS)':
 'DQ'<9>: CDS_PINID='DQ(9)';
NET_NAME
'M_F_DQS_DN<0>'
 '@BASEBOARD_FAB2_LIB.BASEBOARD_FAB2(SCH_1):M_F_DQS_DN'<0>:
 C_SIGNAL='@baseboard_fab2_lib.baseboard_fab2(sch_1):m_f_dqs_dn(0)';
NODE_NAME     U5D1 CP77
 '@BASEBOARD_FAB2_LIB.BASEBOARD_FAB2(SCH_1):PAGE28_I172@CHPSET_LIB.SKX_EXT_B(CHIPS)':
 'DDR5_DQS_DN'<0>: CDS_PINID='DDR5_DQS_DN(0)';
NODE_NAME     J4A1 152
 '@BASEBOARD_FAB2_LIB.BASEBOARD_FAB2(SCH_1):PAGE53_I66@MSTR_SCONN.SCONN288_H44441004(CHIPS)':
 'DQS0N': CDS_PINID='DQS0N';
NODE_NAME     J6L1 152
 '@BASEBOARD_FAB2_LIB.BASEBOARD_FAB2(SCH_1):PAGE54_I66@MSTR_SCONN.SCONN288_H44441003(CHIPS)':
 'DQS0N': CDS_PINID='DQS0N';
NET_NAME
'M_F_DQS_DN<10>'
 '@BASEBOARD_FAB2_LIB.BASEBOARD_FAB2(SCH_1):M_F_DQS_DN'<10>:
 C_SIGNAL='@baseboard_fab2_lib.baseboard_fab2(sch_1):m_f_dqs_dn(10)';
NODE_NAME     U5D1 DF75
 '@BASEBOARD_FAB2_LIB.BASEBOARD_FAB2(SCH_1):PAGE28_I172@CHPSET_LIB.SKX_EXT_B(CHIPS)':
 'DDR5_DQS_DN'<10>: CDS_PINID='DDR5_DQS_DN(10)';
NODE_NAME     J4A1 19
 '@BASEBOARD_FAB2_LIB.BASEBOARD_FAB2(SCH_1):PAGE53_I66@MSTR_SCONN.SCONN288_H44441004(CHIPS)':
 'DQS10N': CDS_PINID='DQS10N';
NODE_NAME     J6L1 19
 '@BASEBOARD_FAB2_LIB.BASEBOARD_FAB2(SCH_1):PAGE54_I66@MSTR_SCONN.SCONN288_H44441003(CHIPS)':
 'DQS10N': CDS_PINID='DQS10N';
NET_NAME
'M_F_DQS_DN<11>'
 '@BASEBOARD_FAB2_LIB.BASEBOARD_FAB2(SCH_1):M_F_DQS_DN'<11>:
 C_SIGNAL='@baseboard_fab2_lib.baseboard_fab2(sch_1):m_f_dqs_dn(11)';
NODE_NAME     U5D1 DJ70
 '@BASEBOARD_FAB2_LIB.BASEBOARD_FAB2(SCH_1):PAGE28_I172@CHPSET_LIB.SKX_EXT_B(CHIPS)':
 'DDR5_DQS_DN'<11>: CDS_PINID='DDR5_DQS_DN(11)';
NODE_NAME     J4A1 30
 '@BASEBOARD_FAB2_LIB.BASEBOARD_FAB2(SCH_1):PAGE53_I66@MSTR_SCONN.SCONN288_H44441004(CHIPS)':
 'DQS11N': CDS_PINID='DQS11N';
NODE_NAME     J6L1 30
 '@BASEBOARD_FAB2_LIB.BASEBOARD_FAB2(SCH_1):PAGE54_I66@MSTR_SCONN.SCONN288_H44441003(CHIPS)':
 'DQS11N': CDS_PINID='DQS11N';
NET_NAME
'M_F_DQS_DN<12>'
 '@BASEBOARD_FAB2_LIB.BASEBOARD_FAB2(SCH_1):M_F_DQS_DN'<12>:
 C_SIGNAL='@baseboard_fab2_lib.baseboard_fab2(sch_1):m_f_dqs_dn(12)';
NODE_NAME     U5D1 CP65
 '@BASEBOARD_FAB2_LIB.BASEBOARD_FAB2(SCH_1):PAGE28_I172@CHPSET_LIB.SKX_EXT_B(CHIPS)':
 'DDR5_DQS_DN'<12>: CDS_PINID='DDR5_DQS_DN(12)';
NODE_NAME     J4A1 41
 '@BASEBOARD_FAB2_LIB.BASEBOARD_FAB2(SCH_1):PAGE53_I66@MSTR_SCONN.SCONN288_H44441004(CHIPS)':
 'DQS12N': CDS_PINID='DQS12N';
NODE_NAME     J6L1 41
 '@BASEBOARD_FAB2_LIB.BASEBOARD_FAB2(SCH_1):PAGE54_I66@MSTR_SCONN.SCONN288_H44441003(CHIPS)':
 'DQS12N': CDS_PINID='DQS12N';
NET_NAME
'M_F_DQS_DN<13>'
 '@BASEBOARD_FAB2_LIB.BASEBOARD_FAB2(SCH_1):M_F_DQS_DN'<13>:
 C_SIGNAL='@baseboard_fab2_lib.baseboard_fab2(sch_1):m_f_dqs_dn(13)';
NODE_NAME     U5D1 DE40
 '@BASEBOARD_FAB2_LIB.BASEBOARD_FAB2(SCH_1):PAGE28_I172@CHPSET_LIB.SKX_EXT_B(CHIPS)':
 'DDR5_DQS_DN'<13>: CDS_PINID='DDR5_DQS_DN(13)';
NODE_NAME     J4A1 100
 '@BASEBOARD_FAB2_LIB.BASEBOARD_FAB2(SCH_1):PAGE53_I66@MSTR_SCONN.SCONN288_H44441004(CHIPS)':
 'DQS13N': CDS_PINID='DQS13N';
NODE_NAME     J6L1 100
 '@BASEBOARD_FAB2_LIB.BASEBOARD_FAB2(SCH_1):PAGE54_I66@MSTR_SCONN.SCONN288_H44441003(CHIPS)':
 'DQS13N': CDS_PINID='DQS13N';
NET_NAME
'M_F_DQS_DN<14>'
 '@BASEBOARD_FAB2_LIB.BASEBOARD_FAB2(SCH_1):M_F_DQS_DN'<14>:
 C_SIGNAL='@baseboard_fab2_lib.baseboard_fab2(sch_1):m_f_dqs_dn(14)';
NODE_NAME     U5D1 DG32
 '@BASEBOARD_FAB2_LIB.BASEBOARD_FAB2(SCH_1):PAGE28_I172@CHPSET_LIB.SKX_EXT_B(CHIPS)':
 'DDR5_DQS_DN'<14>: CDS_PINID='DDR5_DQS_DN(14)';
NODE_NAME     J4A1 111
 '@BASEBOARD_FAB2_LIB.BASEBOARD_FAB2(SCH_1):PAGE53_I66@MSTR_SCONN.SCONN288_H44441004(CHIPS)':
 'DQS14N': CDS_PINID='DQS14N';
NODE_NAME     J6L1 111
 '@BASEBOARD_FAB2_LIB.BASEBOARD_FAB2(SCH_1):PAGE54_I66@MSTR_SCONN.SCONN288_H44441003(CHIPS)':
 'DQS14N': CDS_PINID='DQS14N';
NET_NAME
'M_F_DQS_DN<15>'
 '@BASEBOARD_FAB2_LIB.BASEBOARD_FAB2(SCH_1):M_F_DQS_DN'<15>:
 C_SIGNAL='@baseboard_fab2_lib.baseboard_fab2(sch_1):m_f_dqs_dn(15)';
NODE_NAME     U5D1 CY35
 '@BASEBOARD_FAB2_LIB.BASEBOARD_FAB2(SCH_1):PAGE28_I172@CHPSET_LIB.SKX_EXT_B(CHIPS)':
 'DDR5_DQS_DN'<15>: CDS_PINID='DDR5_DQS_DN(15)';
NODE_NAME     J4A1 122
 '@BASEBOARD_FAB2_LIB.BASEBOARD_FAB2(SCH_1):PAGE53_I66@MSTR_SCONN.SCONN288_H44441004(CHIPS)':
 'DQS15N': CDS_PINID='DQS15N';
NODE_NAME     J6L1 122
 '@BASEBOARD_FAB2_LIB.BASEBOARD_FAB2(SCH_1):PAGE54_I66@MSTR_SCONN.SCONN288_H44441003(CHIPS)':
 'DQS15N': CDS_PINID='DQS15N';
NET_NAME
'M_F_DQS_DN<16>'
 '@BASEBOARD_FAB2_LIB.BASEBOARD_FAB2(SCH_1):M_F_DQS_DN'<16>:
 C_SIGNAL='@baseboard_fab2_lib.baseboard_fab2(sch_1):m_f_dqs_dn(16)';
NODE_NAME     U5D1 CY29
 '@BASEBOARD_FAB2_LIB.BASEBOARD_FAB2(SCH_1):PAGE28_I172@CHPSET_LIB.SKX_EXT_B(CHIPS)':
 'DDR5_DQS_DN'<16>: CDS_PINID='DDR5_DQS_DN(16)';
NODE_NAME     J4A1 133
 '@BASEBOARD_FAB2_LIB.BASEBOARD_FAB2(SCH_1):PAGE53_I66@MSTR_SCONN.SCONN288_H44441004(CHIPS)':
 'DQS16N': CDS_PINID='DQS16N';
NODE_NAME     J6L1 133
 '@BASEBOARD_FAB2_LIB.BASEBOARD_FAB2(SCH_1):PAGE54_I66@MSTR_SCONN.SCONN288_H44441003(CHIPS)':
 'DQS16N': CDS_PINID='DQS16N';
NET_NAME
'M_F_DQS_DN<17>'
 '@BASEBOARD_FAB2_LIB.BASEBOARD_FAB2(SCH_1):M_F_DQS_DN'<17>:
 C_SIGNAL='@baseboard_fab2_lib.baseboard_fab2(sch_1):m_f_dqs_dn(17)';
NODE_NAME     U5D1 CJ70
 '@BASEBOARD_FAB2_LIB.BASEBOARD_FAB2(SCH_1):PAGE28_I172@CHPSET_LIB.SKX_EXT_B(CHIPS)':
 'DDR5_DQS_DN'<17>: CDS_PINID='DDR5_DQS_DN(17)';
NODE_NAME     J4A1 52
 '@BASEBOARD_FAB2_LIB.BASEBOARD_FAB2(SCH_1):PAGE53_I66@MSTR_SCONN.SCONN288_H44441004(CHIPS)':
 'DQS17N': CDS_PINID='DQS17N';
NODE_NAME     J6L1 52
 '@BASEBOARD_FAB2_LIB.BASEBOARD_FAB2(SCH_1):PAGE54_I66@MSTR_SCONN.SCONN288_H44441003(CHIPS)':
 'DQS17N': CDS_PINID='DQS17N';
NET_NAME
'M_F_DQS_DN<1>'
 '@BASEBOARD_FAB2_LIB.BASEBOARD_FAB2(SCH_1):M_F_DQS_DN'<1>:
 C_SIGNAL='@baseboard_fab2_lib.baseboard_fab2(sch_1):m_f_dqs_dn(1)';
NODE_NAME     U5D1 DD77
 '@BASEBOARD_FAB2_LIB.BASEBOARD_FAB2(SCH_1):PAGE28_I172@CHPSET_LIB.SKX_EXT_B(CHIPS)':
 'DDR5_DQS_DN'<1>: CDS_PINID='DDR5_DQS_DN(1)';
NODE_NAME     J4A1 163
 '@BASEBOARD_FAB2_LIB.BASEBOARD_FAB2(SCH_1):PAGE53_I66@MSTR_SCONN.SCONN288_H44441004(CHIPS)':
 'DQS1N': CDS_PINID='DQS1N';
NODE_NAME     J6L1 163
 '@BASEBOARD_FAB2_LIB.BASEBOARD_FAB2(SCH_1):PAGE54_I66@MSTR_SCONN.SCONN288_H44441003(CHIPS)':
 'DQS1N': CDS_PINID='DQS1N';
NET_NAME
'M_F_DQS_DN<2>'
 '@BASEBOARD_FAB2_LIB.BASEBOARD_FAB2(SCH_1):M_F_DQS_DN'<2>:
 C_SIGNAL='@baseboard_fab2_lib.baseboard_fab2(sch_1):m_f_dqs_dn(2)';
NODE_NAME     U5D1 DL72
 '@BASEBOARD_FAB2_LIB.BASEBOARD_FAB2(SCH_1):PAGE28_I172@CHPSET_LIB.SKX_EXT_B(CHIPS)':
 'DDR5_DQS_DN'<2>: CDS_PINID='DDR5_DQS_DN(2)';
NODE_NAME     J4A1 174
 '@BASEBOARD_FAB2_LIB.BASEBOARD_FAB2(SCH_1):PAGE53_I66@MSTR_SCONN.SCONN288_H44441004(CHIPS)':
 'DQS2N': CDS_PINID='DQS2N';
NODE_NAME     J6L1 174
 '@BASEBOARD_FAB2_LIB.BASEBOARD_FAB2(SCH_1):PAGE54_I66@MSTR_SCONN.SCONN288_H44441003(CHIPS)':
 'DQS2N': CDS_PINID='DQS2N';
NET_NAME
'M_F_DQS_DN<3>'
 '@BASEBOARD_FAB2_LIB.BASEBOARD_FAB2(SCH_1):M_F_DQS_DN'<3>:
 C_SIGNAL='@baseboard_fab2_lib.baseboard_fab2(sch_1):m_f_dqs_dn(3)';
NODE_NAME     U5D1 CV65
 '@BASEBOARD_FAB2_LIB.BASEBOARD_FAB2(SCH_1):PAGE28_I172@CHPSET_LIB.SKX_EXT_B(CHIPS)':
 'DDR5_DQS_DN'<3>: CDS_PINID='DDR5_DQS_DN(3)';
NODE_NAME     J4A1 185
 '@BASEBOARD_FAB2_LIB.BASEBOARD_FAB2(SCH_1):PAGE53_I66@MSTR_SCONN.SCONN288_H44441004(CHIPS)':
 'DQS3N': CDS_PINID='DQS3N';
NODE_NAME     J6L1 185
 '@BASEBOARD_FAB2_LIB.BASEBOARD_FAB2(SCH_1):PAGE54_I66@MSTR_SCONN.SCONN288_H44441003(CHIPS)':
 'DQS3N': CDS_PINID='DQS3N';
NET_NAME
'M_F_DQS_DN<4>'
 '@BASEBOARD_FAB2_LIB.BASEBOARD_FAB2(SCH_1):M_F_DQS_DN'<4>:
 C_SIGNAL='@baseboard_fab2_lib.baseboard_fab2(sch_1):m_f_dqs_dn(4)';
NODE_NAME     U5D1 DG40
 '@BASEBOARD_FAB2_LIB.BASEBOARD_FAB2(SCH_1):PAGE28_I172@CHPSET_LIB.SKX_EXT_B(CHIPS)':
 'DDR5_DQS_DN'<4>: CDS_PINID='DDR5_DQS_DN(4)';
NODE_NAME     J4A1 244
 '@BASEBOARD_FAB2_LIB.BASEBOARD_FAB2(SCH_1):PAGE53_I66@MSTR_SCONN.SCONN288_H44441004(CHIPS)':
 'DQS4N': CDS_PINID='DQS4N';
NODE_NAME     J6L1 244
 '@BASEBOARD_FAB2_LIB.BASEBOARD_FAB2(SCH_1):PAGE54_I66@MSTR_SCONN.SCONN288_H44441003(CHIPS)':
 'DQS4N': CDS_PINID='DQS4N';
NET_NAME
'M_F_DQS_DN<5>'
 '@BASEBOARD_FAB2_LIB.BASEBOARD_FAB2(SCH_1):M_F_DQS_DN'<5>:
 C_SIGNAL='@baseboard_fab2_lib.baseboard_fab2(sch_1):m_f_dqs_dn(5)';
NODE_NAME     U5D1 DL32
 '@BASEBOARD_FAB2_LIB.BASEBOARD_FAB2(SCH_1):PAGE28_I172@CHPSET_LIB.SKX_EXT_B(CHIPS)':
 'DDR5_DQS_DN'<5>: CDS_PINID='DDR5_DQS_DN(5)';
NODE_NAME     J4A1 255
 '@BASEBOARD_FAB2_LIB.BASEBOARD_FAB2(SCH_1):PAGE53_I66@MSTR_SCONN.SCONN288_H44441004(CHIPS)':
 'DQS5N': CDS_PINID='DQS5N';
NODE_NAME     J6L1 255
 '@BASEBOARD_FAB2_LIB.BASEBOARD_FAB2(SCH_1):PAGE54_I66@MSTR_SCONN.SCONN288_H44441003(CHIPS)':
 'DQS5N': CDS_PINID='DQS5N';
NET_NAME
'M_F_DQS_DN<6>'
 '@BASEBOARD_FAB2_LIB.BASEBOARD_FAB2(SCH_1):M_F_DQS_DN'<6>:
 C_SIGNAL='@baseboard_fab2_lib.baseboard_fab2(sch_1):m_f_dqs_dn(6)';
NODE_NAME     U5D1 DD35
 '@BASEBOARD_FAB2_LIB.BASEBOARD_FAB2(SCH_1):PAGE28_I172@CHPSET_LIB.SKX_EXT_B(CHIPS)':
 'DDR5_DQS_DN'<6>: CDS_PINID='DDR5_DQS_DN(6)';
NODE_NAME     J4A1 266
 '@BASEBOARD_FAB2_LIB.BASEBOARD_FAB2(SCH_1):PAGE53_I66@MSTR_SCONN.SCONN288_H44441004(CHIPS)':
 'DQS6N': CDS_PINID='DQS6N';
NODE_NAME     J6L1 266
 '@BASEBOARD_FAB2_LIB.BASEBOARD_FAB2(SCH_1):PAGE54_I66@MSTR_SCONN.SCONN288_H44441003(CHIPS)':
 'DQS6N': CDS_PINID='DQS6N';
NET_NAME
'M_F_DQS_DN<7>'
 '@BASEBOARD_FAB2_LIB.BASEBOARD_FAB2(SCH_1):M_F_DQS_DN'<7>:
 C_SIGNAL='@baseboard_fab2_lib.baseboard_fab2(sch_1):m_f_dqs_dn(7)';
NODE_NAME     U5D1 DD29
 '@BASEBOARD_FAB2_LIB.BASEBOARD_FAB2(SCH_1):PAGE28_I172@CHPSET_LIB.SKX_EXT_B(CHIPS)':
 'DDR5_DQS_DN'<7>: CDS_PINID='DDR5_DQS_DN(7)';
NODE_NAME     J4A1 277
 '@BASEBOARD_FAB2_LIB.BASEBOARD_FAB2(SCH_1):PAGE53_I66@MSTR_SCONN.SCONN288_H44441004(CHIPS)':
 'DQS7N': CDS_PINID='DQS7N';
NODE_NAME     J6L1 277
 '@BASEBOARD_FAB2_LIB.BASEBOARD_FAB2(SCH_1):PAGE54_I66@MSTR_SCONN.SCONN288_H44441003(CHIPS)':
 'DQS7N': CDS_PINID='DQS7N';
NET_NAME
'M_F_DQS_DN<8>'
 '@BASEBOARD_FAB2_LIB.BASEBOARD_FAB2(SCH_1):M_F_DQS_DN'<8>:
 C_SIGNAL='@baseboard_fab2_lib.baseboard_fab2(sch_1):m_f_dqs_dn(8)';
NODE_NAME     U5D1 CN70
 '@BASEBOARD_FAB2_LIB.BASEBOARD_FAB2(SCH_1):PAGE28_I172@CHPSET_LIB.SKX_EXT_B(CHIPS)':
 'DDR5_DQS_DN'<8>: CDS_PINID='DDR5_DQS_DN(8)';
NODE_NAME     J4A1 196
 '@BASEBOARD_FAB2_LIB.BASEBOARD_FAB2(SCH_1):PAGE53_I66@MSTR_SCONN.SCONN288_H44441004(CHIPS)':
 'DQS8N': CDS_PINID='DQS8N';
NODE_NAME     J6L1 196
 '@BASEBOARD_FAB2_LIB.BASEBOARD_FAB2(SCH_1):PAGE54_I66@MSTR_SCONN.SCONN288_H44441003(CHIPS)':
 'DQS8N': CDS_PINID='DQS8N';
NET_NAME
'M_F_DQS_DN<9>'
 '@BASEBOARD_FAB2_LIB.BASEBOARD_FAB2(SCH_1):M_F_DQS_DN'<9>:
 C_SIGNAL='@baseboard_fab2_lib.baseboard_fab2(sch_1):m_f_dqs_dn(9)';
NODE_NAME     U5D1 CT75
 '@BASEBOARD_FAB2_LIB.BASEBOARD_FAB2(SCH_1):PAGE28_I172@CHPSET_LIB.SKX_EXT_B(CHIPS)':
 'DDR5_DQS_DN'<9>: CDS_PINID='DDR5_DQS_DN(9)';
NODE_NAME     J4A1 8
 '@BASEBOARD_FAB2_LIB.BASEBOARD_FAB2(SCH_1):PAGE53_I66@MSTR_SCONN.SCONN288_H44441004(CHIPS)':
 'DQS9N': CDS_PINID='DQS9N';
NODE_NAME     J6L1 8
 '@BASEBOARD_FAB2_LIB.BASEBOARD_FAB2(SCH_1):PAGE54_I66@MSTR_SCONN.SCONN288_H44441003(CHIPS)':
 'DQS9N': CDS_PINID='DQS9N';
NET_NAME
'M_F_DQS_DP<0>'
 '@BASEBOARD_FAB2_LIB.BASEBOARD_FAB2(SCH_1):M_F_DQS_DP'<0>:
 C_SIGNAL='@baseboard_fab2_lib.baseboard_fab2(sch_1):m_f_dqs_dp(0)';
NODE_NAME     U5D1 CR76
 '@BASEBOARD_FAB2_LIB.BASEBOARD_FAB2(SCH_1):PAGE28_I172@CHPSET_LIB.SKX_EXT_B(CHIPS)':
 'DDR5_DQS_DP'<0>: CDS_PINID='DDR5_DQS_DP(0)';
NODE_NAME     J4A1 153
 '@BASEBOARD_FAB2_LIB.BASEBOARD_FAB2(SCH_1):PAGE53_I66@MSTR_SCONN.SCONN288_H44441004(CHIPS)':
 'DQS0P': CDS_PINID='DQS0P';
NODE_NAME     J6L1 153
 '@BASEBOARD_FAB2_LIB.BASEBOARD_FAB2(SCH_1):PAGE54_I66@MSTR_SCONN.SCONN288_H44441003(CHIPS)':
 'DQS0P': CDS_PINID='DQS0P';
NET_NAME
'M_F_DQS_DP<10>'
 '@BASEBOARD_FAB2_LIB.BASEBOARD_FAB2(SCH_1):M_F_DQS_DP'<10>:
 C_SIGNAL='@baseboard_fab2_lib.baseboard_fab2(sch_1):m_f_dqs_dp(10)';
NODE_NAME     U5D1 DG74
 '@BASEBOARD_FAB2_LIB.BASEBOARD_FAB2(SCH_1):PAGE28_I172@CHPSET_LIB.SKX_EXT_B(CHIPS)':
 'DDR5_DQS_DP'<10>: CDS_PINID='DDR5_DQS_DP(10)';
NODE_NAME     J4A1 18
 '@BASEBOARD_FAB2_LIB.BASEBOARD_FAB2(SCH_1):PAGE53_I66@MSTR_SCONN.SCONN288_H44441004(CHIPS)':
 'DQS10P': CDS_PINID='DQS10P';
NODE_NAME     J6L1 18
 '@BASEBOARD_FAB2_LIB.BASEBOARD_FAB2(SCH_1):PAGE54_I66@MSTR_SCONN.SCONN288_H44441003(CHIPS)':
 'DQS10P': CDS_PINID='DQS10P';
NET_NAME
'M_F_DQS_DP<11>'
 '@BASEBOARD_FAB2_LIB.BASEBOARD_FAB2(SCH_1):M_F_DQS_DP'<11>:
 C_SIGNAL='@baseboard_fab2_lib.baseboard_fab2(sch_1):m_f_dqs_dp(11)';
NODE_NAME     U5D1 DH69
 '@BASEBOARD_FAB2_LIB.BASEBOARD_FAB2(SCH_1):PAGE28_I172@CHPSET_LIB.SKX_EXT_B(CHIPS)':
 'DDR5_DQS_DP'<11>: CDS_PINID='DDR5_DQS_DP(11)';
NODE_NAME     J4A1 29
 '@BASEBOARD_FAB2_LIB.BASEBOARD_FAB2(SCH_1):PAGE53_I66@MSTR_SCONN.SCONN288_H44441004(CHIPS)':
 'DQS11P': CDS_PINID='DQS11P';
NODE_NAME     J6L1 29
 '@BASEBOARD_FAB2_LIB.BASEBOARD_FAB2(SCH_1):PAGE54_I66@MSTR_SCONN.SCONN288_H44441003(CHIPS)':
 'DQS11P': CDS_PINID='DQS11P';
NET_NAME
'M_F_DQS_DP<12>'
 '@BASEBOARD_FAB2_LIB.BASEBOARD_FAB2(SCH_1):M_F_DQS_DP'<12>:
 C_SIGNAL='@baseboard_fab2_lib.baseboard_fab2(sch_1):m_f_dqs_dp(12)';
NODE_NAME     U5D1 CM65
 '@BASEBOARD_FAB2_LIB.BASEBOARD_FAB2(SCH_1):PAGE28_I172@CHPSET_LIB.SKX_EXT_B(CHIPS)':
 'DDR5_DQS_DP'<12>: CDS_PINID='DDR5_DQS_DP(12)';
NODE_NAME     J4A1 40
 '@BASEBOARD_FAB2_LIB.BASEBOARD_FAB2(SCH_1):PAGE53_I66@MSTR_SCONN.SCONN288_H44441004(CHIPS)':
 'DQS12P': CDS_PINID='DQS12P';
NODE_NAME     J6L1 40
 '@BASEBOARD_FAB2_LIB.BASEBOARD_FAB2(SCH_1):PAGE54_I66@MSTR_SCONN.SCONN288_H44441003(CHIPS)':
 'DQS12P': CDS_PINID='DQS12P';
NET_NAME
'M_F_DQS_DP<13>'
 '@BASEBOARD_FAB2_LIB.BASEBOARD_FAB2(SCH_1):M_F_DQS_DP'<13>:
 C_SIGNAL='@baseboard_fab2_lib.baseboard_fab2(sch_1):m_f_dqs_dp(13)';
NODE_NAME     U5D1 DC40
 '@BASEBOARD_FAB2_LIB.BASEBOARD_FAB2(SCH_1):PAGE28_I172@CHPSET_LIB.SKX_EXT_B(CHIPS)':
 'DDR5_DQS_DP'<13>: CDS_PINID='DDR5_DQS_DP(13)';
NODE_NAME     J4A1 99
 '@BASEBOARD_FAB2_LIB.BASEBOARD_FAB2(SCH_1):PAGE53_I66@MSTR_SCONN.SCONN288_H44441004(CHIPS)':
 'DQS13P': CDS_PINID='DQS13P';
NODE_NAME     J6L1 99
 '@BASEBOARD_FAB2_LIB.BASEBOARD_FAB2(SCH_1):PAGE54_I66@MSTR_SCONN.SCONN288_H44441003(CHIPS)':
 'DQS13P': CDS_PINID='DQS13P';
NET_NAME
'M_F_DQS_DP<14>'
 '@BASEBOARD_FAB2_LIB.BASEBOARD_FAB2(SCH_1):M_F_DQS_DP'<14>:
 C_SIGNAL='@baseboard_fab2_lib.baseboard_fab2(sch_1):m_f_dqs_dp(14)';
NODE_NAME     U5D1 DE32
 '@BASEBOARD_FAB2_LIB.BASEBOARD_FAB2(SCH_1):PAGE28_I172@CHPSET_LIB.SKX_EXT_B(CHIPS)':
 'DDR5_DQS_DP'<14>: CDS_PINID='DDR5_DQS_DP(14)';
NODE_NAME     J4A1 110
 '@BASEBOARD_FAB2_LIB.BASEBOARD_FAB2(SCH_1):PAGE53_I66@MSTR_SCONN.SCONN288_H44441004(CHIPS)':
 'DQS14P': CDS_PINID='DQS14P';
NODE_NAME     J6L1 110
 '@BASEBOARD_FAB2_LIB.BASEBOARD_FAB2(SCH_1):PAGE54_I66@MSTR_SCONN.SCONN288_H44441003(CHIPS)':
 'DQS14P': CDS_PINID='DQS14P';
NET_NAME
'M_F_DQS_DP<15>'
 '@BASEBOARD_FAB2_LIB.BASEBOARD_FAB2(SCH_1):M_F_DQS_DP'<15>:
 C_SIGNAL='@baseboard_fab2_lib.baseboard_fab2(sch_1):m_f_dqs_dp(15)';
NODE_NAME     U5D1 CV35
 '@BASEBOARD_FAB2_LIB.BASEBOARD_FAB2(SCH_1):PAGE28_I172@CHPSET_LIB.SKX_EXT_B(CHIPS)':
 'DDR5_DQS_DP'<15>: CDS_PINID='DDR5_DQS_DP(15)';
NODE_NAME     J4A1 121
 '@BASEBOARD_FAB2_LIB.BASEBOARD_FAB2(SCH_1):PAGE53_I66@MSTR_SCONN.SCONN288_H44441004(CHIPS)':
 'DQS15P': CDS_PINID='DQS15P';
NODE_NAME     J6L1 121
 '@BASEBOARD_FAB2_LIB.BASEBOARD_FAB2(SCH_1):PAGE54_I66@MSTR_SCONN.SCONN288_H44441003(CHIPS)':
 'DQS15P': CDS_PINID='DQS15P';
NET_NAME
'M_F_DQS_DP<16>'
 '@BASEBOARD_FAB2_LIB.BASEBOARD_FAB2(SCH_1):M_F_DQS_DP'<16>:
 C_SIGNAL='@baseboard_fab2_lib.baseboard_fab2(sch_1):m_f_dqs_dp(16)';
NODE_NAME     U5D1 CV29
 '@BASEBOARD_FAB2_LIB.BASEBOARD_FAB2(SCH_1):PAGE28_I172@CHPSET_LIB.SKX_EXT_B(CHIPS)':
 'DDR5_DQS_DP'<16>: CDS_PINID='DDR5_DQS_DP(16)';
NODE_NAME     J4A1 132
 '@BASEBOARD_FAB2_LIB.BASEBOARD_FAB2(SCH_1):PAGE53_I66@MSTR_SCONN.SCONN288_H44441004(CHIPS)':
 'DQS16P': CDS_PINID='DQS16P';
NODE_NAME     J6L1 132
 '@BASEBOARD_FAB2_LIB.BASEBOARD_FAB2(SCH_1):PAGE54_I66@MSTR_SCONN.SCONN288_H44441003(CHIPS)':
 'DQS16P': CDS_PINID='DQS16P';
NET_NAME
'M_F_DQS_DP<17>'
 '@BASEBOARD_FAB2_LIB.BASEBOARD_FAB2(SCH_1):M_F_DQS_DP'<17>:
 C_SIGNAL='@baseboard_fab2_lib.baseboard_fab2(sch_1):m_f_dqs_dp(17)';
NODE_NAME     U5D1 CG70
 '@BASEBOARD_FAB2_LIB.BASEBOARD_FAB2(SCH_1):PAGE28_I172@CHPSET_LIB.SKX_EXT_B(CHIPS)':
 'DDR5_DQS_DP'<17>: CDS_PINID='DDR5_DQS_DP(17)';
NODE_NAME     J4A1 51
 '@BASEBOARD_FAB2_LIB.BASEBOARD_FAB2(SCH_1):PAGE53_I66@MSTR_SCONN.SCONN288_H44441004(CHIPS)':
 'DQS17P': CDS_PINID='DQS17P';
NODE_NAME     J6L1 51
 '@BASEBOARD_FAB2_LIB.BASEBOARD_FAB2(SCH_1):PAGE54_I66@MSTR_SCONN.SCONN288_H44441003(CHIPS)':
 'DQS17P': CDS_PINID='DQS17P';
NET_NAME
'M_F_DQS_DP<1>'
 '@BASEBOARD_FAB2_LIB.BASEBOARD_FAB2(SCH_1):M_F_DQS_DP'<1>:
 C_SIGNAL='@baseboard_fab2_lib.baseboard_fab2(sch_1):m_f_dqs_dp(1)';
NODE_NAME     U5D1 DE76
 '@BASEBOARD_FAB2_LIB.BASEBOARD_FAB2(SCH_1):PAGE28_I172@CHPSET_LIB.SKX_EXT_B(CHIPS)':
 'DDR5_DQS_DP'<1>: CDS_PINID='DDR5_DQS_DP(1)';
NODE_NAME     J4A1 164
 '@BASEBOARD_FAB2_LIB.BASEBOARD_FAB2(SCH_1):PAGE53_I66@MSTR_SCONN.SCONN288_H44441004(CHIPS)':
 'DQS1P': CDS_PINID='DQS1P';
NODE_NAME     J6L1 164
 '@BASEBOARD_FAB2_LIB.BASEBOARD_FAB2(SCH_1):PAGE54_I66@MSTR_SCONN.SCONN288_H44441003(CHIPS)':
 'DQS1P': CDS_PINID='DQS1P';
NET_NAME
'M_F_DQS_DP<2>'
 '@BASEBOARD_FAB2_LIB.BASEBOARD_FAB2(SCH_1):M_F_DQS_DP'<2>:
 C_SIGNAL='@baseboard_fab2_lib.baseboard_fab2(sch_1):m_f_dqs_dp(2)';
NODE_NAME     U5D1 DK71
 '@BASEBOARD_FAB2_LIB.BASEBOARD_FAB2(SCH_1):PAGE28_I172@CHPSET_LIB.SKX_EXT_B(CHIPS)':
 'DDR5_DQS_DP'<2>: CDS_PINID='DDR5_DQS_DP(2)';
NODE_NAME     J4A1 175
 '@BASEBOARD_FAB2_LIB.BASEBOARD_FAB2(SCH_1):PAGE53_I66@MSTR_SCONN.SCONN288_H44441004(CHIPS)':
 'DQS2P': CDS_PINID='DQS2P';
NODE_NAME     J6L1 175
 '@BASEBOARD_FAB2_LIB.BASEBOARD_FAB2(SCH_1):PAGE54_I66@MSTR_SCONN.SCONN288_H44441003(CHIPS)':
 'DQS2P': CDS_PINID='DQS2P';
NET_NAME
'M_F_DQS_DP<3>'
 '@BASEBOARD_FAB2_LIB.BASEBOARD_FAB2(SCH_1):M_F_DQS_DP'<3>:
 C_SIGNAL='@baseboard_fab2_lib.baseboard_fab2(sch_1):m_f_dqs_dp(3)';
NODE_NAME     U5D1 CT65
 '@BASEBOARD_FAB2_LIB.BASEBOARD_FAB2(SCH_1):PAGE28_I172@CHPSET_LIB.SKX_EXT_B(CHIPS)':
 'DDR5_DQS_DP'<3>: CDS_PINID='DDR5_DQS_DP(3)';
NODE_NAME     J4A1 186
 '@BASEBOARD_FAB2_LIB.BASEBOARD_FAB2(SCH_1):PAGE53_I66@MSTR_SCONN.SCONN288_H44441004(CHIPS)':
 'DQS3P': CDS_PINID='DQS3P';
NODE_NAME     J6L1 186
 '@BASEBOARD_FAB2_LIB.BASEBOARD_FAB2(SCH_1):PAGE54_I66@MSTR_SCONN.SCONN288_H44441003(CHIPS)':
 'DQS3P': CDS_PINID='DQS3P';
NET_NAME
'M_F_DQS_DP<4>'
 '@BASEBOARD_FAB2_LIB.BASEBOARD_FAB2(SCH_1):M_F_DQS_DP'<4>:
 C_SIGNAL='@baseboard_fab2_lib.baseboard_fab2(sch_1):m_f_dqs_dp(4)';
NODE_NAME     U5D1 DJ40
 '@BASEBOARD_FAB2_LIB.BASEBOARD_FAB2(SCH_1):PAGE28_I172@CHPSET_LIB.SKX_EXT_B(CHIPS)':
 'DDR5_DQS_DP'<4>: CDS_PINID='DDR5_DQS_DP(4)';
NODE_NAME     J4A1 245
 '@BASEBOARD_FAB2_LIB.BASEBOARD_FAB2(SCH_1):PAGE53_I66@MSTR_SCONN.SCONN288_H44441004(CHIPS)':
 'DQS4P': CDS_PINID='DQS4P';
NODE_NAME     J6L1 245
 '@BASEBOARD_FAB2_LIB.BASEBOARD_FAB2(SCH_1):PAGE54_I66@MSTR_SCONN.SCONN288_H44441003(CHIPS)':
 'DQS4P': CDS_PINID='DQS4P';
NET_NAME
'M_F_DQS_DP<5>'
 '@BASEBOARD_FAB2_LIB.BASEBOARD_FAB2(SCH_1):M_F_DQS_DP'<5>:
 C_SIGNAL='@baseboard_fab2_lib.baseboard_fab2(sch_1):m_f_dqs_dp(5)';
NODE_NAME     U5D1 DJ32
 '@BASEBOARD_FAB2_LIB.BASEBOARD_FAB2(SCH_1):PAGE28_I172@CHPSET_LIB.SKX_EXT_B(CHIPS)':
 'DDR5_DQS_DP'<5>: CDS_PINID='DDR5_DQS_DP(5)';
NODE_NAME     J4A1 256
 '@BASEBOARD_FAB2_LIB.BASEBOARD_FAB2(SCH_1):PAGE53_I66@MSTR_SCONN.SCONN288_H44441004(CHIPS)':
 'DQS5P': CDS_PINID='DQS5P';
NODE_NAME     J6L1 256
 '@BASEBOARD_FAB2_LIB.BASEBOARD_FAB2(SCH_1):PAGE54_I66@MSTR_SCONN.SCONN288_H44441003(CHIPS)':
 'DQS5P': CDS_PINID='DQS5P';
NET_NAME
'M_F_DQS_DP<6>'
 '@BASEBOARD_FAB2_LIB.BASEBOARD_FAB2(SCH_1):M_F_DQS_DP'<6>:
 C_SIGNAL='@baseboard_fab2_lib.baseboard_fab2(sch_1):m_f_dqs_dp(6)';
NODE_NAME     U5D1 DB35
 '@BASEBOARD_FAB2_LIB.BASEBOARD_FAB2(SCH_1):PAGE28_I172@CHPSET_LIB.SKX_EXT_B(CHIPS)':
 'DDR5_DQS_DP'<6>: CDS_PINID='DDR5_DQS_DP(6)';
NODE_NAME     J4A1 267
 '@BASEBOARD_FAB2_LIB.BASEBOARD_FAB2(SCH_1):PAGE53_I66@MSTR_SCONN.SCONN288_H44441004(CHIPS)':
 'DQS6P': CDS_PINID='DQS6P';
NODE_NAME     J6L1 267
 '@BASEBOARD_FAB2_LIB.BASEBOARD_FAB2(SCH_1):PAGE54_I66@MSTR_SCONN.SCONN288_H44441003(CHIPS)':
 'DQS6P': CDS_PINID='DQS6P';
NET_NAME
'M_F_DQS_DP<7>'
 '@BASEBOARD_FAB2_LIB.BASEBOARD_FAB2(SCH_1):M_F_DQS_DP'<7>:
 C_SIGNAL='@baseboard_fab2_lib.baseboard_fab2(sch_1):m_f_dqs_dp(7)';
NODE_NAME     U5D1 DB29
 '@BASEBOARD_FAB2_LIB.BASEBOARD_FAB2(SCH_1):PAGE28_I172@CHPSET_LIB.SKX_EXT_B(CHIPS)':
 'DDR5_DQS_DP'<7>: CDS_PINID='DDR5_DQS_DP(7)';
NODE_NAME     J4A1 278
 '@BASEBOARD_FAB2_LIB.BASEBOARD_FAB2(SCH_1):PAGE53_I66@MSTR_SCONN.SCONN288_H44441004(CHIPS)':
 'DQS7P': CDS_PINID='DQS7P';
NODE_NAME     J6L1 278
 '@BASEBOARD_FAB2_LIB.BASEBOARD_FAB2(SCH_1):PAGE54_I66@MSTR_SCONN.SCONN288_H44441003(CHIPS)':
 'DQS7P': CDS_PINID='DQS7P';
NET_NAME
'M_F_DQS_DP<8>'
 '@BASEBOARD_FAB2_LIB.BASEBOARD_FAB2(SCH_1):M_F_DQS_DP'<8>:
 C_SIGNAL='@baseboard_fab2_lib.baseboard_fab2(sch_1):m_f_dqs_dp(8)';
NODE_NAME     U5D1 CL70
 '@BASEBOARD_FAB2_LIB.BASEBOARD_FAB2(SCH_1):PAGE28_I172@CHPSET_LIB.SKX_EXT_B(CHIPS)':
 'DDR5_DQS_DP'<8>: CDS_PINID='DDR5_DQS_DP(8)';
NODE_NAME     J4A1 197
 '@BASEBOARD_FAB2_LIB.BASEBOARD_FAB2(SCH_1):PAGE53_I66@MSTR_SCONN.SCONN288_H44441004(CHIPS)':
 'DQS8P': CDS_PINID='DQS8P';
NODE_NAME     J6L1 197
 '@BASEBOARD_FAB2_LIB.BASEBOARD_FAB2(SCH_1):PAGE54_I66@MSTR_SCONN.SCONN288_H44441003(CHIPS)':
 'DQS8P': CDS_PINID='DQS8P';
NET_NAME
'M_F_DQS_DP<9>'
 '@BASEBOARD_FAB2_LIB.BASEBOARD_FAB2(SCH_1):M_F_DQS_DP'<9>:
 C_SIGNAL='@baseboard_fab2_lib.baseboard_fab2(sch_1):m_f_dqs_dp(9)';
NODE_NAME     U5D1 CU74
 '@BASEBOARD_FAB2_LIB.BASEBOARD_FAB2(SCH_1):PAGE28_I172@CHPSET_LIB.SKX_EXT_B(CHIPS)':
 'DDR5_DQS_DP'<9>: CDS_PINID='DDR5_DQS_DP(9)';
NODE_NAME     J4A1 7
 '@BASEBOARD_FAB2_LIB.BASEBOARD_FAB2(SCH_1):PAGE53_I66@MSTR_SCONN.SCONN288_H44441004(CHIPS)':
 'DQS9P': CDS_PINID='DQS9P';
NODE_NAME     J6L1 7
 '@BASEBOARD_FAB2_LIB.BASEBOARD_FAB2(SCH_1):PAGE54_I66@MSTR_SCONN.SCONN288_H44441003(CHIPS)':
 'DQS9P': CDS_PINID='DQS9P';
NET_NAME
'M_F_ECC<0>'
 '@BASEBOARD_FAB2_LIB.BASEBOARD_FAB2(SCH_1):M_F_ECC'<0>:
 C_SIGNAL='@baseboard_fab2_lib.baseboard_fab2(sch_1):m_f_ecc(0)';
NODE_NAME     U5D1 CH71
 '@BASEBOARD_FAB2_LIB.BASEBOARD_FAB2(SCH_1):PAGE28_I172@CHPSET_LIB.SKX_EXT_B(CHIPS)':
 'DDR5_ECC'<0>: CDS_PINID='DDR5_ECC(0)';
NODE_NAME     J4A1 194
 '@BASEBOARD_FAB2_LIB.BASEBOARD_FAB2(SCH_1):PAGE53_I111@MSTR_SCONN.SCONN288_H44441004(CHIPS)':
 'CB'<1>: CDS_PINID='CB(1)';
NODE_NAME     J6L1 49
 '@BASEBOARD_FAB2_LIB.BASEBOARD_FAB2(SCH_1):PAGE54_I111@MSTR_SCONN.SCONN288_H44441003(CHIPS)':
 'CB'<0>: CDS_PINID='CB(0)';
NET_NAME
'M_F_ECC<1>'
 '@BASEBOARD_FAB2_LIB.BASEBOARD_FAB2(SCH_1):M_F_ECC'<1>:
 C_SIGNAL='@baseboard_fab2_lib.baseboard_fab2(sch_1):m_f_ecc(1)';
NODE_NAME     U5D1 CM71
 '@BASEBOARD_FAB2_LIB.BASEBOARD_FAB2(SCH_1):PAGE28_I172@CHPSET_LIB.SKX_EXT_B(CHIPS)':
 'DDR5_ECC'<1>: CDS_PINID='DDR5_ECC(1)';
NODE_NAME     J4A1 49
 '@BASEBOARD_FAB2_LIB.BASEBOARD_FAB2(SCH_1):PAGE53_I111@MSTR_SCONN.SCONN288_H44441004(CHIPS)':
 'CB'<0>: CDS_PINID='CB(0)';
NODE_NAME     J6L1 194
 '@BASEBOARD_FAB2_LIB.BASEBOARD_FAB2(SCH_1):PAGE54_I111@MSTR_SCONN.SCONN288_H44441003(CHIPS)':
 'CB'<1>: CDS_PINID='CB(1)';
NET_NAME
'M_F_ECC<2>'
 '@BASEBOARD_FAB2_LIB.BASEBOARD_FAB2(SCH_1):M_F_ECC'<2>:
 C_SIGNAL='@baseboard_fab2_lib.baseboard_fab2(sch_1):m_f_ecc(2)';
NODE_NAME     U5D1 CJ68
 '@BASEBOARD_FAB2_LIB.BASEBOARD_FAB2(SCH_1):PAGE28_I172@CHPSET_LIB.SKX_EXT_B(CHIPS)':
 'DDR5_ECC'<2>: CDS_PINID='DDR5_ECC(2)';
NODE_NAME     J4A1 201
 '@BASEBOARD_FAB2_LIB.BASEBOARD_FAB2(SCH_1):PAGE53_I111@MSTR_SCONN.SCONN288_H44441004(CHIPS)':
 'CB'<3>: CDS_PINID='CB(3)';
NODE_NAME     J6L1 56
 '@BASEBOARD_FAB2_LIB.BASEBOARD_FAB2(SCH_1):PAGE54_I111@MSTR_SCONN.SCONN288_H44441003(CHIPS)':
 'CB'<2>: CDS_PINID='CB(2)';
NET_NAME
'M_F_ECC<3>'
 '@BASEBOARD_FAB2_LIB.BASEBOARD_FAB2(SCH_1):M_F_ECC'<3>:
 C_SIGNAL='@baseboard_fab2_lib.baseboard_fab2(sch_1):m_f_ecc(3)';
NODE_NAME     U5D1 CL68
 '@BASEBOARD_FAB2_LIB.BASEBOARD_FAB2(SCH_1):PAGE28_I172@CHPSET_LIB.SKX_EXT_B(CHIPS)':
 'DDR5_ECC'<3>: CDS_PINID='DDR5_ECC(3)';
NODE_NAME     J4A1 56
 '@BASEBOARD_FAB2_LIB.BASEBOARD_FAB2(SCH_1):PAGE53_I111@MSTR_SCONN.SCONN288_H44441004(CHIPS)':
 'CB'<2>: CDS_PINID='CB(2)';
NODE_NAME     J6L1 201
 '@BASEBOARD_FAB2_LIB.BASEBOARD_FAB2(SCH_1):PAGE54_I111@MSTR_SCONN.SCONN288_H44441003(CHIPS)':
 'CB'<3>: CDS_PINID='CB(3)';
NET_NAME
'M_F_ECC<4>'
 '@BASEBOARD_FAB2_LIB.BASEBOARD_FAB2(SCH_1):M_F_ECC'<4>:
 C_SIGNAL='@baseboard_fab2_lib.baseboard_fab2(sch_1):m_f_ecc(4)';
NODE_NAME     U5D1 CJ72
 '@BASEBOARD_FAB2_LIB.BASEBOARD_FAB2(SCH_1):PAGE28_I172@CHPSET_LIB.SKX_EXT_B(CHIPS)':
 'DDR5_ECC'<4>: CDS_PINID='DDR5_ECC(4)';
NODE_NAME     J4A1 192
 '@BASEBOARD_FAB2_LIB.BASEBOARD_FAB2(SCH_1):PAGE53_I111@MSTR_SCONN.SCONN288_H44441004(CHIPS)':
 'CB'<5>: CDS_PINID='CB(5)';
NODE_NAME     J6L1 47
 '@BASEBOARD_FAB2_LIB.BASEBOARD_FAB2(SCH_1):PAGE54_I111@MSTR_SCONN.SCONN288_H44441003(CHIPS)':
 'CB'<4>: CDS_PINID='CB(4)';
NET_NAME
'M_F_ECC<5>'
 '@BASEBOARD_FAB2_LIB.BASEBOARD_FAB2(SCH_1):M_F_ECC'<5>:
 C_SIGNAL='@baseboard_fab2_lib.baseboard_fab2(sch_1):m_f_ecc(5)';
NODE_NAME     U5D1 CL72
 '@BASEBOARD_FAB2_LIB.BASEBOARD_FAB2(SCH_1):PAGE28_I172@CHPSET_LIB.SKX_EXT_B(CHIPS)':
 'DDR5_ECC'<5>: CDS_PINID='DDR5_ECC(5)';
NODE_NAME     J4A1 47
 '@BASEBOARD_FAB2_LIB.BASEBOARD_FAB2(SCH_1):PAGE53_I111@MSTR_SCONN.SCONN288_H44441004(CHIPS)':
 'CB'<4>: CDS_PINID='CB(4)';
NODE_NAME     J6L1 192
 '@BASEBOARD_FAB2_LIB.BASEBOARD_FAB2(SCH_1):PAGE54_I111@MSTR_SCONN.SCONN288_H44441003(CHIPS)':
 'CB'<5>: CDS_PINID='CB(5)';
NET_NAME
'M_F_ECC<6>'
 '@BASEBOARD_FAB2_LIB.BASEBOARD_FAB2(SCH_1):M_F_ECC'<6>:
 C_SIGNAL='@baseboard_fab2_lib.baseboard_fab2(sch_1):m_f_ecc(6)';
NODE_NAME     U5D1 CH69
 '@BASEBOARD_FAB2_LIB.BASEBOARD_FAB2(SCH_1):PAGE28_I172@CHPSET_LIB.SKX_EXT_B(CHIPS)':
 'DDR5_ECC'<6>: CDS_PINID='DDR5_ECC(6)';
NODE_NAME     J4A1 199
 '@BASEBOARD_FAB2_LIB.BASEBOARD_FAB2(SCH_1):PAGE53_I111@MSTR_SCONN.SCONN288_H44441004(CHIPS)':
 'CB'<7>: CDS_PINID='CB(7)';
NODE_NAME     J6L1 54
 '@BASEBOARD_FAB2_LIB.BASEBOARD_FAB2(SCH_1):PAGE54_I111@MSTR_SCONN.SCONN288_H44441003(CHIPS)':
 'CB'<6>: CDS_PINID='CB(6)';
NET_NAME
'M_F_ECC<7>'
 '@BASEBOARD_FAB2_LIB.BASEBOARD_FAB2(SCH_1):M_F_ECC'<7>:
 C_SIGNAL='@baseboard_fab2_lib.baseboard_fab2(sch_1):m_f_ecc(7)';
NODE_NAME     U5D1 CM69
 '@BASEBOARD_FAB2_LIB.BASEBOARD_FAB2(SCH_1):PAGE28_I172@CHPSET_LIB.SKX_EXT_B(CHIPS)':
 'DDR5_ECC'<7>: CDS_PINID='DDR5_ECC(7)';
NODE_NAME     J4A1 54
 '@BASEBOARD_FAB2_LIB.BASEBOARD_FAB2(SCH_1):PAGE53_I111@MSTR_SCONN.SCONN288_H44441004(CHIPS)':
 'CB'<6>: CDS_PINID='CB(6)';
NODE_NAME     J6L1 199
 '@BASEBOARD_FAB2_LIB.BASEBOARD_FAB2(SCH_1):PAGE54_I111@MSTR_SCONN.SCONN288_H44441003(CHIPS)':
 'CB'<7>: CDS_PINID='CB(7)';
NET_NAME
'M_F_MA<0>'
 '@BASEBOARD_FAB2_LIB.BASEBOARD_FAB2(SCH_1):M_F_MA'<0>:
 C_SIGNAL='@baseboard_fab2_lib.baseboard_fab2(sch_1):m_f_ma(0)';
NODE_NAME     U5D1 DF53
 '@BASEBOARD_FAB2_LIB.BASEBOARD_FAB2(SCH_1):PAGE28_I172@CHPSET_LIB.SKX_EXT_B(CHIPS)':
 'DDR5_MA'<0>: CDS_PINID='DDR5_MA(0)';
NODE_NAME     J4A1 79
 '@BASEBOARD_FAB2_LIB.BASEBOARD_FAB2(SCH_1):PAGE53_I111@MSTR_SCONN.SCONN288_H44441004(CHIPS)':
 'A0': CDS_PINID='A0';
NODE_NAME     J6L1 79
 '@BASEBOARD_FAB2_LIB.BASEBOARD_FAB2(SCH_1):PAGE54_I111@MSTR_SCONN.SCONN288_H44441003(CHIPS)':
 'A0': CDS_PINID='A0';
NET_NAME
'M_F_MA<10>'
 '@BASEBOARD_FAB2_LIB.BASEBOARD_FAB2(SCH_1):M_F_MA'<10>:
 C_SIGNAL='@baseboard_fab2_lib.baseboard_fab2(sch_1):m_f_ma(10)';
NODE_NAME     U5D1 DD55
 '@BASEBOARD_FAB2_LIB.BASEBOARD_FAB2(SCH_1):PAGE28_I172@CHPSET_LIB.SKX_EXT_B(CHIPS)':
 'DDR5_MA'<10>: CDS_PINID='DDR5_MA(10)';
NODE_NAME     J4A1 225
 '@BASEBOARD_FAB2_LIB.BASEBOARD_FAB2(SCH_1):PAGE53_I111@MSTR_SCONN.SCONN288_H44441004(CHIPS)':
 'A10': CDS_PINID='A10';
NODE_NAME     J6L1 225
 '@BASEBOARD_FAB2_LIB.BASEBOARD_FAB2(SCH_1):PAGE54_I111@MSTR_SCONN.SCONN288_H44441003(CHIPS)':
 'A10': CDS_PINID='A10';
NET_NAME
'M_F_MA<11>'
 '@BASEBOARD_FAB2_LIB.BASEBOARD_FAB2(SCH_1):M_F_MA'<11>:
 C_SIGNAL='@baseboard_fab2_lib.baseboard_fab2(sch_1):m_f_ma(11)';
NODE_NAME     U5D1 DA60
 '@BASEBOARD_FAB2_LIB.BASEBOARD_FAB2(SCH_1):PAGE28_I172@CHPSET_LIB.SKX_EXT_B(CHIPS)':
 'DDR5_MA'<11>: CDS_PINID='DDR5_MA(11)';
NODE_NAME     J4A1 210
 '@BASEBOARD_FAB2_LIB.BASEBOARD_FAB2(SCH_1):PAGE53_I111@MSTR_SCONN.SCONN288_H44441004(CHIPS)':
 'A11': CDS_PINID='A11';
NODE_NAME     J6L1 210
 '@BASEBOARD_FAB2_LIB.BASEBOARD_FAB2(SCH_1):PAGE54_I111@MSTR_SCONN.SCONN288_H44441003(CHIPS)':
 'A11': CDS_PINID='A11';
NET_NAME
'M_F_MA<12>'
 '@BASEBOARD_FAB2_LIB.BASEBOARD_FAB2(SCH_1):M_F_MA'<12>:
 C_SIGNAL='@baseboard_fab2_lib.baseboard_fab2(sch_1):m_f_ma(12)';
NODE_NAME     U5D1 DG60
 '@BASEBOARD_FAB2_LIB.BASEBOARD_FAB2(SCH_1):PAGE28_I172@CHPSET_LIB.SKX_EXT_B(CHIPS)':
 'DDR5_MA'<12>: CDS_PINID='DDR5_MA(12)';
NODE_NAME     J4A1 65
 '@BASEBOARD_FAB2_LIB.BASEBOARD_FAB2(SCH_1):PAGE53_I111@MSTR_SCONN.SCONN288_H44441004(CHIPS)':
 'A12': CDS_PINID='A12';
NODE_NAME     J6L1 65
 '@BASEBOARD_FAB2_LIB.BASEBOARD_FAB2(SCH_1):PAGE54_I111@MSTR_SCONN.SCONN288_H44441003(CHIPS)':
 'A12': CDS_PINID='A12';
NET_NAME
'M_F_MA<13>'
 '@BASEBOARD_FAB2_LIB.BASEBOARD_FAB2(SCH_1):M_F_MA'<13>:
 C_SIGNAL='@baseboard_fab2_lib.baseboard_fab2(sch_1):m_f_ma(13)';
NODE_NAME     U5D1 DD53
 '@BASEBOARD_FAB2_LIB.BASEBOARD_FAB2(SCH_1):PAGE28_I172@CHPSET_LIB.SKX_EXT_B(CHIPS)':
 'DDR5_MA'<13>: CDS_PINID='DDR5_MA(13)';
NODE_NAME     J4A1 232
 '@BASEBOARD_FAB2_LIB.BASEBOARD_FAB2(SCH_1):PAGE53_I111@MSTR_SCONN.SCONN288_H44441004(CHIPS)':
 'A13': CDS_PINID='A13';
NODE_NAME     J6L1 232
 '@BASEBOARD_FAB2_LIB.BASEBOARD_FAB2(SCH_1):PAGE54_I111@MSTR_SCONN.SCONN288_H44441003(CHIPS)':
 'A13': CDS_PINID='A13';
NET_NAME
'M_F_MA<14>'
 '@BASEBOARD_FAB2_LIB.BASEBOARD_FAB2(SCH_1):M_F_MA'<14>:
 C_SIGNAL='@baseboard_fab2_lib.baseboard_fab2(sch_1):m_f_ma(14)';
NODE_NAME     U5D1 DJ50
 '@BASEBOARD_FAB2_LIB.BASEBOARD_FAB2(SCH_1):PAGE28_I172@CHPSET_LIB.SKX_EXT_B(CHIPS)':
 'DDR5_MA'<14>: CDS_PINID='DDR5_MA(14)';
NODE_NAME     J4A1 228
 '@BASEBOARD_FAB2_LIB.BASEBOARD_FAB2(SCH_1):PAGE53_I111@MSTR_SCONN.SCONN288_H44441004(CHIPS)':
 'A14_WE_N': CDS_PINID='A14_WE_N';
NODE_NAME     J6L1 228
 '@BASEBOARD_FAB2_LIB.BASEBOARD_FAB2(SCH_1):PAGE54_I111@MSTR_SCONN.SCONN288_H44441003(CHIPS)':
 'A14_WE_N': CDS_PINID='A14_WE_N';
NET_NAME
'M_F_MA<15>'
 '@BASEBOARD_FAB2_LIB.BASEBOARD_FAB2(SCH_1):M_F_MA'<15>:
 C_SIGNAL='@baseboard_fab2_lib.baseboard_fab2(sch_1):m_f_ma(15)';
NODE_NAME     U5D1 DC54
 '@BASEBOARD_FAB2_LIB.BASEBOARD_FAB2(SCH_1):PAGE28_I172@CHPSET_LIB.SKX_EXT_B(CHIPS)':
 'DDR5_MA'<15>: CDS_PINID='DDR5_MA(15)';
NODE_NAME     J4A1 86
 '@BASEBOARD_FAB2_LIB.BASEBOARD_FAB2(SCH_1):PAGE53_I111@MSTR_SCONN.SCONN288_H44441004(CHIPS)':
 'A15_CAS_N': CDS_PINID='A15_CAS_N';
NODE_NAME     J6L1 86
 '@BASEBOARD_FAB2_LIB.BASEBOARD_FAB2(SCH_1):PAGE54_I111@MSTR_SCONN.SCONN288_H44441003(CHIPS)':
 'A15_CAS_N': CDS_PINID='A15_CAS_N';
NET_NAME
'M_F_MA<16>'
 '@BASEBOARD_FAB2_LIB.BASEBOARD_FAB2(SCH_1):M_F_MA'<16>:
 C_SIGNAL='@baseboard_fab2_lib.baseboard_fab2(sch_1):m_f_ma(16)';
NODE_NAME     U5D1 DG52
 '@BASEBOARD_FAB2_LIB.BASEBOARD_FAB2(SCH_1):PAGE28_I172@CHPSET_LIB.SKX_EXT_B(CHIPS)':
 'DDR5_MA'<16>: CDS_PINID='DDR5_MA(16)';
NODE_NAME     J4A1 82
 '@BASEBOARD_FAB2_LIB.BASEBOARD_FAB2(SCH_1):PAGE53_I111@MSTR_SCONN.SCONN288_H44441004(CHIPS)':
 'A16_RAS_N': CDS_PINID='A16_RAS_N';
NODE_NAME     J6L1 82
 '@BASEBOARD_FAB2_LIB.BASEBOARD_FAB2(SCH_1):PAGE54_I111@MSTR_SCONN.SCONN288_H44441003(CHIPS)':
 'A16_RAS_N': CDS_PINID='A16_RAS_N';
NET_NAME
'M_F_MA<17>'
 '@BASEBOARD_FAB2_LIB.BASEBOARD_FAB2(SCH_1):M_F_MA'<17>:
 C_SIGNAL='@baseboard_fab2_lib.baseboard_fab2(sch_1):m_f_ma(17)';
NODE_NAME     U5D1 DE46
 '@BASEBOARD_FAB2_LIB.BASEBOARD_FAB2(SCH_1):PAGE28_I172@CHPSET_LIB.SKX_EXT_B(CHIPS)':
 'DDR5_MA'<17>: CDS_PINID='DDR5_MA(17)';
NODE_NAME     J4A1 234
 '@BASEBOARD_FAB2_LIB.BASEBOARD_FAB2(SCH_1):PAGE53_I111@MSTR_SCONN.SCONN288_H44441004(CHIPS)':
 'A17': CDS_PINID='A17';
NODE_NAME     J6L1 234
 '@BASEBOARD_FAB2_LIB.BASEBOARD_FAB2(SCH_1):PAGE54_I111@MSTR_SCONN.SCONN288_H44441003(CHIPS)':
 'A17': CDS_PINID='A17';
NET_NAME
'M_F_MA<1>'
 '@BASEBOARD_FAB2_LIB.BASEBOARD_FAB2(SCH_1):M_F_MA'<1>:
 C_SIGNAL='@baseboard_fab2_lib.baseboard_fab2(sch_1):m_f_ma(1)';
NODE_NAME     U5D1 DC58
 '@BASEBOARD_FAB2_LIB.BASEBOARD_FAB2(SCH_1):PAGE28_I172@CHPSET_LIB.SKX_EXT_B(CHIPS)':
 'DDR5_MA'<1>: CDS_PINID='DDR5_MA(1)';
NODE_NAME     J4A1 72
 '@BASEBOARD_FAB2_LIB.BASEBOARD_FAB2(SCH_1):PAGE53_I111@MSTR_SCONN.SCONN288_H44441004(CHIPS)':
 'A1': CDS_PINID='A1';
NODE_NAME     J6L1 72
 '@BASEBOARD_FAB2_LIB.BASEBOARD_FAB2(SCH_1):PAGE54_I111@MSTR_SCONN.SCONN288_H44441003(CHIPS)':
 'A1': CDS_PINID='A1';
NET_NAME
'M_F_MA<2>'
 '@BASEBOARD_FAB2_LIB.BASEBOARD_FAB2(SCH_1):M_F_MA'<2>:
 C_SIGNAL='@baseboard_fab2_lib.baseboard_fab2(sch_1):m_f_ma(2)';
NODE_NAME     U5D1 DD57
 '@BASEBOARD_FAB2_LIB.BASEBOARD_FAB2(SCH_1):PAGE28_I172@CHPSET_LIB.SKX_EXT_B(CHIPS)':
 'DDR5_MA'<2>: CDS_PINID='DDR5_MA(2)';
NODE_NAME     J4A1 216
 '@BASEBOARD_FAB2_LIB.BASEBOARD_FAB2(SCH_1):PAGE53_I111@MSTR_SCONN.SCONN288_H44441004(CHIPS)':
 'A2': CDS_PINID='A2';
NODE_NAME     J6L1 216
 '@BASEBOARD_FAB2_LIB.BASEBOARD_FAB2(SCH_1):PAGE54_I111@MSTR_SCONN.SCONN288_H44441003(CHIPS)':
 'A2': CDS_PINID='A2';
NET_NAME
'M_F_MA<3>'
 '@BASEBOARD_FAB2_LIB.BASEBOARD_FAB2(SCH_1):M_F_MA'<3>:
 C_SIGNAL='@baseboard_fab2_lib.baseboard_fab2(sch_1):m_f_ma(3)';
NODE_NAME     U5D1 DG58
 '@BASEBOARD_FAB2_LIB.BASEBOARD_FAB2(SCH_1):PAGE28_I172@CHPSET_LIB.SKX_EXT_B(CHIPS)':
 'DDR5_MA'<3>: CDS_PINID='DDR5_MA(3)';
NODE_NAME     J4A1 71
 '@BASEBOARD_FAB2_LIB.BASEBOARD_FAB2(SCH_1):PAGE53_I111@MSTR_SCONN.SCONN288_H44441004(CHIPS)':
 'A3': CDS_PINID='A3';
NODE_NAME     J6L1 71
 '@BASEBOARD_FAB2_LIB.BASEBOARD_FAB2(SCH_1):PAGE54_I111@MSTR_SCONN.SCONN288_H44441003(CHIPS)':
 'A3': CDS_PINID='A3';
NET_NAME
'M_F_MA<4>'
 '@BASEBOARD_FAB2_LIB.BASEBOARD_FAB2(SCH_1):M_F_MA'<4>:
 C_SIGNAL='@baseboard_fab2_lib.baseboard_fab2(sch_1):m_f_ma(4)';
NODE_NAME     U5D1 DJ58
 '@BASEBOARD_FAB2_LIB.BASEBOARD_FAB2(SCH_1):PAGE28_I172@CHPSET_LIB.SKX_EXT_B(CHIPS)':
 'DDR5_MA'<4>: CDS_PINID='DDR5_MA(4)';
NODE_NAME     J4A1 214
 '@BASEBOARD_FAB2_LIB.BASEBOARD_FAB2(SCH_1):PAGE53_I111@MSTR_SCONN.SCONN288_H44441004(CHIPS)':
 'A4': CDS_PINID='A4';
NODE_NAME     J6L1 214
 '@BASEBOARD_FAB2_LIB.BASEBOARD_FAB2(SCH_1):PAGE54_I111@MSTR_SCONN.SCONN288_H44441003(CHIPS)':
 'A4': CDS_PINID='A4';
NET_NAME
'M_F_MA<5>'
 '@BASEBOARD_FAB2_LIB.BASEBOARD_FAB2(SCH_1):M_F_MA'<5>:
 C_SIGNAL='@baseboard_fab2_lib.baseboard_fab2(sch_1):m_f_ma(5)';
NODE_NAME     U5D1 DF59
 '@BASEBOARD_FAB2_LIB.BASEBOARD_FAB2(SCH_1):PAGE28_I172@CHPSET_LIB.SKX_EXT_B(CHIPS)':
 'DDR5_MA'<5>: CDS_PINID='DDR5_MA(5)';
NODE_NAME     J4A1 213
 '@BASEBOARD_FAB2_LIB.BASEBOARD_FAB2(SCH_1):PAGE53_I111@MSTR_SCONN.SCONN288_H44441004(CHIPS)':
 'A5': CDS_PINID='A5';
NODE_NAME     J6L1 213
 '@BASEBOARD_FAB2_LIB.BASEBOARD_FAB2(SCH_1):PAGE54_I111@MSTR_SCONN.SCONN288_H44441003(CHIPS)':
 'A5': CDS_PINID='A5';
NET_NAME
'M_F_MA<6>'
 '@BASEBOARD_FAB2_LIB.BASEBOARD_FAB2(SCH_1):M_F_MA'<6>:
 C_SIGNAL='@baseboard_fab2_lib.baseboard_fab2(sch_1):m_f_ma(6)';
NODE_NAME     U5D1 DK59
 '@BASEBOARD_FAB2_LIB.BASEBOARD_FAB2(SCH_1):PAGE28_I172@CHPSET_LIB.SKX_EXT_B(CHIPS)':
 'DDR5_MA'<6>: CDS_PINID='DDR5_MA(6)';
NODE_NAME     J4A1 69
 '@BASEBOARD_FAB2_LIB.BASEBOARD_FAB2(SCH_1):PAGE53_I111@MSTR_SCONN.SCONN288_H44441004(CHIPS)':
 'A6': CDS_PINID='A6';
NODE_NAME     J6L1 69
 '@BASEBOARD_FAB2_LIB.BASEBOARD_FAB2(SCH_1):PAGE54_I111@MSTR_SCONN.SCONN288_H44441003(CHIPS)':
 'A6': CDS_PINID='A6';
NET_NAME
'M_F_MA<7>'
 '@BASEBOARD_FAB2_LIB.BASEBOARD_FAB2(SCH_1):M_F_MA'<7>:
 C_SIGNAL='@baseboard_fab2_lib.baseboard_fab2(sch_1):m_f_ma(7)';
NODE_NAME     U5D1 DC60
 '@BASEBOARD_FAB2_LIB.BASEBOARD_FAB2(SCH_1):PAGE28_I172@CHPSET_LIB.SKX_EXT_B(CHIPS)':
 'DDR5_MA'<7>: CDS_PINID='DDR5_MA(7)';
NODE_NAME     J4A1 211
 '@BASEBOARD_FAB2_LIB.BASEBOARD_FAB2(SCH_1):PAGE53_I111@MSTR_SCONN.SCONN288_H44441004(CHIPS)':
 'A7': CDS_PINID='A7';
NODE_NAME     J6L1 211
 '@BASEBOARD_FAB2_LIB.BASEBOARD_FAB2(SCH_1):PAGE54_I111@MSTR_SCONN.SCONN288_H44441003(CHIPS)':
 'A7': CDS_PINID='A7';
NET_NAME
'M_F_MA<8>'
 '@BASEBOARD_FAB2_LIB.BASEBOARD_FAB2(SCH_1):M_F_MA'<8>:
 C_SIGNAL='@baseboard_fab2_lib.baseboard_fab2(sch_1):m_f_ma(8)';
NODE_NAME     U5D1 DD59
 '@BASEBOARD_FAB2_LIB.BASEBOARD_FAB2(SCH_1):PAGE28_I172@CHPSET_LIB.SKX_EXT_B(CHIPS)':
 'DDR5_MA'<8>: CDS_PINID='DDR5_MA(8)';
NODE_NAME     J4A1 68
 '@BASEBOARD_FAB2_LIB.BASEBOARD_FAB2(SCH_1):PAGE53_I111@MSTR_SCONN.SCONN288_H44441004(CHIPS)':
 'A8': CDS_PINID='A8';
NODE_NAME     J6L1 68
 '@BASEBOARD_FAB2_LIB.BASEBOARD_FAB2(SCH_1):PAGE54_I111@MSTR_SCONN.SCONN288_H44441003(CHIPS)':
 'A8': CDS_PINID='A8';
NET_NAME
'M_F_MA<9>'
 '@BASEBOARD_FAB2_LIB.BASEBOARD_FAB2(SCH_1):M_F_MA'<9>:
 C_SIGNAL='@baseboard_fab2_lib.baseboard_fab2(sch_1):m_f_ma(9)';
NODE_NAME     U5D1 DA58
 '@BASEBOARD_FAB2_LIB.BASEBOARD_FAB2(SCH_1):PAGE28_I172@CHPSET_LIB.SKX_EXT_B(CHIPS)':
 'DDR5_MA'<9>: CDS_PINID='DDR5_MA(9)';
NODE_NAME     J4A1 66
 '@BASEBOARD_FAB2_LIB.BASEBOARD_FAB2(SCH_1):PAGE53_I111@MSTR_SCONN.SCONN288_H44441004(CHIPS)':
 'A9': CDS_PINID='A9';
NODE_NAME     J6L1 66
 '@BASEBOARD_FAB2_LIB.BASEBOARD_FAB2(SCH_1):PAGE54_I111@MSTR_SCONN.SCONN288_H44441003(CHIPS)':
 'A9': CDS_PINID='A9';
NET_NAME
'M_F_ODT<0>'
 '@BASEBOARD_FAB2_LIB.BASEBOARD_FAB2(SCH_1):M_F_ODT'<0>:
 C_SIGNAL='@baseboard_fab2_lib.baseboard_fab2(sch_1):m_f_odt(0)';
NODE_NAME     U5D1 DG50
 '@BASEBOARD_FAB2_LIB.BASEBOARD_FAB2(SCH_1):PAGE28_I172@CHPSET_LIB.SKX_EXT_B(CHIPS)':
 'DDR5_ODT'<0>: CDS_PINID='DDR5_ODT(0)';
NODE_NAME     J4A1 87
 '@BASEBOARD_FAB2_LIB.BASEBOARD_FAB2(SCH_1):PAGE53_I111@MSTR_SCONN.SCONN288_H44441004(CHIPS)':
 'ODT'<0>: CDS_PINID='ODT(0)';
NET_NAME
'M_F_ODT<1>'
 '@BASEBOARD_FAB2_LIB.BASEBOARD_FAB2(SCH_1):M_F_ODT'<1>:
 C_SIGNAL='@baseboard_fab2_lib.baseboard_fab2(sch_1):m_f_odt(1)';
NODE_NAME     U5D1 DG48
 '@BASEBOARD_FAB2_LIB.BASEBOARD_FAB2(SCH_1):PAGE28_I172@CHPSET_LIB.SKX_EXT_B(CHIPS)':
 'DDR5_ODT'<1>: CDS_PINID='DDR5_ODT(1)';
NODE_NAME     J4A1 91
 '@BASEBOARD_FAB2_LIB.BASEBOARD_FAB2(SCH_1):PAGE53_I111@MSTR_SCONN.SCONN288_H44441004(CHIPS)':
 'ODT'<1>: CDS_PINID='ODT(1)';
NET_NAME
'M_F_ODT<2>'
 '@BASEBOARD_FAB2_LIB.BASEBOARD_FAB2(SCH_1):M_F_ODT'<2>:
 C_SIGNAL='@baseboard_fab2_lib.baseboard_fab2(sch_1):m_f_odt(2)';
NODE_NAME     U5D1 DK49
 '@BASEBOARD_FAB2_LIB.BASEBOARD_FAB2(SCH_1):PAGE28_I172@CHPSET_LIB.SKX_EXT_B(CHIPS)':
 'DDR5_ODT'<2>: CDS_PINID='DDR5_ODT(2)';
NODE_NAME     J6L1 87
 '@BASEBOARD_FAB2_LIB.BASEBOARD_FAB2(SCH_1):PAGE54_I111@MSTR_SCONN.SCONN288_H44441003(CHIPS)':
 'ODT'<0>: CDS_PINID='ODT(0)';
NET_NAME
'M_F_ODT<3>'
 '@BASEBOARD_FAB2_LIB.BASEBOARD_FAB2(SCH_1):M_F_ODT'<3>:
 C_SIGNAL='@baseboard_fab2_lib.baseboard_fab2(sch_1):m_f_odt(3)';
NODE_NAME     U5D1 DF47
 '@BASEBOARD_FAB2_LIB.BASEBOARD_FAB2(SCH_1):PAGE28_I172@CHPSET_LIB.SKX_EXT_B(CHIPS)':
 'DDR5_ODT'<3>: CDS_PINID='DDR5_ODT(3)';
NODE_NAME     J6L1 91
 '@BASEBOARD_FAB2_LIB.BASEBOARD_FAB2(SCH_1):PAGE54_I111@MSTR_SCONN.SCONN288_H44441003(CHIPS)':
 'ODT'<1>: CDS_PINID='ODT(1)';
NET_NAME
'M_F_PAR'
 '@BASEBOARD_FAB2_LIB.BASEBOARD_FAB2(SCH_1):M_F_PAR':
 C_SIGNAL='@baseboard_fab2_lib.baseboard_fab2(sch_1):m_f_par';
NODE_NAME     U5D1 DK53
 '@BASEBOARD_FAB2_LIB.BASEBOARD_FAB2(SCH_1):PAGE28_I172@CHPSET_LIB.SKX_EXT_B(CHIPS)':
 'DDR5_PAR': CDS_PINID='DDR5_PAR';
NODE_NAME     J4A1 222
 '@BASEBOARD_FAB2_LIB.BASEBOARD_FAB2(SCH_1):PAGE53_I111@MSTR_SCONN.SCONN288_H44441004(CHIPS)':
 'PAR': CDS_PINID='PAR';
NODE_NAME     J6L1 222
 '@BASEBOARD_FAB2_LIB.BASEBOARD_FAB2(SCH_1):PAGE54_I111@MSTR_SCONN.SCONN288_H44441003(CHIPS)':
 'PAR': CDS_PINID='PAR';
NET_NAME
'M_F_VREF'
 '@BASEBOARD_FAB2_LIB.BASEBOARD_FAB2(SCH_1):M_F_VREF':
 C_SIGNAL='@baseboard_fab2_lib.baseboard_fab2(sch_1):m_f_vref';
NODE_NAME     J4A1 146
 '@BASEBOARD_FAB2_LIB.BASEBOARD_FAB2(SCH_1):PAGE53_I111@MSTR_SCONN.SCONN288_H44441004(CHIPS)':
 'VREFCA': CDS_PINID='VREFCA';
NODE_NAME     C6L1 1
 '@BASEBOARD_FAB2_LIB.BASEBOARD_FAB2(SCH_1):PAGE53_I178@DEV_DISCRETE.CAP_A(CHIPS)':
 'A': CDS_PINID='A';
NODE_NAME     J6L1 146
 '@BASEBOARD_FAB2_LIB.BASEBOARD_FAB2(SCH_1):PAGE54_I111@MSTR_SCONN.SCONN288_H44441003(CHIPS)':
 'VREFCA': CDS_PINID='VREFCA';
NODE_NAME     C4A5 1
 '@BASEBOARD_FAB2_LIB.BASEBOARD_FAB2(SCH_1):PAGE54_I179@DEV_DISCRETE.CAP_A(CHIPS)':
 'A': CDS_PINID='A';
NODE_NAME     R6L2 2
 '@BASEBOARD_FAB2_LIB.BASEBOARD_FAB2(SCH_1):PAGE98_I62@MSTR_DISCRETE.RES(CHIPS)':
 'B': CDS_PINID='B';
NODE_NAME     R6L1 1
 '@BASEBOARD_FAB2_LIB.BASEBOARD_FAB2(SCH_1):PAGE98_I64@MSTR_DISCRETE.RES(CHIPS)':
 'A': CDS_PINID='A';
NODE_NAME     R6L3 2
 '@BASEBOARD_FAB2_LIB.BASEBOARD_FAB2(SCH_1):PAGE98_I66@MSTR_DISCRETE.RES(CHIPS)':
 'B': CDS_PINID='B';
NET_NAME
'M_GHJ_RST_N'
 '@BASEBOARD_FAB2_LIB.BASEBOARD_FAB2(SCH_1):M_GHJ_RST_N':
 C_SIGNAL='@baseboard_fab2_lib.baseboard_fab2(sch_1):m_ghj_rst_n';
NODE_NAME     U2D1 U64
 '@BASEBOARD_FAB2_LIB.BASEBOARD_FAB2(SCH_1):PAGE55_I172@CHPSET_LIB.SKX_EXT_B(CHIPS)':
 'DDR012_RESET_N': CDS_PINID='DDR012_RESET_N';
NODE_NAME     J1G1 58
 '@BASEBOARD_FAB2_LIB.BASEBOARD_FAB2(SCH_1):PAGE77_I111@MSTR_SCONN.SCONN288_H44441004(CHIPS)':
 'RESET_N': CDS_PINID='RESET_N';
NODE_NAME     J9T1 58
 '@BASEBOARD_FAB2_LIB.BASEBOARD_FAB2(SCH_1):PAGE78_I13@MSTR_SCONN.SCONN288_H44441003(CHIPS)':
 'RESET_N': CDS_PINID='RESET_N';
NODE_NAME     J1G2 58
 '@BASEBOARD_FAB2_LIB.BASEBOARD_FAB2(SCH_1):PAGE79_I111@MSTR_SCONN.SCONN288_H44441004(CHIPS)':
 'RESET_N': CDS_PINID='RESET_N';
NODE_NAME     J9U1 58
 '@BASEBOARD_FAB2_LIB.BASEBOARD_FAB2(SCH_1):PAGE80_I24@MSTR_SCONN.SCONN288_H44441003(CHIPS)':
 'RESET_N': CDS_PINID='RESET_N';
NODE_NAME     J1G3 58
 '@BASEBOARD_FAB2_LIB.BASEBOARD_FAB2(SCH_1):PAGE81_I186@MSTR_SCONN.SCONN288_H44441004(CHIPS)':
 'RESET_N': CDS_PINID='RESET_N';
NODE_NAME     J9U2 58
 '@BASEBOARD_FAB2_LIB.BASEBOARD_FAB2(SCH_1):PAGE82_I187@MSTR_SCONN.SCONN288_H44441003(CHIPS)':
 'RESET_N': CDS_PINID='RESET_N';
NET_NAME
'M_G_ACT_N'
 '@BASEBOARD_FAB2_LIB.BASEBOARD_FAB2(SCH_1):M_G_ACT_N':
 C_SIGNAL='@baseboard_fab2_lib.baseboard_fab2(sch_1):m_g_act_n';
NODE_NAME     U2D1 J60
 '@BASEBOARD_FAB2_LIB.BASEBOARD_FAB2(SCH_1):PAGE57_I172@CHPSET_LIB.SKX_EXT_B(CHIPS)':
 'DDR0_ACT_N': CDS_PINID='DDR0_ACT_N';
NODE_NAME     J1G1 62
 '@BASEBOARD_FAB2_LIB.BASEBOARD_FAB2(SCH_1):PAGE77_I111@MSTR_SCONN.SCONN288_H44441004(CHIPS)':
 'ACT_N': CDS_PINID='ACT_N';
NODE_NAME     J9T1 62
 '@BASEBOARD_FAB2_LIB.BASEBOARD_FAB2(SCH_1):PAGE78_I13@MSTR_SCONN.SCONN288_H44441003(CHIPS)':
 'ACT_N': CDS_PINID='ACT_N';
NET_NAME
'M_G_ALERT_N'
 '@BASEBOARD_FAB2_LIB.BASEBOARD_FAB2(SCH_1):M_G_ALERT_N':
 C_SIGNAL='@baseboard_fab2_lib.baseboard_fab2(sch_1):m_g_alert_n';
NODE_NAME     U2D1 B61
 '@BASEBOARD_FAB2_LIB.BASEBOARD_FAB2(SCH_1):PAGE57_I172@CHPSET_LIB.SKX_EXT_B(CHIPS)':
 'DDR0_ALERT_N': CDS_PINID='DDR0_ALERT_N';
NODE_NAME     J1G1 208
 '@BASEBOARD_FAB2_LIB.BASEBOARD_FAB2(SCH_1):PAGE77_I111@MSTR_SCONN.SCONN288_H44441004(CHIPS)':
 'ALERT_N': CDS_PINID='ALERT_N';
NODE_NAME     J9T1 208
 '@BASEBOARD_FAB2_LIB.BASEBOARD_FAB2(SCH_1):PAGE78_I13@MSTR_SCONN.SCONN288_H44441003(CHIPS)':
 'ALERT_N': CDS_PINID='ALERT_N';
NET_NAME
'M_G_BA<0>'
 '@BASEBOARD_FAB2_LIB.BASEBOARD_FAB2(SCH_1):M_G_BA'<0>:
 C_SIGNAL='@baseboard_fab2_lib.baseboard_fab2(sch_1):m_g_ba(0)';
NODE_NAME     U2D1 C52
 '@BASEBOARD_FAB2_LIB.BASEBOARD_FAB2(SCH_1):PAGE57_I172@CHPSET_LIB.SKX_EXT_B(CHIPS)':
 'DDR0_BA'<0>: CDS_PINID='DDR0_BA(0)';
NODE_NAME     J1G1 81
 '@BASEBOARD_FAB2_LIB.BASEBOARD_FAB2(SCH_1):PAGE77_I111@MSTR_SCONN.SCONN288_H44441004(CHIPS)':
 'BA'<0>: CDS_PINID='BA(0)';
NODE_NAME     J9T1 81
 '@BASEBOARD_FAB2_LIB.BASEBOARD_FAB2(SCH_1):PAGE78_I13@MSTR_SCONN.SCONN288_H44441003(CHIPS)':
 'BA'<0>: CDS_PINID='BA(0)';
NET_NAME
'M_G_BA<1>'
 '@BASEBOARD_FAB2_LIB.BASEBOARD_FAB2(SCH_1):M_G_BA'<1>:
 C_SIGNAL='@baseboard_fab2_lib.baseboard_fab2(sch_1):m_g_ba(1)';
NODE_NAME     U2D1 G54
 '@BASEBOARD_FAB2_LIB.BASEBOARD_FAB2(SCH_1):PAGE57_I172@CHPSET_LIB.SKX_EXT_B(CHIPS)':
 'DDR0_BA'<1>: CDS_PINID='DDR0_BA(1)';
NODE_NAME     J1G1 224
 '@BASEBOARD_FAB2_LIB.BASEBOARD_FAB2(SCH_1):PAGE77_I111@MSTR_SCONN.SCONN288_H44441004(CHIPS)':
 'BA'<1>: CDS_PINID='BA(1)';
NODE_NAME     J9T1 224
 '@BASEBOARD_FAB2_LIB.BASEBOARD_FAB2(SCH_1):PAGE78_I13@MSTR_SCONN.SCONN288_H44441003(CHIPS)':
 'BA'<1>: CDS_PINID='BA(1)';
NET_NAME
'M_G_BG<0>'
 '@BASEBOARD_FAB2_LIB.BASEBOARD_FAB2(SCH_1):M_G_BG'<0>:
 C_SIGNAL='@baseboard_fab2_lib.baseboard_fab2(sch_1):m_g_bg(0)';
NODE_NAME     U2D1 D61
 '@BASEBOARD_FAB2_LIB.BASEBOARD_FAB2(SCH_1):PAGE57_I172@CHPSET_LIB.SKX_EXT_B(CHIPS)':
 'DDR0_BG'<0>: CDS_PINID='DDR0_BG(0)';
NODE_NAME     J1G1 63
 '@BASEBOARD_FAB2_LIB.BASEBOARD_FAB2(SCH_1):PAGE77_I111@MSTR_SCONN.SCONN288_H44441004(CHIPS)':
 'BG'<0>: CDS_PINID='BG(0)';
NODE_NAME     J9T1 63
 '@BASEBOARD_FAB2_LIB.BASEBOARD_FAB2(SCH_1):PAGE78_I13@MSTR_SCONN.SCONN288_H44441003(CHIPS)':
 'BG'<0>: CDS_PINID='BG(0)';
NET_NAME
'M_G_BG<1>'
 '@BASEBOARD_FAB2_LIB.BASEBOARD_FAB2(SCH_1):M_G_BG'<1>:
 C_SIGNAL='@baseboard_fab2_lib.baseboard_fab2(sch_1):m_g_bg(1)';
NODE_NAME     U2D1 F63
 '@BASEBOARD_FAB2_LIB.BASEBOARD_FAB2(SCH_1):PAGE57_I172@CHPSET_LIB.SKX_EXT_B(CHIPS)':
 'DDR0_BG'<1>: CDS_PINID='DDR0_BG(1)';
NODE_NAME     J1G1 207
 '@BASEBOARD_FAB2_LIB.BASEBOARD_FAB2(SCH_1):PAGE77_I111@MSTR_SCONN.SCONN288_H44441004(CHIPS)':
 'BG'<1>: CDS_PINID='BG(1)';
NODE_NAME     J9T1 207
 '@BASEBOARD_FAB2_LIB.BASEBOARD_FAB2(SCH_1):PAGE78_I13@MSTR_SCONN.SCONN288_H44441003(CHIPS)':
 'BG'<1>: CDS_PINID='BG(1)';
NET_NAME
'M_G_C<2>'
 '@BASEBOARD_FAB2_LIB.BASEBOARD_FAB2(SCH_1):M_G_C'<2>:
 C_SIGNAL='@baseboard_fab2_lib.baseboard_fab2(sch_1):m_g_c(2)';
NODE_NAME     U2D1 G46
 '@BASEBOARD_FAB2_LIB.BASEBOARD_FAB2(SCH_1):PAGE57_I172@CHPSET_LIB.SKX_EXT_B(CHIPS)':
 'DDR0_CID'<2>: CDS_PINID='DDR0_CID(2)';
NODE_NAME     J1G1 235
 '@BASEBOARD_FAB2_LIB.BASEBOARD_FAB2(SCH_1):PAGE77_I111@MSTR_SCONN.SCONN288_H44441004(CHIPS)':
 'C'<2>: CDS_PINID='C(2)';
NODE_NAME     J9T1 235
 '@BASEBOARD_FAB2_LIB.BASEBOARD_FAB2(SCH_1):PAGE78_I13@MSTR_SCONN.SCONN288_H44441003(CHIPS)':
 'C'<2>: CDS_PINID='C(2)';
NET_NAME
'M_G_CKE<0>'
 '@BASEBOARD_FAB2_LIB.BASEBOARD_FAB2(SCH_1):M_G_CKE'<0>:
 C_SIGNAL='@baseboard_fab2_lib.baseboard_fab2(sch_1):m_g_cke(0)';
NODE_NAME     U2D1 C62
 '@BASEBOARD_FAB2_LIB.BASEBOARD_FAB2(SCH_1):PAGE57_I172@CHPSET_LIB.SKX_EXT_B(CHIPS)':
 'DDR0_CKE'<0>: CDS_PINID='DDR0_CKE(0)';
NODE_NAME     J1G1 60
 '@BASEBOARD_FAB2_LIB.BASEBOARD_FAB2(SCH_1):PAGE77_I111@MSTR_SCONN.SCONN288_H44441004(CHIPS)':
 'CKE'<0>: CDS_PINID='CKE(0)';
NET_NAME
'M_G_CKE<1>'
 '@BASEBOARD_FAB2_LIB.BASEBOARD_FAB2(SCH_1):M_G_CKE'<1>:
 C_SIGNAL='@baseboard_fab2_lib.baseboard_fab2(sch_1):m_g_cke(1)';
NODE_NAME     U2D1 C64
 '@BASEBOARD_FAB2_LIB.BASEBOARD_FAB2(SCH_1):PAGE57_I172@CHPSET_LIB.SKX_EXT_B(CHIPS)':
 'DDR0_CKE'<1>: CDS_PINID='DDR0_CKE(1)';
NODE_NAME     J1G1 203
 '@BASEBOARD_FAB2_LIB.BASEBOARD_FAB2(SCH_1):PAGE77_I111@MSTR_SCONN.SCONN288_H44441004(CHIPS)':
 'CKE'<1>: CDS_PINID='CKE(1)';
NET_NAME
'M_G_CKE<2>'
 '@BASEBOARD_FAB2_LIB.BASEBOARD_FAB2(SCH_1):M_G_CKE'<2>:
 C_SIGNAL='@baseboard_fab2_lib.baseboard_fab2(sch_1):m_g_cke(2)';
NODE_NAME     U2D1 B63
 '@BASEBOARD_FAB2_LIB.BASEBOARD_FAB2(SCH_1):PAGE57_I172@CHPSET_LIB.SKX_EXT_B(CHIPS)':
 'DDR0_CKE'<2>: CDS_PINID='DDR0_CKE(2)';
NODE_NAME     J9T1 60
 '@BASEBOARD_FAB2_LIB.BASEBOARD_FAB2(SCH_1):PAGE78_I13@MSTR_SCONN.SCONN288_H44441003(CHIPS)':
 'CKE'<0>: CDS_PINID='CKE(0)';
NET_NAME
'M_G_CKE<3>'
 '@BASEBOARD_FAB2_LIB.BASEBOARD_FAB2(SCH_1):M_G_CKE'<3>:
 C_SIGNAL='@baseboard_fab2_lib.baseboard_fab2(sch_1):m_g_cke(3)';
NODE_NAME     U2D1 D63
 '@BASEBOARD_FAB2_LIB.BASEBOARD_FAB2(SCH_1):PAGE57_I172@CHPSET_LIB.SKX_EXT_B(CHIPS)':
 'DDR0_CKE'<3>: CDS_PINID='DDR0_CKE(3)';
NODE_NAME     J9T1 203
 '@BASEBOARD_FAB2_LIB.BASEBOARD_FAB2(SCH_1):PAGE78_I13@MSTR_SCONN.SCONN288_H44441003(CHIPS)':
 'CKE'<1>: CDS_PINID='CKE(1)';
NET_NAME
'M_G_CLK_DN<0>'
 '@BASEBOARD_FAB2_LIB.BASEBOARD_FAB2(SCH_1):M_G_CLK_DN'<0>:
 C_SIGNAL='@baseboard_fab2_lib.baseboard_fab2(sch_1):m_g_clk_dn(0)';
NODE_NAME     U2D1 F55
 '@BASEBOARD_FAB2_LIB.BASEBOARD_FAB2(SCH_1):PAGE57_I172@CHPSET_LIB.SKX_EXT_B(CHIPS)':
 'DDR0_CLK_DN'<0>: CDS_PINID='DDR0_CLK_DN(0)';
NODE_NAME     J1G1 75
 '@BASEBOARD_FAB2_LIB.BASEBOARD_FAB2(SCH_1):PAGE77_I111@MSTR_SCONN.SCONN288_H44441004(CHIPS)':
 'CK0N': CDS_PINID='CK0N';
NET_NAME
'M_G_CLK_DN<1>'
 '@BASEBOARD_FAB2_LIB.BASEBOARD_FAB2(SCH_1):M_G_CLK_DN'<1>:
 C_SIGNAL='@baseboard_fab2_lib.baseboard_fab2(sch_1):m_g_clk_dn(1)';
NODE_NAME     U2D1 C54
 '@BASEBOARD_FAB2_LIB.BASEBOARD_FAB2(SCH_1):PAGE57_I172@CHPSET_LIB.SKX_EXT_B(CHIPS)':
 'DDR0_CLK_DN'<1>: CDS_PINID='DDR0_CLK_DN(1)';
NODE_NAME     J1G1 219
 '@BASEBOARD_FAB2_LIB.BASEBOARD_FAB2(SCH_1):PAGE77_I111@MSTR_SCONN.SCONN288_H44441004(CHIPS)':
 'CK1N': CDS_PINID='CK1N';
NET_NAME
'M_G_CLK_DN<2>'
 '@BASEBOARD_FAB2_LIB.BASEBOARD_FAB2(SCH_1):M_G_CLK_DN'<2>:
 C_SIGNAL='@baseboard_fab2_lib.baseboard_fab2(sch_1):m_g_clk_dn(2)';
NODE_NAME     U2D1 J56
 '@BASEBOARD_FAB2_LIB.BASEBOARD_FAB2(SCH_1):PAGE57_I172@CHPSET_LIB.SKX_EXT_B(CHIPS)':
 'DDR0_CLK_DN'<2>: CDS_PINID='DDR0_CLK_DN(2)';
NODE_NAME     J9T1 75
 '@BASEBOARD_FAB2_LIB.BASEBOARD_FAB2(SCH_1):PAGE78_I13@MSTR_SCONN.SCONN288_H44441003(CHIPS)':
 'CK0N': CDS_PINID='CK0N';
NET_NAME
'M_G_CLK_DN<3>'
 '@BASEBOARD_FAB2_LIB.BASEBOARD_FAB2(SCH_1):M_G_CLK_DN'<3>:
 C_SIGNAL='@baseboard_fab2_lib.baseboard_fab2(sch_1):m_g_clk_dn(3)';
NODE_NAME     U2D1 C56
 '@BASEBOARD_FAB2_LIB.BASEBOARD_FAB2(SCH_1):PAGE57_I172@CHPSET_LIB.SKX_EXT_B(CHIPS)':
 'DDR0_CLK_DN'<3>: CDS_PINID='DDR0_CLK_DN(3)';
NODE_NAME     J9T1 219
 '@BASEBOARD_FAB2_LIB.BASEBOARD_FAB2(SCH_1):PAGE78_I13@MSTR_SCONN.SCONN288_H44441003(CHIPS)':
 'CK1N': CDS_PINID='CK1N';
NET_NAME
'M_G_CLK_DP<0>'
 '@BASEBOARD_FAB2_LIB.BASEBOARD_FAB2(SCH_1):M_G_CLK_DP'<0>:
 C_SIGNAL='@baseboard_fab2_lib.baseboard_fab2(sch_1):m_g_clk_dp(0)';
NODE_NAME     U2D1 D55
 '@BASEBOARD_FAB2_LIB.BASEBOARD_FAB2(SCH_1):PAGE57_I172@CHPSET_LIB.SKX_EXT_B(CHIPS)':
 'DDR0_CLK_DP'<0>: CDS_PINID='DDR0_CLK_DP(0)';
NODE_NAME     J1G1 74
 '@BASEBOARD_FAB2_LIB.BASEBOARD_FAB2(SCH_1):PAGE77_I111@MSTR_SCONN.SCONN288_H44441004(CHIPS)':
 'CK0P': CDS_PINID='CK0P';
NET_NAME
'M_G_CLK_DP<1>'
 '@BASEBOARD_FAB2_LIB.BASEBOARD_FAB2(SCH_1):M_G_CLK_DP'<1>:
 C_SIGNAL='@baseboard_fab2_lib.baseboard_fab2(sch_1):m_g_clk_dp(1)';
NODE_NAME     U2D1 B55
 '@BASEBOARD_FAB2_LIB.BASEBOARD_FAB2(SCH_1):PAGE57_I172@CHPSET_LIB.SKX_EXT_B(CHIPS)':
 'DDR0_CLK_DP'<1>: CDS_PINID='DDR0_CLK_DP(1)';
NODE_NAME     J1G1 218
 '@BASEBOARD_FAB2_LIB.BASEBOARD_FAB2(SCH_1):PAGE77_I111@MSTR_SCONN.SCONN288_H44441004(CHIPS)':
 'CK1P': CDS_PINID='CK1P';
NET_NAME
'M_G_CLK_DP<2>'
 '@BASEBOARD_FAB2_LIB.BASEBOARD_FAB2(SCH_1):M_G_CLK_DP'<2>:
 C_SIGNAL='@baseboard_fab2_lib.baseboard_fab2(sch_1):m_g_clk_dp(2)';
NODE_NAME     U2D1 G56
 '@BASEBOARD_FAB2_LIB.BASEBOARD_FAB2(SCH_1):PAGE57_I172@CHPSET_LIB.SKX_EXT_B(CHIPS)':
 'DDR0_CLK_DP'<2>: CDS_PINID='DDR0_CLK_DP(2)';
NODE_NAME     J9T1 74
 '@BASEBOARD_FAB2_LIB.BASEBOARD_FAB2(SCH_1):PAGE78_I13@MSTR_SCONN.SCONN288_H44441003(CHIPS)':
 'CK0P': CDS_PINID='CK0P';
NET_NAME
'M_G_CLK_DP<3>'
 '@BASEBOARD_FAB2_LIB.BASEBOARD_FAB2(SCH_1):M_G_CLK_DP'<3>:
 C_SIGNAL='@baseboard_fab2_lib.baseboard_fab2(sch_1):m_g_clk_dp(3)';
NODE_NAME     U2D1 B57
 '@BASEBOARD_FAB2_LIB.BASEBOARD_FAB2(SCH_1):PAGE57_I172@CHPSET_LIB.SKX_EXT_B(CHIPS)':
 'DDR0_CLK_DP'<3>: CDS_PINID='DDR0_CLK_DP(3)';
NODE_NAME     J9T1 218
 '@BASEBOARD_FAB2_LIB.BASEBOARD_FAB2(SCH_1):PAGE78_I13@MSTR_SCONN.SCONN288_H44441003(CHIPS)':
 'CK1P': CDS_PINID='CK1P';
NET_NAME
'M_G_CPU_VREF'
 '@BASEBOARD_FAB2_LIB.BASEBOARD_FAB2(SCH_1):M_G_CPU_VREF':
 C_SIGNAL='@baseboard_fab2_lib.baseboard_fab2(sch_1):m_g_cpu_vref';
NODE_NAME     U2D1 AJ64
 '@BASEBOARD_FAB2_LIB.BASEBOARD_FAB2(SCH_1):PAGE55_I172@CHPSET_LIB.SKX_EXT_B(CHIPS)':
 'DDR0_CAVREF': CDS_PINID='DDR0_CAVREF';
NODE_NAME     R1F4 1
 '@BASEBOARD_FAB2_LIB.BASEBOARD_FAB2(SCH_1):PAGE100_I7@MSTR_DISCRETE.RES(CHIPS)':
 'A': CDS_PINID='A';
NODE_NAME     C1F19 1
 '@BASEBOARD_FAB2_LIB.BASEBOARD_FAB2(SCH_1):PAGE100_I8@DEV_DISCRETE.CAP_A(CHIPS)':
 'A': CDS_PINID='A';
NET_NAME
'M_G_CS_N<0>'
 '@BASEBOARD_FAB2_LIB.BASEBOARD_FAB2(SCH_1):M_G_CS_N'<0>:
 C_SIGNAL='@baseboard_fab2_lib.baseboard_fab2(sch_1):m_g_cs_n(0)';
NODE_NAME     U2D1 G52
 '@BASEBOARD_FAB2_LIB.BASEBOARD_FAB2(SCH_1):PAGE57_I172@CHPSET_LIB.SKX_EXT_B(CHIPS)':
 'DDR0_CS_N'<0>: CDS_PINID='DDR0_CS_N(0)';
NODE_NAME     J1G1 84
 '@BASEBOARD_FAB2_LIB.BASEBOARD_FAB2(SCH_1):PAGE77_I111@MSTR_SCONN.SCONN288_H44441004(CHIPS)':
 'S0_N': CDS_PINID='S0_N';
NET_NAME
'M_G_CS_N<1>'
 '@BASEBOARD_FAB2_LIB.BASEBOARD_FAB2(SCH_1):M_G_CS_N'<1>:
 C_SIGNAL='@baseboard_fab2_lib.baseboard_fab2(sch_1):m_g_cs_n(1)';
NODE_NAME     U2D1 F49
 '@BASEBOARD_FAB2_LIB.BASEBOARD_FAB2(SCH_1):PAGE57_I172@CHPSET_LIB.SKX_EXT_B(CHIPS)':
 'DDR0_CS_N'<1>: CDS_PINID='DDR0_CS_N(1)';
NODE_NAME     J1G1 89
 '@BASEBOARD_FAB2_LIB.BASEBOARD_FAB2(SCH_1):PAGE77_I111@MSTR_SCONN.SCONN288_H44441004(CHIPS)':
 'S1_N': CDS_PINID='S1_N';
NET_NAME
'M_G_CS_N<2>'
 '@BASEBOARD_FAB2_LIB.BASEBOARD_FAB2(SCH_1):M_G_CS_N'<2>:
 C_SIGNAL='@baseboard_fab2_lib.baseboard_fab2(sch_1):m_g_cs_n(2)';
NODE_NAME     U2D1 D47
 '@BASEBOARD_FAB2_LIB.BASEBOARD_FAB2(SCH_1):PAGE57_I172@CHPSET_LIB.SKX_EXT_B(CHIPS)':
 'DDR0_CS_N'<2>: CDS_PINID='DDR0_CS_N(2)';
NODE_NAME     J1G1 93
 '@BASEBOARD_FAB2_LIB.BASEBOARD_FAB2(SCH_1):PAGE77_I111@MSTR_SCONN.SCONN288_H44441004(CHIPS)':
 'S2_N_C'<0>: CDS_PINID='S2_N_C(0)';
NET_NAME
'M_G_CS_N<3>'
 '@BASEBOARD_FAB2_LIB.BASEBOARD_FAB2(SCH_1):M_G_CS_N'<3>:
 C_SIGNAL='@baseboard_fab2_lib.baseboard_fab2(sch_1):m_g_cs_n(3)';
NODE_NAME     U2D1 F47
 '@BASEBOARD_FAB2_LIB.BASEBOARD_FAB2(SCH_1):PAGE57_I172@CHPSET_LIB.SKX_EXT_B(CHIPS)':
 'DDR0_CS_N'<3>: CDS_PINID='DDR0_CS_N(3)';
NODE_NAME     J1G1 237
 '@BASEBOARD_FAB2_LIB.BASEBOARD_FAB2(SCH_1):PAGE77_I111@MSTR_SCONN.SCONN288_H44441004(CHIPS)':
 'S3_N_C'<1>: CDS_PINID='S3_N_C(1)';
NET_NAME
'M_G_CS_N<4>'
 '@BASEBOARD_FAB2_LIB.BASEBOARD_FAB2(SCH_1):M_G_CS_N'<4>:
 C_SIGNAL='@baseboard_fab2_lib.baseboard_fab2(sch_1):m_g_cs_n(4)';
NODE_NAME     U2D1 B51
 '@BASEBOARD_FAB2_LIB.BASEBOARD_FAB2(SCH_1):PAGE57_I172@CHPSET_LIB.SKX_EXT_B(CHIPS)':
 'DDR0_CS_N'<4>: CDS_PINID='DDR0_CS_N(4)';
NODE_NAME     J9T1 84
 '@BASEBOARD_FAB2_LIB.BASEBOARD_FAB2(SCH_1):PAGE78_I13@MSTR_SCONN.SCONN288_H44441003(CHIPS)':
 'S0_N': CDS_PINID='S0_N';
NET_NAME
'M_G_CS_N<5>'
 '@BASEBOARD_FAB2_LIB.BASEBOARD_FAB2(SCH_1):M_G_CS_N'<5>:
 C_SIGNAL='@baseboard_fab2_lib.baseboard_fab2(sch_1):m_g_cs_n(5)';
NODE_NAME     U2D1 D49
 '@BASEBOARD_FAB2_LIB.BASEBOARD_FAB2(SCH_1):PAGE57_I172@CHPSET_LIB.SKX_EXT_B(CHIPS)':
 'DDR0_CS_N'<5>: CDS_PINID='DDR0_CS_N(5)';
NODE_NAME     J9T1 89
 '@BASEBOARD_FAB2_LIB.BASEBOARD_FAB2(SCH_1):PAGE78_I13@MSTR_SCONN.SCONN288_H44441003(CHIPS)':
 'S1_N': CDS_PINID='S1_N';
NET_NAME
'M_G_CS_N<6>'
 '@BASEBOARD_FAB2_LIB.BASEBOARD_FAB2(SCH_1):M_G_CS_N'<6>:
 C_SIGNAL='@baseboard_fab2_lib.baseboard_fab2(sch_1):m_g_cs_n(6)';
NODE_NAME     U2D1 F45
 '@BASEBOARD_FAB2_LIB.BASEBOARD_FAB2(SCH_1):PAGE57_I172@CHPSET_LIB.SKX_EXT_B(CHIPS)':
 'DDR0_CS_N'<6>: CDS_PINID='DDR0_CS_N(6)';
NODE_NAME     J9T1 93
 '@BASEBOARD_FAB2_LIB.BASEBOARD_FAB2(SCH_1):PAGE78_I13@MSTR_SCONN.SCONN288_H44441003(CHIPS)':
 'S2_N_C'<0>: CDS_PINID='S2_N_C(0)';
NET_NAME
'M_G_CS_N<7>'
 '@BASEBOARD_FAB2_LIB.BASEBOARD_FAB2(SCH_1):M_G_CS_N'<7>:
 C_SIGNAL='@baseboard_fab2_lib.baseboard_fab2(sch_1):m_g_cs_n(7)';
NODE_NAME     U2D1 K45
 '@BASEBOARD_FAB2_LIB.BASEBOARD_FAB2(SCH_1):PAGE57_I172@CHPSET_LIB.SKX_EXT_B(CHIPS)':
 'DDR0_CS_N'<7>: CDS_PINID='DDR0_CS_N(7)';
NODE_NAME     J9T1 237
 '@BASEBOARD_FAB2_LIB.BASEBOARD_FAB2(SCH_1):PAGE78_I13@MSTR_SCONN.SCONN288_H44441003(CHIPS)':
 'S3_N_C'<1>: CDS_PINID='S3_N_C(1)';
NET_NAME
'M_G_DQ<0>'
 '@BASEBOARD_FAB2_LIB.BASEBOARD_FAB2(SCH_1):M_G_DQ'<0>:
 C_SIGNAL='@baseboard_fab2_lib.baseboard_fab2(sch_1):m_g_dq(0)';
NODE_NAME     U2D1 AN86
 '@BASEBOARD_FAB2_LIB.BASEBOARD_FAB2(SCH_1):PAGE57_I172@CHPSET_LIB.SKX_EXT_B(CHIPS)':
 'DDR0_DQ'<0>: CDS_PINID='DDR0_DQ(0)';
NODE_NAME     J1G1 150
 '@BASEBOARD_FAB2_LIB.BASEBOARD_FAB2(SCH_1):PAGE77_I111@MSTR_SCONN.SCONN288_H44441004(CHIPS)':
 'DQ'<1>: CDS_PINID='DQ(1)';
NODE_NAME     J9T1 5
 '@BASEBOARD_FAB2_LIB.BASEBOARD_FAB2(SCH_1):PAGE78_I13@MSTR_SCONN.SCONN288_H44441003(CHIPS)':
 'DQ'<0>: CDS_PINID='DQ(0)';
NET_NAME
'M_G_DQ<10>'
 '@BASEBOARD_FAB2_LIB.BASEBOARD_FAB2(SCH_1):M_G_DQ'<10>:
 C_SIGNAL='@baseboard_fab2_lib.baseboard_fab2(sch_1):m_g_dq(10)';
NODE_NAME     U2D1 L86
 '@BASEBOARD_FAB2_LIB.BASEBOARD_FAB2(SCH_1):PAGE57_I172@CHPSET_LIB.SKX_EXT_B(CHIPS)':
 'DDR0_DQ'<10>: CDS_PINID='DDR0_DQ(10)';
NODE_NAME     J1G1 168
 '@BASEBOARD_FAB2_LIB.BASEBOARD_FAB2(SCH_1):PAGE77_I111@MSTR_SCONN.SCONN288_H44441004(CHIPS)':
 'DQ'<11>: CDS_PINID='DQ(11)';
NODE_NAME     J9T1 23
 '@BASEBOARD_FAB2_LIB.BASEBOARD_FAB2(SCH_1):PAGE78_I13@MSTR_SCONN.SCONN288_H44441003(CHIPS)':
 'DQ'<10>: CDS_PINID='DQ(10)';
NET_NAME
'M_G_DQ<11>'
 '@BASEBOARD_FAB2_LIB.BASEBOARD_FAB2(SCH_1):M_G_DQ'<11>:
 C_SIGNAL='@baseboard_fab2_lib.baseboard_fab2(sch_1):m_g_dq(11)';
NODE_NAME     U2D1 L84
 '@BASEBOARD_FAB2_LIB.BASEBOARD_FAB2(SCH_1):PAGE57_I172@CHPSET_LIB.SKX_EXT_B(CHIPS)':
 'DDR0_DQ'<11>: CDS_PINID='DDR0_DQ(11)';
NODE_NAME     J1G1 23
 '@BASEBOARD_FAB2_LIB.BASEBOARD_FAB2(SCH_1):PAGE77_I111@MSTR_SCONN.SCONN288_H44441004(CHIPS)':
 'DQ'<10>: CDS_PINID='DQ(10)';
NODE_NAME     J9T1 168
 '@BASEBOARD_FAB2_LIB.BASEBOARD_FAB2(SCH_1):PAGE78_I13@MSTR_SCONN.SCONN288_H44441003(CHIPS)':
 'DQ'<11>: CDS_PINID='DQ(11)';
NET_NAME
'M_G_DQ<12>'
 '@BASEBOARD_FAB2_LIB.BASEBOARD_FAB2(SCH_1):M_G_DQ'<12>:
 C_SIGNAL='@baseboard_fab2_lib.baseboard_fab2(sch_1):m_g_dq(12)';
NODE_NAME     U2D1 AA86
 '@BASEBOARD_FAB2_LIB.BASEBOARD_FAB2(SCH_1):PAGE57_I172@CHPSET_LIB.SKX_EXT_B(CHIPS)':
 'DDR0_DQ'<12>: CDS_PINID='DDR0_DQ(12)';
NODE_NAME     J1G1 159
 '@BASEBOARD_FAB2_LIB.BASEBOARD_FAB2(SCH_1):PAGE77_I111@MSTR_SCONN.SCONN288_H44441004(CHIPS)':
 'DQ'<13>: CDS_PINID='DQ(13)';
NODE_NAME     J9T1 14
 '@BASEBOARD_FAB2_LIB.BASEBOARD_FAB2(SCH_1):PAGE78_I13@MSTR_SCONN.SCONN288_H44441003(CHIPS)':
 'DQ'<12>: CDS_PINID='DQ(12)';
NET_NAME
'M_G_DQ<13>'
 '@BASEBOARD_FAB2_LIB.BASEBOARD_FAB2(SCH_1):M_G_DQ'<13>:
 C_SIGNAL='@baseboard_fab2_lib.baseboard_fab2(sch_1):m_g_dq(13)';
NODE_NAME     U2D1 AA84
 '@BASEBOARD_FAB2_LIB.BASEBOARD_FAB2(SCH_1):PAGE57_I172@CHPSET_LIB.SKX_EXT_B(CHIPS)':
 'DDR0_DQ'<13>: CDS_PINID='DDR0_DQ(13)';
NODE_NAME     J1G1 14
 '@BASEBOARD_FAB2_LIB.BASEBOARD_FAB2(SCH_1):PAGE77_I111@MSTR_SCONN.SCONN288_H44441004(CHIPS)':
 'DQ'<12>: CDS_PINID='DQ(12)';
NODE_NAME     J9T1 159
 '@BASEBOARD_FAB2_LIB.BASEBOARD_FAB2(SCH_1):PAGE78_I13@MSTR_SCONN.SCONN288_H44441003(CHIPS)':
 'DQ'<13>: CDS_PINID='DQ(13)';
NET_NAME
'M_G_DQ<14>'
 '@BASEBOARD_FAB2_LIB.BASEBOARD_FAB2(SCH_1):M_G_DQ'<14>:
 C_SIGNAL='@baseboard_fab2_lib.baseboard_fab2(sch_1):m_g_dq(14)';
NODE_NAME     U2D1 N86
 '@BASEBOARD_FAB2_LIB.BASEBOARD_FAB2(SCH_1):PAGE57_I172@CHPSET_LIB.SKX_EXT_B(CHIPS)':
 'DDR0_DQ'<14>: CDS_PINID='DDR0_DQ(14)';
NODE_NAME     J1G1 166
 '@BASEBOARD_FAB2_LIB.BASEBOARD_FAB2(SCH_1):PAGE77_I111@MSTR_SCONN.SCONN288_H44441004(CHIPS)':
 'DQ'<15>: CDS_PINID='DQ(15)';
NODE_NAME     J9T1 21
 '@BASEBOARD_FAB2_LIB.BASEBOARD_FAB2(SCH_1):PAGE78_I13@MSTR_SCONN.SCONN288_H44441003(CHIPS)':
 'DQ'<14>: CDS_PINID='DQ(14)';
NET_NAME
'M_G_DQ<15>'
 '@BASEBOARD_FAB2_LIB.BASEBOARD_FAB2(SCH_1):M_G_DQ'<15>:
 C_SIGNAL='@baseboard_fab2_lib.baseboard_fab2(sch_1):m_g_dq(15)';
NODE_NAME     U2D1 N84
 '@BASEBOARD_FAB2_LIB.BASEBOARD_FAB2(SCH_1):PAGE57_I172@CHPSET_LIB.SKX_EXT_B(CHIPS)':
 'DDR0_DQ'<15>: CDS_PINID='DDR0_DQ(15)';
NODE_NAME     J1G1 21
 '@BASEBOARD_FAB2_LIB.BASEBOARD_FAB2(SCH_1):PAGE77_I111@MSTR_SCONN.SCONN288_H44441004(CHIPS)':
 'DQ'<14>: CDS_PINID='DQ(14)';
NODE_NAME     J9T1 166
 '@BASEBOARD_FAB2_LIB.BASEBOARD_FAB2(SCH_1):PAGE78_I13@MSTR_SCONN.SCONN288_H44441003(CHIPS)':
 'DQ'<15>: CDS_PINID='DQ(15)';
NET_NAME
'M_G_DQ<16>'
 '@BASEBOARD_FAB2_LIB.BASEBOARD_FAB2(SCH_1):M_G_DQ'<16>:
 C_SIGNAL='@baseboard_fab2_lib.baseboard_fab2(sch_1):m_g_dq(16)';
NODE_NAME     U2D1 V81
 '@BASEBOARD_FAB2_LIB.BASEBOARD_FAB2(SCH_1):PAGE57_I172@CHPSET_LIB.SKX_EXT_B(CHIPS)':
 'DDR0_DQ'<16>: CDS_PINID='DDR0_DQ(16)';
NODE_NAME     J1G1 172
 '@BASEBOARD_FAB2_LIB.BASEBOARD_FAB2(SCH_1):PAGE77_I111@MSTR_SCONN.SCONN288_H44441004(CHIPS)':
 'DQ'<17>: CDS_PINID='DQ(17)';
NODE_NAME     J9T1 27
 '@BASEBOARD_FAB2_LIB.BASEBOARD_FAB2(SCH_1):PAGE78_I13@MSTR_SCONN.SCONN288_H44441003(CHIPS)':
 'DQ'<16>: CDS_PINID='DQ(16)';
NET_NAME
'M_G_DQ<17>'
 '@BASEBOARD_FAB2_LIB.BASEBOARD_FAB2(SCH_1):M_G_DQ'<17>:
 C_SIGNAL='@baseboard_fab2_lib.baseboard_fab2(sch_1):m_g_dq(17)';
NODE_NAME     U2D1 T79
 '@BASEBOARD_FAB2_LIB.BASEBOARD_FAB2(SCH_1):PAGE57_I172@CHPSET_LIB.SKX_EXT_B(CHIPS)':
 'DDR0_DQ'<17>: CDS_PINID='DDR0_DQ(17)';
NODE_NAME     J1G1 27
 '@BASEBOARD_FAB2_LIB.BASEBOARD_FAB2(SCH_1):PAGE77_I111@MSTR_SCONN.SCONN288_H44441004(CHIPS)':
 'DQ'<16>: CDS_PINID='DQ(16)';
NODE_NAME     J9T1 172
 '@BASEBOARD_FAB2_LIB.BASEBOARD_FAB2(SCH_1):PAGE78_I13@MSTR_SCONN.SCONN288_H44441003(CHIPS)':
 'DQ'<17>: CDS_PINID='DQ(17)';
NET_NAME
'M_G_DQ<18>'
 '@BASEBOARD_FAB2_LIB.BASEBOARD_FAB2(SCH_1):M_G_DQ'<18>:
 C_SIGNAL='@baseboard_fab2_lib.baseboard_fab2(sch_1):m_g_dq(18)';
NODE_NAME     U2D1 N82
 '@BASEBOARD_FAB2_LIB.BASEBOARD_FAB2(SCH_1):PAGE57_I172@CHPSET_LIB.SKX_EXT_B(CHIPS)':
 'DDR0_DQ'<18>: CDS_PINID='DDR0_DQ(18)';
NODE_NAME     J1G1 179
 '@BASEBOARD_FAB2_LIB.BASEBOARD_FAB2(SCH_1):PAGE77_I111@MSTR_SCONN.SCONN288_H44441004(CHIPS)':
 'DQ'<19>: CDS_PINID='DQ(19)';
NODE_NAME     J9T1 34
 '@BASEBOARD_FAB2_LIB.BASEBOARD_FAB2(SCH_1):PAGE78_I13@MSTR_SCONN.SCONN288_H44441003(CHIPS)':
 'DQ'<18>: CDS_PINID='DQ(18)';
NET_NAME
'M_G_DQ<19>'
 '@BASEBOARD_FAB2_LIB.BASEBOARD_FAB2(SCH_1):M_G_DQ'<19>:
 C_SIGNAL='@baseboard_fab2_lib.baseboard_fab2(sch_1):m_g_dq(19)';
NODE_NAME     U2D1 M81
 '@BASEBOARD_FAB2_LIB.BASEBOARD_FAB2(SCH_1):PAGE57_I172@CHPSET_LIB.SKX_EXT_B(CHIPS)':
 'DDR0_DQ'<19>: CDS_PINID='DDR0_DQ(19)';
NODE_NAME     J1G1 34
 '@BASEBOARD_FAB2_LIB.BASEBOARD_FAB2(SCH_1):PAGE77_I111@MSTR_SCONN.SCONN288_H44441004(CHIPS)':
 'DQ'<18>: CDS_PINID='DQ(18)';
NODE_NAME     J9T1 179
 '@BASEBOARD_FAB2_LIB.BASEBOARD_FAB2(SCH_1):PAGE78_I13@MSTR_SCONN.SCONN288_H44441003(CHIPS)':
 'DQ'<19>: CDS_PINID='DQ(19)';
NET_NAME
'M_G_DQ<1>'
 '@BASEBOARD_FAB2_LIB.BASEBOARD_FAB2(SCH_1):M_G_DQ'<1>:
 C_SIGNAL='@baseboard_fab2_lib.baseboard_fab2(sch_1):m_g_dq(1)';
NODE_NAME     U2D1 AN84
 '@BASEBOARD_FAB2_LIB.BASEBOARD_FAB2(SCH_1):PAGE57_I172@CHPSET_LIB.SKX_EXT_B(CHIPS)':
 'DDR0_DQ'<1>: CDS_PINID='DDR0_DQ(1)';
NODE_NAME     J1G1 5
 '@BASEBOARD_FAB2_LIB.BASEBOARD_FAB2(SCH_1):PAGE77_I111@MSTR_SCONN.SCONN288_H44441004(CHIPS)':
 'DQ'<0>: CDS_PINID='DQ(0)';
NODE_NAME     J9T1 150
 '@BASEBOARD_FAB2_LIB.BASEBOARD_FAB2(SCH_1):PAGE78_I13@MSTR_SCONN.SCONN288_H44441003(CHIPS)':
 'DQ'<1>: CDS_PINID='DQ(1)';
NET_NAME
'M_G_DQ<20>'
 '@BASEBOARD_FAB2_LIB.BASEBOARD_FAB2(SCH_1):M_G_DQ'<20>:
 C_SIGNAL='@baseboard_fab2_lib.baseboard_fab2(sch_1):m_g_dq(20)';
NODE_NAME     U2D1 W80
 '@BASEBOARD_FAB2_LIB.BASEBOARD_FAB2(SCH_1):PAGE57_I172@CHPSET_LIB.SKX_EXT_B(CHIPS)':
 'DDR0_DQ'<20>: CDS_PINID='DDR0_DQ(20)';
NODE_NAME     J1G1 170
 '@BASEBOARD_FAB2_LIB.BASEBOARD_FAB2(SCH_1):PAGE77_I111@MSTR_SCONN.SCONN288_H44441004(CHIPS)':
 'DQ'<21>: CDS_PINID='DQ(21)';
NODE_NAME     J9T1 25
 '@BASEBOARD_FAB2_LIB.BASEBOARD_FAB2(SCH_1):PAGE78_I13@MSTR_SCONN.SCONN288_H44441003(CHIPS)':
 'DQ'<20>: CDS_PINID='DQ(20)';
NET_NAME
'M_G_DQ<21>'
 '@BASEBOARD_FAB2_LIB.BASEBOARD_FAB2(SCH_1):M_G_DQ'<21>:
 C_SIGNAL='@baseboard_fab2_lib.baseboard_fab2(sch_1):m_g_dq(21)';
NODE_NAME     U2D1 V79
 '@BASEBOARD_FAB2_LIB.BASEBOARD_FAB2(SCH_1):PAGE57_I172@CHPSET_LIB.SKX_EXT_B(CHIPS)':
 'DDR0_DQ'<21>: CDS_PINID='DDR0_DQ(21)';
NODE_NAME     J1G1 25
 '@BASEBOARD_FAB2_LIB.BASEBOARD_FAB2(SCH_1):PAGE77_I111@MSTR_SCONN.SCONN288_H44441004(CHIPS)':
 'DQ'<20>: CDS_PINID='DQ(20)';
NODE_NAME     J9T1 170
 '@BASEBOARD_FAB2_LIB.BASEBOARD_FAB2(SCH_1):PAGE78_I13@MSTR_SCONN.SCONN288_H44441003(CHIPS)':
 'DQ'<21>: CDS_PINID='DQ(21)';
NET_NAME
'M_G_DQ<22>'
 '@BASEBOARD_FAB2_LIB.BASEBOARD_FAB2(SCH_1):M_G_DQ'<22>:
 C_SIGNAL='@baseboard_fab2_lib.baseboard_fab2(sch_1):m_g_dq(22)';
NODE_NAME     U2D1 R82
 '@BASEBOARD_FAB2_LIB.BASEBOARD_FAB2(SCH_1):PAGE57_I172@CHPSET_LIB.SKX_EXT_B(CHIPS)':
 'DDR0_DQ'<22>: CDS_PINID='DDR0_DQ(22)';
NODE_NAME     J1G1 177
 '@BASEBOARD_FAB2_LIB.BASEBOARD_FAB2(SCH_1):PAGE77_I111@MSTR_SCONN.SCONN288_H44441004(CHIPS)':
 'DQ'<23>: CDS_PINID='DQ(23)';
NODE_NAME     J9T1 32
 '@BASEBOARD_FAB2_LIB.BASEBOARD_FAB2(SCH_1):PAGE78_I13@MSTR_SCONN.SCONN288_H44441003(CHIPS)':
 'DQ'<22>: CDS_PINID='DQ(22)';
NET_NAME
'M_G_DQ<23>'
 '@BASEBOARD_FAB2_LIB.BASEBOARD_FAB2(SCH_1):M_G_DQ'<23>:
 C_SIGNAL='@baseboard_fab2_lib.baseboard_fab2(sch_1):m_g_dq(23)';
NODE_NAME     U2D1 N80
 '@BASEBOARD_FAB2_LIB.BASEBOARD_FAB2(SCH_1):PAGE57_I172@CHPSET_LIB.SKX_EXT_B(CHIPS)':
 'DDR0_DQ'<23>: CDS_PINID='DDR0_DQ(23)';
NODE_NAME     J1G1 32
 '@BASEBOARD_FAB2_LIB.BASEBOARD_FAB2(SCH_1):PAGE77_I111@MSTR_SCONN.SCONN288_H44441004(CHIPS)':
 'DQ'<22>: CDS_PINID='DQ(22)';
NODE_NAME     J9T1 177
 '@BASEBOARD_FAB2_LIB.BASEBOARD_FAB2(SCH_1):PAGE78_I13@MSTR_SCONN.SCONN288_H44441003(CHIPS)':
 'DQ'<23>: CDS_PINID='DQ(23)';
NET_NAME
'M_G_DQ<24>'
 '@BASEBOARD_FAB2_LIB.BASEBOARD_FAB2(SCH_1):M_G_DQ'<24>:
 C_SIGNAL='@baseboard_fab2_lib.baseboard_fab2(sch_1):m_g_dq(24)';
NODE_NAME     U2D1 L76
 '@BASEBOARD_FAB2_LIB.BASEBOARD_FAB2(SCH_1):PAGE57_I172@CHPSET_LIB.SKX_EXT_B(CHIPS)':
 'DDR0_DQ'<24>: CDS_PINID='DDR0_DQ(24)';
NODE_NAME     J1G1 183
 '@BASEBOARD_FAB2_LIB.BASEBOARD_FAB2(SCH_1):PAGE77_I111@MSTR_SCONN.SCONN288_H44441004(CHIPS)':
 'DQ'<25>: CDS_PINID='DQ(25)';
NODE_NAME     J9T1 38
 '@BASEBOARD_FAB2_LIB.BASEBOARD_FAB2(SCH_1):PAGE78_I13@MSTR_SCONN.SCONN288_H44441003(CHIPS)':
 'DQ'<24>: CDS_PINID='DQ(24)';
NET_NAME
'M_G_DQ<25>'
 '@BASEBOARD_FAB2_LIB.BASEBOARD_FAB2(SCH_1):M_G_DQ'<25>:
 C_SIGNAL='@baseboard_fab2_lib.baseboard_fab2(sch_1):m_g_dq(25)';
NODE_NAME     U2D1 R76
 '@BASEBOARD_FAB2_LIB.BASEBOARD_FAB2(SCH_1):PAGE57_I172@CHPSET_LIB.SKX_EXT_B(CHIPS)':
 'DDR0_DQ'<25>: CDS_PINID='DDR0_DQ(25)';
NODE_NAME     J1G1 38
 '@BASEBOARD_FAB2_LIB.BASEBOARD_FAB2(SCH_1):PAGE77_I111@MSTR_SCONN.SCONN288_H44441004(CHIPS)':
 'DQ'<24>: CDS_PINID='DQ(24)';
NODE_NAME     J9T1 183
 '@BASEBOARD_FAB2_LIB.BASEBOARD_FAB2(SCH_1):PAGE78_I13@MSTR_SCONN.SCONN288_H44441003(CHIPS)':
 'DQ'<25>: CDS_PINID='DQ(25)';
NET_NAME
'M_G_DQ<26>'
 '@BASEBOARD_FAB2_LIB.BASEBOARD_FAB2(SCH_1):M_G_DQ'<26>:
 C_SIGNAL='@baseboard_fab2_lib.baseboard_fab2(sch_1):m_g_dq(26)';
NODE_NAME     U2D1 M73
 '@BASEBOARD_FAB2_LIB.BASEBOARD_FAB2(SCH_1):PAGE57_I172@CHPSET_LIB.SKX_EXT_B(CHIPS)':
 'DDR0_DQ'<26>: CDS_PINID='DDR0_DQ(26)';
NODE_NAME     J1G1 190
 '@BASEBOARD_FAB2_LIB.BASEBOARD_FAB2(SCH_1):PAGE77_I111@MSTR_SCONN.SCONN288_H44441004(CHIPS)':
 'DQ'<27>: CDS_PINID='DQ(27)';
NODE_NAME     J9T1 45
 '@BASEBOARD_FAB2_LIB.BASEBOARD_FAB2(SCH_1):PAGE78_I13@MSTR_SCONN.SCONN288_H44441003(CHIPS)':
 'DQ'<26>: CDS_PINID='DQ(26)';
NET_NAME
'M_G_DQ<27>'
 '@BASEBOARD_FAB2_LIB.BASEBOARD_FAB2(SCH_1):M_G_DQ'<27>:
 C_SIGNAL='@baseboard_fab2_lib.baseboard_fab2(sch_1):m_g_dq(27)';
NODE_NAME     U2D1 P73
 '@BASEBOARD_FAB2_LIB.BASEBOARD_FAB2(SCH_1):PAGE57_I172@CHPSET_LIB.SKX_EXT_B(CHIPS)':
 'DDR0_DQ'<27>: CDS_PINID='DDR0_DQ(27)';
NODE_NAME     J1G1 45
 '@BASEBOARD_FAB2_LIB.BASEBOARD_FAB2(SCH_1):PAGE77_I111@MSTR_SCONN.SCONN288_H44441004(CHIPS)':
 'DQ'<26>: CDS_PINID='DQ(26)';
NODE_NAME     J9T1 190
 '@BASEBOARD_FAB2_LIB.BASEBOARD_FAB2(SCH_1):PAGE78_I13@MSTR_SCONN.SCONN288_H44441003(CHIPS)':
 'DQ'<27>: CDS_PINID='DQ(27)';
NET_NAME
'M_G_DQ<28>'
 '@BASEBOARD_FAB2_LIB.BASEBOARD_FAB2(SCH_1):M_G_DQ'<28>:
 C_SIGNAL='@baseboard_fab2_lib.baseboard_fab2(sch_1):m_g_dq(28)';
NODE_NAME     U2D1 M77
 '@BASEBOARD_FAB2_LIB.BASEBOARD_FAB2(SCH_1):PAGE57_I172@CHPSET_LIB.SKX_EXT_B(CHIPS)':
 'DDR0_DQ'<28>: CDS_PINID='DDR0_DQ(28)';
NODE_NAME     J1G1 181
 '@BASEBOARD_FAB2_LIB.BASEBOARD_FAB2(SCH_1):PAGE77_I111@MSTR_SCONN.SCONN288_H44441004(CHIPS)':
 'DQ'<29>: CDS_PINID='DQ(29)';
NODE_NAME     J9T1 36
 '@BASEBOARD_FAB2_LIB.BASEBOARD_FAB2(SCH_1):PAGE78_I13@MSTR_SCONN.SCONN288_H44441003(CHIPS)':
 'DQ'<28>: CDS_PINID='DQ(28)';
NET_NAME
'M_G_DQ<29>'
 '@BASEBOARD_FAB2_LIB.BASEBOARD_FAB2(SCH_1):M_G_DQ'<29>:
 C_SIGNAL='@baseboard_fab2_lib.baseboard_fab2(sch_1):m_g_dq(29)';
NODE_NAME     U2D1 P77
 '@BASEBOARD_FAB2_LIB.BASEBOARD_FAB2(SCH_1):PAGE57_I172@CHPSET_LIB.SKX_EXT_B(CHIPS)':
 'DDR0_DQ'<29>: CDS_PINID='DDR0_DQ(29)';
NODE_NAME     J1G1 36
 '@BASEBOARD_FAB2_LIB.BASEBOARD_FAB2(SCH_1):PAGE77_I111@MSTR_SCONN.SCONN288_H44441004(CHIPS)':
 'DQ'<28>: CDS_PINID='DQ(28)';
NODE_NAME     J9T1 181
 '@BASEBOARD_FAB2_LIB.BASEBOARD_FAB2(SCH_1):PAGE78_I13@MSTR_SCONN.SCONN288_H44441003(CHIPS)':
 'DQ'<29>: CDS_PINID='DQ(29)';
NET_NAME
'M_G_DQ<2>'
 '@BASEBOARD_FAB2_LIB.BASEBOARD_FAB2(SCH_1):M_G_DQ'<2>:
 C_SIGNAL='@baseboard_fab2_lib.baseboard_fab2(sch_1):m_g_dq(2)';
NODE_NAME     U2D1 AE86
 '@BASEBOARD_FAB2_LIB.BASEBOARD_FAB2(SCH_1):PAGE57_I172@CHPSET_LIB.SKX_EXT_B(CHIPS)':
 'DDR0_DQ'<2>: CDS_PINID='DDR0_DQ(2)';
NODE_NAME     J1G1 157
 '@BASEBOARD_FAB2_LIB.BASEBOARD_FAB2(SCH_1):PAGE77_I111@MSTR_SCONN.SCONN288_H44441004(CHIPS)':
 'DQ'<3>: CDS_PINID='DQ(3)';
NODE_NAME     J9T1 12
 '@BASEBOARD_FAB2_LIB.BASEBOARD_FAB2(SCH_1):PAGE78_I13@MSTR_SCONN.SCONN288_H44441003(CHIPS)':
 'DQ'<2>: CDS_PINID='DQ(2)';
NET_NAME
'M_G_DQ<30>'
 '@BASEBOARD_FAB2_LIB.BASEBOARD_FAB2(SCH_1):M_G_DQ'<30>:
 C_SIGNAL='@baseboard_fab2_lib.baseboard_fab2(sch_1):m_g_dq(30)';
NODE_NAME     U2D1 L74
 '@BASEBOARD_FAB2_LIB.BASEBOARD_FAB2(SCH_1):PAGE57_I172@CHPSET_LIB.SKX_EXT_B(CHIPS)':
 'DDR0_DQ'<30>: CDS_PINID='DDR0_DQ(30)';
NODE_NAME     J1G1 188
 '@BASEBOARD_FAB2_LIB.BASEBOARD_FAB2(SCH_1):PAGE77_I111@MSTR_SCONN.SCONN288_H44441004(CHIPS)':
 'DQ'<31>: CDS_PINID='DQ(31)';
NODE_NAME     J9T1 43
 '@BASEBOARD_FAB2_LIB.BASEBOARD_FAB2(SCH_1):PAGE78_I13@MSTR_SCONN.SCONN288_H44441003(CHIPS)':
 'DQ'<30>: CDS_PINID='DQ(30)';
NET_NAME
'M_G_DQ<31>'
 '@BASEBOARD_FAB2_LIB.BASEBOARD_FAB2(SCH_1):M_G_DQ'<31>:
 C_SIGNAL='@baseboard_fab2_lib.baseboard_fab2(sch_1):m_g_dq(31)';
NODE_NAME     U2D1 R74
 '@BASEBOARD_FAB2_LIB.BASEBOARD_FAB2(SCH_1):PAGE57_I172@CHPSET_LIB.SKX_EXT_B(CHIPS)':
 'DDR0_DQ'<31>: CDS_PINID='DDR0_DQ(31)';
NODE_NAME     J1G1 43
 '@BASEBOARD_FAB2_LIB.BASEBOARD_FAB2(SCH_1):PAGE77_I111@MSTR_SCONN.SCONN288_H44441004(CHIPS)':
 'DQ'<30>: CDS_PINID='DQ(30)';
NODE_NAME     J9T1 188
 '@BASEBOARD_FAB2_LIB.BASEBOARD_FAB2(SCH_1):PAGE78_I13@MSTR_SCONN.SCONN288_H44441003(CHIPS)':
 'DQ'<31>: CDS_PINID='DQ(31)';
NET_NAME
'M_G_DQ<32>'
 '@BASEBOARD_FAB2_LIB.BASEBOARD_FAB2(SCH_1):M_G_DQ'<32>:
 C_SIGNAL='@baseboard_fab2_lib.baseboard_fab2(sch_1):m_g_dq(32)';
NODE_NAME     U2D1 C42
 '@BASEBOARD_FAB2_LIB.BASEBOARD_FAB2(SCH_1):PAGE57_I172@CHPSET_LIB.SKX_EXT_B(CHIPS)':
 'DDR0_DQ'<32>: CDS_PINID='DDR0_DQ(32)';
NODE_NAME     J1G1 242
 '@BASEBOARD_FAB2_LIB.BASEBOARD_FAB2(SCH_1):PAGE77_I111@MSTR_SCONN.SCONN288_H44441004(CHIPS)':
 'DQ'<33>: CDS_PINID='DQ(33)';
NODE_NAME     J9T1 97
 '@BASEBOARD_FAB2_LIB.BASEBOARD_FAB2(SCH_1):PAGE78_I13@MSTR_SCONN.SCONN288_H44441003(CHIPS)':
 'DQ'<32>: CDS_PINID='DQ(32)';
NET_NAME
'M_G_DQ<33>'
 '@BASEBOARD_FAB2_LIB.BASEBOARD_FAB2(SCH_1):M_G_DQ'<33>:
 C_SIGNAL='@baseboard_fab2_lib.baseboard_fab2(sch_1):m_g_dq(33)';
NODE_NAME     U2D1 B41
 '@BASEBOARD_FAB2_LIB.BASEBOARD_FAB2(SCH_1):PAGE57_I172@CHPSET_LIB.SKX_EXT_B(CHIPS)':
 'DDR0_DQ'<33>: CDS_PINID='DDR0_DQ(33)';
NODE_NAME     J1G1 97
 '@BASEBOARD_FAB2_LIB.BASEBOARD_FAB2(SCH_1):PAGE77_I111@MSTR_SCONN.SCONN288_H44441004(CHIPS)':
 'DQ'<32>: CDS_PINID='DQ(32)';
NODE_NAME     J9T1 242
 '@BASEBOARD_FAB2_LIB.BASEBOARD_FAB2(SCH_1):PAGE78_I13@MSTR_SCONN.SCONN288_H44441003(CHIPS)':
 'DQ'<33>: CDS_PINID='DQ(33)';
NET_NAME
'M_G_DQ<34>'
 '@BASEBOARD_FAB2_LIB.BASEBOARD_FAB2(SCH_1):M_G_DQ'<34>:
 C_SIGNAL='@baseboard_fab2_lib.baseboard_fab2(sch_1):m_g_dq(34)';
NODE_NAME     U2D1 C38
 '@BASEBOARD_FAB2_LIB.BASEBOARD_FAB2(SCH_1):PAGE57_I172@CHPSET_LIB.SKX_EXT_B(CHIPS)':
 'DDR0_DQ'<34>: CDS_PINID='DDR0_DQ(34)';
NODE_NAME     J1G1 249
 '@BASEBOARD_FAB2_LIB.BASEBOARD_FAB2(SCH_1):PAGE77_I111@MSTR_SCONN.SCONN288_H44441004(CHIPS)':
 'DQ'<35>: CDS_PINID='DQ(35)';
NODE_NAME     J9T1 104
 '@BASEBOARD_FAB2_LIB.BASEBOARD_FAB2(SCH_1):PAGE78_I13@MSTR_SCONN.SCONN288_H44441003(CHIPS)':
 'DQ'<34>: CDS_PINID='DQ(34)';
NET_NAME
'M_G_DQ<35>'
 '@BASEBOARD_FAB2_LIB.BASEBOARD_FAB2(SCH_1):M_G_DQ'<35>:
 C_SIGNAL='@baseboard_fab2_lib.baseboard_fab2(sch_1):m_g_dq(35)';
NODE_NAME     U2D1 E38
 '@BASEBOARD_FAB2_LIB.BASEBOARD_FAB2(SCH_1):PAGE57_I172@CHPSET_LIB.SKX_EXT_B(CHIPS)':
 'DDR0_DQ'<35>: CDS_PINID='DDR0_DQ(35)';
NODE_NAME     J1G1 104
 '@BASEBOARD_FAB2_LIB.BASEBOARD_FAB2(SCH_1):PAGE77_I111@MSTR_SCONN.SCONN288_H44441004(CHIPS)':
 'DQ'<34>: CDS_PINID='DQ(34)';
NODE_NAME     J9T1 249
 '@BASEBOARD_FAB2_LIB.BASEBOARD_FAB2(SCH_1):PAGE78_I13@MSTR_SCONN.SCONN288_H44441003(CHIPS)':
 'DQ'<35>: CDS_PINID='DQ(35)';
NET_NAME
'M_G_DQ<36>'
 '@BASEBOARD_FAB2_LIB.BASEBOARD_FAB2(SCH_1):M_G_DQ'<36>:
 C_SIGNAL='@baseboard_fab2_lib.baseboard_fab2(sch_1):m_g_dq(36)';
NODE_NAME     U2D1 E42
 '@BASEBOARD_FAB2_LIB.BASEBOARD_FAB2(SCH_1):PAGE57_I172@CHPSET_LIB.SKX_EXT_B(CHIPS)':
 'DDR0_DQ'<36>: CDS_PINID='DDR0_DQ(36)';
NODE_NAME     J1G1 240
 '@BASEBOARD_FAB2_LIB.BASEBOARD_FAB2(SCH_1):PAGE77_I111@MSTR_SCONN.SCONN288_H44441004(CHIPS)':
 'DQ'<37>: CDS_PINID='DQ(37)';
NODE_NAME     J9T1 95
 '@BASEBOARD_FAB2_LIB.BASEBOARD_FAB2(SCH_1):PAGE78_I13@MSTR_SCONN.SCONN288_H44441003(CHIPS)':
 'DQ'<36>: CDS_PINID='DQ(36)';
NET_NAME
'M_G_DQ<37>'
 '@BASEBOARD_FAB2_LIB.BASEBOARD_FAB2(SCH_1):M_G_DQ'<37>:
 C_SIGNAL='@baseboard_fab2_lib.baseboard_fab2(sch_1):m_g_dq(37)';
NODE_NAME     U2D1 F41
 '@BASEBOARD_FAB2_LIB.BASEBOARD_FAB2(SCH_1):PAGE57_I172@CHPSET_LIB.SKX_EXT_B(CHIPS)':
 'DDR0_DQ'<37>: CDS_PINID='DDR0_DQ(37)';
NODE_NAME     J1G1 95
 '@BASEBOARD_FAB2_LIB.BASEBOARD_FAB2(SCH_1):PAGE77_I111@MSTR_SCONN.SCONN288_H44441004(CHIPS)':
 'DQ'<36>: CDS_PINID='DQ(36)';
NODE_NAME     J9T1 240
 '@BASEBOARD_FAB2_LIB.BASEBOARD_FAB2(SCH_1):PAGE78_I13@MSTR_SCONN.SCONN288_H44441003(CHIPS)':
 'DQ'<37>: CDS_PINID='DQ(37)';
NET_NAME
'M_G_DQ<38>'
 '@BASEBOARD_FAB2_LIB.BASEBOARD_FAB2(SCH_1):M_G_DQ'<38>:
 C_SIGNAL='@baseboard_fab2_lib.baseboard_fab2(sch_1):m_g_dq(38)';
NODE_NAME     U2D1 B39
 '@BASEBOARD_FAB2_LIB.BASEBOARD_FAB2(SCH_1):PAGE57_I172@CHPSET_LIB.SKX_EXT_B(CHIPS)':
 'DDR0_DQ'<38>: CDS_PINID='DDR0_DQ(38)';
NODE_NAME     J1G1 247
 '@BASEBOARD_FAB2_LIB.BASEBOARD_FAB2(SCH_1):PAGE77_I111@MSTR_SCONN.SCONN288_H44441004(CHIPS)':
 'DQ'<39>: CDS_PINID='DQ(39)';
NODE_NAME     J9T1 102
 '@BASEBOARD_FAB2_LIB.BASEBOARD_FAB2(SCH_1):PAGE78_I13@MSTR_SCONN.SCONN288_H44441003(CHIPS)':
 'DQ'<38>: CDS_PINID='DQ(38)';
NET_NAME
'M_G_DQ<39>'
 '@BASEBOARD_FAB2_LIB.BASEBOARD_FAB2(SCH_1):M_G_DQ'<39>:
 C_SIGNAL='@baseboard_fab2_lib.baseboard_fab2(sch_1):m_g_dq(39)';
NODE_NAME     U2D1 F39
 '@BASEBOARD_FAB2_LIB.BASEBOARD_FAB2(SCH_1):PAGE57_I172@CHPSET_LIB.SKX_EXT_B(CHIPS)':
 'DDR0_DQ'<39>: CDS_PINID='DDR0_DQ(39)';
NODE_NAME     J1G1 102
 '@BASEBOARD_FAB2_LIB.BASEBOARD_FAB2(SCH_1):PAGE77_I111@MSTR_SCONN.SCONN288_H44441004(CHIPS)':
 'DQ'<38>: CDS_PINID='DQ(38)';
NODE_NAME     J9T1 247
 '@BASEBOARD_FAB2_LIB.BASEBOARD_FAB2(SCH_1):PAGE78_I13@MSTR_SCONN.SCONN288_H44441003(CHIPS)':
 'DQ'<39>: CDS_PINID='DQ(39)';
NET_NAME
'M_G_DQ<3>'
 '@BASEBOARD_FAB2_LIB.BASEBOARD_FAB2(SCH_1):M_G_DQ'<3>:
 C_SIGNAL='@baseboard_fab2_lib.baseboard_fab2(sch_1):m_g_dq(3)';
NODE_NAME     U2D1 AE84
 '@BASEBOARD_FAB2_LIB.BASEBOARD_FAB2(SCH_1):PAGE57_I172@CHPSET_LIB.SKX_EXT_B(CHIPS)':
 'DDR0_DQ'<3>: CDS_PINID='DDR0_DQ(3)';
NODE_NAME     J1G1 12
 '@BASEBOARD_FAB2_LIB.BASEBOARD_FAB2(SCH_1):PAGE77_I111@MSTR_SCONN.SCONN288_H44441004(CHIPS)':
 'DQ'<2>: CDS_PINID='DQ(2)';
NODE_NAME     J9T1 157
 '@BASEBOARD_FAB2_LIB.BASEBOARD_FAB2(SCH_1):PAGE78_I13@MSTR_SCONN.SCONN288_H44441003(CHIPS)':
 'DQ'<3>: CDS_PINID='DQ(3)';
NET_NAME
'M_G_DQ<40>'
 '@BASEBOARD_FAB2_LIB.BASEBOARD_FAB2(SCH_1):M_G_DQ'<40>:
 C_SIGNAL='@baseboard_fab2_lib.baseboard_fab2(sch_1):m_g_dq(40)';
NODE_NAME     U2D1 K37
 '@BASEBOARD_FAB2_LIB.BASEBOARD_FAB2(SCH_1):PAGE57_I172@CHPSET_LIB.SKX_EXT_B(CHIPS)':
 'DDR0_DQ'<40>: CDS_PINID='DDR0_DQ(40)';
NODE_NAME     J1G1 253
 '@BASEBOARD_FAB2_LIB.BASEBOARD_FAB2(SCH_1):PAGE77_I111@MSTR_SCONN.SCONN288_H44441004(CHIPS)':
 'DQ'<41>: CDS_PINID='DQ(41)';
NODE_NAME     J9T1 108
 '@BASEBOARD_FAB2_LIB.BASEBOARD_FAB2(SCH_1):PAGE78_I13@MSTR_SCONN.SCONN288_H44441003(CHIPS)':
 'DQ'<40>: CDS_PINID='DQ(40)';
NET_NAME
'M_G_DQ<41>'
 '@BASEBOARD_FAB2_LIB.BASEBOARD_FAB2(SCH_1):M_G_DQ'<41>:
 C_SIGNAL='@baseboard_fab2_lib.baseboard_fab2(sch_1):m_g_dq(41)';
NODE_NAME     U2D1 P37
 '@BASEBOARD_FAB2_LIB.BASEBOARD_FAB2(SCH_1):PAGE57_I172@CHPSET_LIB.SKX_EXT_B(CHIPS)':
 'DDR0_DQ'<41>: CDS_PINID='DDR0_DQ(41)';
NODE_NAME     J1G1 108
 '@BASEBOARD_FAB2_LIB.BASEBOARD_FAB2(SCH_1):PAGE77_I111@MSTR_SCONN.SCONN288_H44441004(CHIPS)':
 'DQ'<40>: CDS_PINID='DQ(40)';
NODE_NAME     J9T1 253
 '@BASEBOARD_FAB2_LIB.BASEBOARD_FAB2(SCH_1):PAGE78_I13@MSTR_SCONN.SCONN288_H44441003(CHIPS)':
 'DQ'<41>: CDS_PINID='DQ(41)';
NET_NAME
'M_G_DQ<42>'
 '@BASEBOARD_FAB2_LIB.BASEBOARD_FAB2(SCH_1):M_G_DQ'<42>:
 C_SIGNAL='@baseboard_fab2_lib.baseboard_fab2(sch_1):m_g_dq(42)';
NODE_NAME     U2D1 L34
 '@BASEBOARD_FAB2_LIB.BASEBOARD_FAB2(SCH_1):PAGE57_I172@CHPSET_LIB.SKX_EXT_B(CHIPS)':
 'DDR0_DQ'<42>: CDS_PINID='DDR0_DQ(42)';
NODE_NAME     J1G1 260
 '@BASEBOARD_FAB2_LIB.BASEBOARD_FAB2(SCH_1):PAGE77_I111@MSTR_SCONN.SCONN288_H44441004(CHIPS)':
 'DQ'<43>: CDS_PINID='DQ(43)';
NODE_NAME     J9T1 115
 '@BASEBOARD_FAB2_LIB.BASEBOARD_FAB2(SCH_1):PAGE78_I13@MSTR_SCONN.SCONN288_H44441003(CHIPS)':
 'DQ'<42>: CDS_PINID='DQ(42)';
NET_NAME
'M_G_DQ<43>'
 '@BASEBOARD_FAB2_LIB.BASEBOARD_FAB2(SCH_1):M_G_DQ'<43>:
 C_SIGNAL='@baseboard_fab2_lib.baseboard_fab2(sch_1):m_g_dq(43)';
NODE_NAME     U2D1 N34
 '@BASEBOARD_FAB2_LIB.BASEBOARD_FAB2(SCH_1):PAGE57_I172@CHPSET_LIB.SKX_EXT_B(CHIPS)':
 'DDR0_DQ'<43>: CDS_PINID='DDR0_DQ(43)';
NODE_NAME     J1G1 115
 '@BASEBOARD_FAB2_LIB.BASEBOARD_FAB2(SCH_1):PAGE77_I111@MSTR_SCONN.SCONN288_H44441004(CHIPS)':
 'DQ'<42>: CDS_PINID='DQ(42)';
NODE_NAME     J9T1 260
 '@BASEBOARD_FAB2_LIB.BASEBOARD_FAB2(SCH_1):PAGE78_I13@MSTR_SCONN.SCONN288_H44441003(CHIPS)':
 'DQ'<43>: CDS_PINID='DQ(43)';
NET_NAME
'M_G_DQ<44>'
 '@BASEBOARD_FAB2_LIB.BASEBOARD_FAB2(SCH_1):M_G_DQ'<44>:
 C_SIGNAL='@baseboard_fab2_lib.baseboard_fab2(sch_1):m_g_dq(44)';
NODE_NAME     U2D1 L38
 '@BASEBOARD_FAB2_LIB.BASEBOARD_FAB2(SCH_1):PAGE57_I172@CHPSET_LIB.SKX_EXT_B(CHIPS)':
 'DDR0_DQ'<44>: CDS_PINID='DDR0_DQ(44)';
NODE_NAME     J1G1 251
 '@BASEBOARD_FAB2_LIB.BASEBOARD_FAB2(SCH_1):PAGE77_I111@MSTR_SCONN.SCONN288_H44441004(CHIPS)':
 'DQ'<45>: CDS_PINID='DQ(45)';
NODE_NAME     J9T1 106
 '@BASEBOARD_FAB2_LIB.BASEBOARD_FAB2(SCH_1):PAGE78_I13@MSTR_SCONN.SCONN288_H44441003(CHIPS)':
 'DQ'<44>: CDS_PINID='DQ(44)';
NET_NAME
'M_G_DQ<45>'
 '@BASEBOARD_FAB2_LIB.BASEBOARD_FAB2(SCH_1):M_G_DQ'<45>:
 C_SIGNAL='@baseboard_fab2_lib.baseboard_fab2(sch_1):m_g_dq(45)';
NODE_NAME     U2D1 N38
 '@BASEBOARD_FAB2_LIB.BASEBOARD_FAB2(SCH_1):PAGE57_I172@CHPSET_LIB.SKX_EXT_B(CHIPS)':
 'DDR0_DQ'<45>: CDS_PINID='DDR0_DQ(45)';
NODE_NAME     J1G1 106
 '@BASEBOARD_FAB2_LIB.BASEBOARD_FAB2(SCH_1):PAGE77_I111@MSTR_SCONN.SCONN288_H44441004(CHIPS)':
 'DQ'<44>: CDS_PINID='DQ(44)';
NODE_NAME     J9T1 251
 '@BASEBOARD_FAB2_LIB.BASEBOARD_FAB2(SCH_1):PAGE78_I13@MSTR_SCONN.SCONN288_H44441003(CHIPS)':
 'DQ'<45>: CDS_PINID='DQ(45)';
NET_NAME
'M_G_DQ<46>'
 '@BASEBOARD_FAB2_LIB.BASEBOARD_FAB2(SCH_1):M_G_DQ'<46>:
 C_SIGNAL='@baseboard_fab2_lib.baseboard_fab2(sch_1):m_g_dq(46)';
NODE_NAME     U2D1 K35
 '@BASEBOARD_FAB2_LIB.BASEBOARD_FAB2(SCH_1):PAGE57_I172@CHPSET_LIB.SKX_EXT_B(CHIPS)':
 'DDR0_DQ'<46>: CDS_PINID='DDR0_DQ(46)';
NODE_NAME     J1G1 258
 '@BASEBOARD_FAB2_LIB.BASEBOARD_FAB2(SCH_1):PAGE77_I111@MSTR_SCONN.SCONN288_H44441004(CHIPS)':
 'DQ'<47>: CDS_PINID='DQ(47)';
NODE_NAME     J9T1 113
 '@BASEBOARD_FAB2_LIB.BASEBOARD_FAB2(SCH_1):PAGE78_I13@MSTR_SCONN.SCONN288_H44441003(CHIPS)':
 'DQ'<46>: CDS_PINID='DQ(46)';
NET_NAME
'M_G_DQ<47>'
 '@BASEBOARD_FAB2_LIB.BASEBOARD_FAB2(SCH_1):M_G_DQ'<47>:
 C_SIGNAL='@baseboard_fab2_lib.baseboard_fab2(sch_1):m_g_dq(47)';
NODE_NAME     U2D1 P35
 '@BASEBOARD_FAB2_LIB.BASEBOARD_FAB2(SCH_1):PAGE57_I172@CHPSET_LIB.SKX_EXT_B(CHIPS)':
 'DDR0_DQ'<47>: CDS_PINID='DDR0_DQ(47)';
NODE_NAME     J1G1 113
 '@BASEBOARD_FAB2_LIB.BASEBOARD_FAB2(SCH_1):PAGE77_I111@MSTR_SCONN.SCONN288_H44441004(CHIPS)':
 'DQ'<46>: CDS_PINID='DQ(46)';
NODE_NAME     J9T1 258
 '@BASEBOARD_FAB2_LIB.BASEBOARD_FAB2(SCH_1):PAGE78_I13@MSTR_SCONN.SCONN288_H44441003(CHIPS)':
 'DQ'<47>: CDS_PINID='DQ(47)';
NET_NAME
'M_G_DQ<48>'
 '@BASEBOARD_FAB2_LIB.BASEBOARD_FAB2(SCH_1):M_G_DQ'<48>:
 C_SIGNAL='@baseboard_fab2_lib.baseboard_fab2(sch_1):m_g_dq(48)';
NODE_NAME     U2D1 K31
 '@BASEBOARD_FAB2_LIB.BASEBOARD_FAB2(SCH_1):PAGE57_I172@CHPSET_LIB.SKX_EXT_B(CHIPS)':
 'DDR0_DQ'<48>: CDS_PINID='DDR0_DQ(48)';
NODE_NAME     J1G1 264
 '@BASEBOARD_FAB2_LIB.BASEBOARD_FAB2(SCH_1):PAGE77_I111@MSTR_SCONN.SCONN288_H44441004(CHIPS)':
 'DQ'<49>: CDS_PINID='DQ(49)';
NODE_NAME     J9T1 119
 '@BASEBOARD_FAB2_LIB.BASEBOARD_FAB2(SCH_1):PAGE78_I13@MSTR_SCONN.SCONN288_H44441003(CHIPS)':
 'DQ'<48>: CDS_PINID='DQ(48)';
NET_NAME
'M_G_DQ<49>'
 '@BASEBOARD_FAB2_LIB.BASEBOARD_FAB2(SCH_1):M_G_DQ'<49>:
 C_SIGNAL='@baseboard_fab2_lib.baseboard_fab2(sch_1):m_g_dq(49)';
NODE_NAME     U2D1 P31
 '@BASEBOARD_FAB2_LIB.BASEBOARD_FAB2(SCH_1):PAGE57_I172@CHPSET_LIB.SKX_EXT_B(CHIPS)':
 'DDR0_DQ'<49>: CDS_PINID='DDR0_DQ(49)';
NODE_NAME     J1G1 119
 '@BASEBOARD_FAB2_LIB.BASEBOARD_FAB2(SCH_1):PAGE77_I111@MSTR_SCONN.SCONN288_H44441004(CHIPS)':
 'DQ'<48>: CDS_PINID='DQ(48)';
NODE_NAME     J9T1 264
 '@BASEBOARD_FAB2_LIB.BASEBOARD_FAB2(SCH_1):PAGE78_I13@MSTR_SCONN.SCONN288_H44441003(CHIPS)':
 'DQ'<49>: CDS_PINID='DQ(49)';
NET_NAME
'M_G_DQ<4>'
 '@BASEBOARD_FAB2_LIB.BASEBOARD_FAB2(SCH_1):M_G_DQ'<4>:
 C_SIGNAL='@baseboard_fab2_lib.baseboard_fab2(sch_1):m_g_dq(4)';
NODE_NAME     U2D1 AR86
 '@BASEBOARD_FAB2_LIB.BASEBOARD_FAB2(SCH_1):PAGE57_I172@CHPSET_LIB.SKX_EXT_B(CHIPS)':
 'DDR0_DQ'<4>: CDS_PINID='DDR0_DQ(4)';
NODE_NAME     J1G1 148
 '@BASEBOARD_FAB2_LIB.BASEBOARD_FAB2(SCH_1):PAGE77_I111@MSTR_SCONN.SCONN288_H44441004(CHIPS)':
 'DQ'<5>: CDS_PINID='DQ(5)';
NODE_NAME     J9T1 3
 '@BASEBOARD_FAB2_LIB.BASEBOARD_FAB2(SCH_1):PAGE78_I13@MSTR_SCONN.SCONN288_H44441003(CHIPS)':
 'DQ'<4>: CDS_PINID='DQ(4)';
NET_NAME
'M_G_DQ<50>'
 '@BASEBOARD_FAB2_LIB.BASEBOARD_FAB2(SCH_1):M_G_DQ'<50>:
 C_SIGNAL='@baseboard_fab2_lib.baseboard_fab2(sch_1):m_g_dq(50)';
NODE_NAME     U2D1 L28
 '@BASEBOARD_FAB2_LIB.BASEBOARD_FAB2(SCH_1):PAGE57_I172@CHPSET_LIB.SKX_EXT_B(CHIPS)':
 'DDR0_DQ'<50>: CDS_PINID='DDR0_DQ(50)';
NODE_NAME     J1G1 271
 '@BASEBOARD_FAB2_LIB.BASEBOARD_FAB2(SCH_1):PAGE77_I111@MSTR_SCONN.SCONN288_H44441004(CHIPS)':
 'DQ'<51>: CDS_PINID='DQ(51)';
NODE_NAME     J9T1 126
 '@BASEBOARD_FAB2_LIB.BASEBOARD_FAB2(SCH_1):PAGE78_I13@MSTR_SCONN.SCONN288_H44441003(CHIPS)':
 'DQ'<50>: CDS_PINID='DQ(50)';
NET_NAME
'M_G_DQ<51>'
 '@BASEBOARD_FAB2_LIB.BASEBOARD_FAB2(SCH_1):M_G_DQ'<51>:
 C_SIGNAL='@baseboard_fab2_lib.baseboard_fab2(sch_1):m_g_dq(51)';
NODE_NAME     U2D1 N28
 '@BASEBOARD_FAB2_LIB.BASEBOARD_FAB2(SCH_1):PAGE57_I172@CHPSET_LIB.SKX_EXT_B(CHIPS)':
 'DDR0_DQ'<51>: CDS_PINID='DDR0_DQ(51)';
NODE_NAME     J1G1 126
 '@BASEBOARD_FAB2_LIB.BASEBOARD_FAB2(SCH_1):PAGE77_I111@MSTR_SCONN.SCONN288_H44441004(CHIPS)':
 'DQ'<50>: CDS_PINID='DQ(50)';
NODE_NAME     J9T1 271
 '@BASEBOARD_FAB2_LIB.BASEBOARD_FAB2(SCH_1):PAGE78_I13@MSTR_SCONN.SCONN288_H44441003(CHIPS)':
 'DQ'<51>: CDS_PINID='DQ(51)';
NET_NAME
'M_G_DQ<52>'
 '@BASEBOARD_FAB2_LIB.BASEBOARD_FAB2(SCH_1):M_G_DQ'<52>:
 C_SIGNAL='@baseboard_fab2_lib.baseboard_fab2(sch_1):m_g_dq(52)';
NODE_NAME     U2D1 L32
 '@BASEBOARD_FAB2_LIB.BASEBOARD_FAB2(SCH_1):PAGE57_I172@CHPSET_LIB.SKX_EXT_B(CHIPS)':
 'DDR0_DQ'<52>: CDS_PINID='DDR0_DQ(52)';
NODE_NAME     J1G1 262
 '@BASEBOARD_FAB2_LIB.BASEBOARD_FAB2(SCH_1):PAGE77_I111@MSTR_SCONN.SCONN288_H44441004(CHIPS)':
 'DQ'<53>: CDS_PINID='DQ(53)';
NODE_NAME     J9T1 117
 '@BASEBOARD_FAB2_LIB.BASEBOARD_FAB2(SCH_1):PAGE78_I13@MSTR_SCONN.SCONN288_H44441003(CHIPS)':
 'DQ'<52>: CDS_PINID='DQ(52)';
NET_NAME
'M_G_DQ<53>'
 '@BASEBOARD_FAB2_LIB.BASEBOARD_FAB2(SCH_1):M_G_DQ'<53>:
 C_SIGNAL='@baseboard_fab2_lib.baseboard_fab2(sch_1):m_g_dq(53)';
NODE_NAME     U2D1 N32
 '@BASEBOARD_FAB2_LIB.BASEBOARD_FAB2(SCH_1):PAGE57_I172@CHPSET_LIB.SKX_EXT_B(CHIPS)':
 'DDR0_DQ'<53>: CDS_PINID='DDR0_DQ(53)';
NODE_NAME     J1G1 117
 '@BASEBOARD_FAB2_LIB.BASEBOARD_FAB2(SCH_1):PAGE77_I111@MSTR_SCONN.SCONN288_H44441004(CHIPS)':
 'DQ'<52>: CDS_PINID='DQ(52)';
NODE_NAME     J9T1 262
 '@BASEBOARD_FAB2_LIB.BASEBOARD_FAB2(SCH_1):PAGE78_I13@MSTR_SCONN.SCONN288_H44441003(CHIPS)':
 'DQ'<53>: CDS_PINID='DQ(53)';
NET_NAME
'M_G_DQ<54>'
 '@BASEBOARD_FAB2_LIB.BASEBOARD_FAB2(SCH_1):M_G_DQ'<54>:
 C_SIGNAL='@baseboard_fab2_lib.baseboard_fab2(sch_1):m_g_dq(54)';
NODE_NAME     U2D1 K29
 '@BASEBOARD_FAB2_LIB.BASEBOARD_FAB2(SCH_1):PAGE57_I172@CHPSET_LIB.SKX_EXT_B(CHIPS)':
 'DDR0_DQ'<54>: CDS_PINID='DDR0_DQ(54)';
NODE_NAME     J1G1 269
 '@BASEBOARD_FAB2_LIB.BASEBOARD_FAB2(SCH_1):PAGE77_I111@MSTR_SCONN.SCONN288_H44441004(CHIPS)':
 'DQ'<55>: CDS_PINID='DQ(55)';
NODE_NAME     J9T1 124
 '@BASEBOARD_FAB2_LIB.BASEBOARD_FAB2(SCH_1):PAGE78_I13@MSTR_SCONN.SCONN288_H44441003(CHIPS)':
 'DQ'<54>: CDS_PINID='DQ(54)';
NET_NAME
'M_G_DQ<55>'
 '@BASEBOARD_FAB2_LIB.BASEBOARD_FAB2(SCH_1):M_G_DQ'<55>:
 C_SIGNAL='@baseboard_fab2_lib.baseboard_fab2(sch_1):m_g_dq(55)';
NODE_NAME     U2D1 P29
 '@BASEBOARD_FAB2_LIB.BASEBOARD_FAB2(SCH_1):PAGE57_I172@CHPSET_LIB.SKX_EXT_B(CHIPS)':
 'DDR0_DQ'<55>: CDS_PINID='DDR0_DQ(55)';
NODE_NAME     J1G1 124
 '@BASEBOARD_FAB2_LIB.BASEBOARD_FAB2(SCH_1):PAGE77_I111@MSTR_SCONN.SCONN288_H44441004(CHIPS)':
 'DQ'<54>: CDS_PINID='DQ(54)';
NODE_NAME     J9T1 269
 '@BASEBOARD_FAB2_LIB.BASEBOARD_FAB2(SCH_1):PAGE78_I13@MSTR_SCONN.SCONN288_H44441003(CHIPS)':
 'DQ'<55>: CDS_PINID='DQ(55)';
NET_NAME
'M_G_DQ<56>'
 '@BASEBOARD_FAB2_LIB.BASEBOARD_FAB2(SCH_1):M_G_DQ'<56>:
 C_SIGNAL='@baseboard_fab2_lib.baseboard_fab2(sch_1):m_g_dq(56)';
NODE_NAME     U2D1 K25
 '@BASEBOARD_FAB2_LIB.BASEBOARD_FAB2(SCH_1):PAGE57_I172@CHPSET_LIB.SKX_EXT_B(CHIPS)':
 'DDR0_DQ'<56>: CDS_PINID='DDR0_DQ(56)';
NODE_NAME     J1G1 275
 '@BASEBOARD_FAB2_LIB.BASEBOARD_FAB2(SCH_1):PAGE77_I111@MSTR_SCONN.SCONN288_H44441004(CHIPS)':
 'DQ'<57>: CDS_PINID='DQ(57)';
NODE_NAME     J9T1 130
 '@BASEBOARD_FAB2_LIB.BASEBOARD_FAB2(SCH_1):PAGE78_I13@MSTR_SCONN.SCONN288_H44441003(CHIPS)':
 'DQ'<56>: CDS_PINID='DQ(56)';
NET_NAME
'M_G_DQ<57>'
 '@BASEBOARD_FAB2_LIB.BASEBOARD_FAB2(SCH_1):M_G_DQ'<57>:
 C_SIGNAL='@baseboard_fab2_lib.baseboard_fab2(sch_1):m_g_dq(57)';
NODE_NAME     U2D1 P25
 '@BASEBOARD_FAB2_LIB.BASEBOARD_FAB2(SCH_1):PAGE57_I172@CHPSET_LIB.SKX_EXT_B(CHIPS)':
 'DDR0_DQ'<57>: CDS_PINID='DDR0_DQ(57)';
NODE_NAME     J1G1 130
 '@BASEBOARD_FAB2_LIB.BASEBOARD_FAB2(SCH_1):PAGE77_I111@MSTR_SCONN.SCONN288_H44441004(CHIPS)':
 'DQ'<56>: CDS_PINID='DQ(56)';
NODE_NAME     J9T1 275
 '@BASEBOARD_FAB2_LIB.BASEBOARD_FAB2(SCH_1):PAGE78_I13@MSTR_SCONN.SCONN288_H44441003(CHIPS)':
 'DQ'<57>: CDS_PINID='DQ(57)';
NET_NAME
'M_G_DQ<58>'
 '@BASEBOARD_FAB2_LIB.BASEBOARD_FAB2(SCH_1):M_G_DQ'<58>:
 C_SIGNAL='@baseboard_fab2_lib.baseboard_fab2(sch_1):m_g_dq(58)';
NODE_NAME     U2D1 P23
 '@BASEBOARD_FAB2_LIB.BASEBOARD_FAB2(SCH_1):PAGE57_I172@CHPSET_LIB.SKX_EXT_B(CHIPS)':
 'DDR0_DQ'<58>: CDS_PINID='DDR0_DQ(58)';
NODE_NAME     J1G1 282
 '@BASEBOARD_FAB2_LIB.BASEBOARD_FAB2(SCH_1):PAGE77_I111@MSTR_SCONN.SCONN288_H44441004(CHIPS)':
 'DQ'<59>: CDS_PINID='DQ(59)';
NODE_NAME     J9T1 137
 '@BASEBOARD_FAB2_LIB.BASEBOARD_FAB2(SCH_1):PAGE78_I13@MSTR_SCONN.SCONN288_H44441003(CHIPS)':
 'DQ'<58>: CDS_PINID='DQ(58)';
NET_NAME
'M_G_DQ<59>'
 '@BASEBOARD_FAB2_LIB.BASEBOARD_FAB2(SCH_1):M_G_DQ'<59>:
 C_SIGNAL='@baseboard_fab2_lib.baseboard_fab2(sch_1):m_g_dq(59)';
NODE_NAME     U2D1 T23
 '@BASEBOARD_FAB2_LIB.BASEBOARD_FAB2(SCH_1):PAGE57_I172@CHPSET_LIB.SKX_EXT_B(CHIPS)':
 'DDR0_DQ'<59>: CDS_PINID='DDR0_DQ(59)';
NODE_NAME     J1G1 137
 '@BASEBOARD_FAB2_LIB.BASEBOARD_FAB2(SCH_1):PAGE77_I111@MSTR_SCONN.SCONN288_H44441004(CHIPS)':
 'DQ'<58>: CDS_PINID='DQ(58)';
NODE_NAME     J9T1 282
 '@BASEBOARD_FAB2_LIB.BASEBOARD_FAB2(SCH_1):PAGE78_I13@MSTR_SCONN.SCONN288_H44441003(CHIPS)':
 'DQ'<59>: CDS_PINID='DQ(59)';
NET_NAME
'M_G_DQ<5>'
 '@BASEBOARD_FAB2_LIB.BASEBOARD_FAB2(SCH_1):M_G_DQ'<5>:
 C_SIGNAL='@baseboard_fab2_lib.baseboard_fab2(sch_1):m_g_dq(5)';
NODE_NAME     U2D1 AR84
 '@BASEBOARD_FAB2_LIB.BASEBOARD_FAB2(SCH_1):PAGE57_I172@CHPSET_LIB.SKX_EXT_B(CHIPS)':
 'DDR0_DQ'<5>: CDS_PINID='DDR0_DQ(5)';
NODE_NAME     J1G1 3
 '@BASEBOARD_FAB2_LIB.BASEBOARD_FAB2(SCH_1):PAGE77_I111@MSTR_SCONN.SCONN288_H44441004(CHIPS)':
 'DQ'<4>: CDS_PINID='DQ(4)';
NODE_NAME     J9T1 148
 '@BASEBOARD_FAB2_LIB.BASEBOARD_FAB2(SCH_1):PAGE78_I13@MSTR_SCONN.SCONN288_H44441003(CHIPS)':
 'DQ'<5>: CDS_PINID='DQ(5)';
NET_NAME
'M_G_DQ<60>'
 '@BASEBOARD_FAB2_LIB.BASEBOARD_FAB2(SCH_1):M_G_DQ'<60>:
 C_SIGNAL='@baseboard_fab2_lib.baseboard_fab2(sch_1):m_g_dq(60)';
NODE_NAME     U2D1 L26
 '@BASEBOARD_FAB2_LIB.BASEBOARD_FAB2(SCH_1):PAGE57_I172@CHPSET_LIB.SKX_EXT_B(CHIPS)':
 'DDR0_DQ'<60>: CDS_PINID='DDR0_DQ(60)';
NODE_NAME     J1G1 273
 '@BASEBOARD_FAB2_LIB.BASEBOARD_FAB2(SCH_1):PAGE77_I111@MSTR_SCONN.SCONN288_H44441004(CHIPS)':
 'DQ'<61>: CDS_PINID='DQ(61)';
NODE_NAME     J9T1 128
 '@BASEBOARD_FAB2_LIB.BASEBOARD_FAB2(SCH_1):PAGE78_I13@MSTR_SCONN.SCONN288_H44441003(CHIPS)':
 'DQ'<60>: CDS_PINID='DQ(60)';
NET_NAME
'M_G_DQ<61>'
 '@BASEBOARD_FAB2_LIB.BASEBOARD_FAB2(SCH_1):M_G_DQ'<61>:
 C_SIGNAL='@baseboard_fab2_lib.baseboard_fab2(sch_1):m_g_dq(61)';
NODE_NAME     U2D1 N26
 '@BASEBOARD_FAB2_LIB.BASEBOARD_FAB2(SCH_1):PAGE57_I172@CHPSET_LIB.SKX_EXT_B(CHIPS)':
 'DDR0_DQ'<61>: CDS_PINID='DDR0_DQ(61)';
NODE_NAME     J1G1 128
 '@BASEBOARD_FAB2_LIB.BASEBOARD_FAB2(SCH_1):PAGE77_I111@MSTR_SCONN.SCONN288_H44441004(CHIPS)':
 'DQ'<60>: CDS_PINID='DQ(60)';
NODE_NAME     J9T1 273
 '@BASEBOARD_FAB2_LIB.BASEBOARD_FAB2(SCH_1):PAGE78_I13@MSTR_SCONN.SCONN288_H44441003(CHIPS)':
 'DQ'<61>: CDS_PINID='DQ(61)';
NET_NAME
'M_G_DQ<62>'
 '@BASEBOARD_FAB2_LIB.BASEBOARD_FAB2(SCH_1):M_G_DQ'<62>:
 C_SIGNAL='@baseboard_fab2_lib.baseboard_fab2(sch_1):m_g_dq(62)';
NODE_NAME     U2D1 H23
 '@BASEBOARD_FAB2_LIB.BASEBOARD_FAB2(SCH_1):PAGE57_I172@CHPSET_LIB.SKX_EXT_B(CHIPS)':
 'DDR0_DQ'<62>: CDS_PINID='DDR0_DQ(62)';
NODE_NAME     J1G1 280
 '@BASEBOARD_FAB2_LIB.BASEBOARD_FAB2(SCH_1):PAGE77_I111@MSTR_SCONN.SCONN288_H44441004(CHIPS)':
 'DQ'<63>: CDS_PINID='DQ(63)';
NODE_NAME     J9T1 135
 '@BASEBOARD_FAB2_LIB.BASEBOARD_FAB2(SCH_1):PAGE78_I13@MSTR_SCONN.SCONN288_H44441003(CHIPS)':
 'DQ'<62>: CDS_PINID='DQ(62)';
NET_NAME
'M_G_DQ<63>'
 '@BASEBOARD_FAB2_LIB.BASEBOARD_FAB2(SCH_1):M_G_DQ'<63>:
 C_SIGNAL='@baseboard_fab2_lib.baseboard_fab2(sch_1):m_g_dq(63)';
NODE_NAME     U2D1 K23
 '@BASEBOARD_FAB2_LIB.BASEBOARD_FAB2(SCH_1):PAGE57_I172@CHPSET_LIB.SKX_EXT_B(CHIPS)':
 'DDR0_DQ'<63>: CDS_PINID='DDR0_DQ(63)';
NODE_NAME     J1G1 135
 '@BASEBOARD_FAB2_LIB.BASEBOARD_FAB2(SCH_1):PAGE77_I111@MSTR_SCONN.SCONN288_H44441004(CHIPS)':
 'DQ'<62>: CDS_PINID='DQ(62)';
NODE_NAME     J9T1 280
 '@BASEBOARD_FAB2_LIB.BASEBOARD_FAB2(SCH_1):PAGE78_I13@MSTR_SCONN.SCONN288_H44441003(CHIPS)':
 'DQ'<63>: CDS_PINID='DQ(63)';
NET_NAME
'M_G_DQ<6>'
 '@BASEBOARD_FAB2_LIB.BASEBOARD_FAB2(SCH_1):M_G_DQ'<6>:
 C_SIGNAL='@baseboard_fab2_lib.baseboard_fab2(sch_1):m_g_dq(6)';
NODE_NAME     U2D1 AG86
 '@BASEBOARD_FAB2_LIB.BASEBOARD_FAB2(SCH_1):PAGE57_I172@CHPSET_LIB.SKX_EXT_B(CHIPS)':
 'DDR0_DQ'<6>: CDS_PINID='DDR0_DQ(6)';
NODE_NAME     J1G1 155
 '@BASEBOARD_FAB2_LIB.BASEBOARD_FAB2(SCH_1):PAGE77_I111@MSTR_SCONN.SCONN288_H44441004(CHIPS)':
 'DQ'<7>: CDS_PINID='DQ(7)';
NODE_NAME     J9T1 10
 '@BASEBOARD_FAB2_LIB.BASEBOARD_FAB2(SCH_1):PAGE78_I13@MSTR_SCONN.SCONN288_H44441003(CHIPS)':
 'DQ'<6>: CDS_PINID='DQ(6)';
NET_NAME
'M_G_DQ<7>'
 '@BASEBOARD_FAB2_LIB.BASEBOARD_FAB2(SCH_1):M_G_DQ'<7>:
 C_SIGNAL='@baseboard_fab2_lib.baseboard_fab2(sch_1):m_g_dq(7)';
NODE_NAME     U2D1 AG84
 '@BASEBOARD_FAB2_LIB.BASEBOARD_FAB2(SCH_1):PAGE57_I172@CHPSET_LIB.SKX_EXT_B(CHIPS)':
 'DDR0_DQ'<7>: CDS_PINID='DDR0_DQ(7)';
NODE_NAME     J1G1 10
 '@BASEBOARD_FAB2_LIB.BASEBOARD_FAB2(SCH_1):PAGE77_I111@MSTR_SCONN.SCONN288_H44441004(CHIPS)':
 'DQ'<6>: CDS_PINID='DQ(6)';
NODE_NAME     J9T1 155
 '@BASEBOARD_FAB2_LIB.BASEBOARD_FAB2(SCH_1):PAGE78_I13@MSTR_SCONN.SCONN288_H44441003(CHIPS)':
 'DQ'<7>: CDS_PINID='DQ(7)';
NET_NAME
'M_G_DQ<8>'
 '@BASEBOARD_FAB2_LIB.BASEBOARD_FAB2(SCH_1):M_G_DQ'<8>:
 C_SIGNAL='@baseboard_fab2_lib.baseboard_fab2(sch_1):m_g_dq(8)';
NODE_NAME     U2D1 W86
 '@BASEBOARD_FAB2_LIB.BASEBOARD_FAB2(SCH_1):PAGE57_I172@CHPSET_LIB.SKX_EXT_B(CHIPS)':
 'DDR0_DQ'<8>: CDS_PINID='DDR0_DQ(8)';
NODE_NAME     J1G1 161
 '@BASEBOARD_FAB2_LIB.BASEBOARD_FAB2(SCH_1):PAGE77_I111@MSTR_SCONN.SCONN288_H44441004(CHIPS)':
 'DQ'<9>: CDS_PINID='DQ(9)';
NODE_NAME     J9T1 16
 '@BASEBOARD_FAB2_LIB.BASEBOARD_FAB2(SCH_1):PAGE78_I13@MSTR_SCONN.SCONN288_H44441003(CHIPS)':
 'DQ'<8>: CDS_PINID='DQ(8)';
NET_NAME
'M_G_DQ<9>'
 '@BASEBOARD_FAB2_LIB.BASEBOARD_FAB2(SCH_1):M_G_DQ'<9>:
 C_SIGNAL='@baseboard_fab2_lib.baseboard_fab2(sch_1):m_g_dq(9)';
NODE_NAME     U2D1 W84
 '@BASEBOARD_FAB2_LIB.BASEBOARD_FAB2(SCH_1):PAGE57_I172@CHPSET_LIB.SKX_EXT_B(CHIPS)':
 'DDR0_DQ'<9>: CDS_PINID='DDR0_DQ(9)';
NODE_NAME     J1G1 16
 '@BASEBOARD_FAB2_LIB.BASEBOARD_FAB2(SCH_1):PAGE77_I111@MSTR_SCONN.SCONN288_H44441004(CHIPS)':
 'DQ'<8>: CDS_PINID='DQ(8)';
NODE_NAME     J9T1 161
 '@BASEBOARD_FAB2_LIB.BASEBOARD_FAB2(SCH_1):PAGE78_I13@MSTR_SCONN.SCONN288_H44441003(CHIPS)':
 'DQ'<9>: CDS_PINID='DQ(9)';
NET_NAME
'M_G_DQS_DN<0>'
 '@BASEBOARD_FAB2_LIB.BASEBOARD_FAB2(SCH_1):M_G_DQS_DN'<0>:
 C_SIGNAL='@baseboard_fab2_lib.baseboard_fab2(sch_1):m_g_dqs_dn(0)';
NODE_NAME     U2D1 AJ84
 '@BASEBOARD_FAB2_LIB.BASEBOARD_FAB2(SCH_1):PAGE57_I172@CHPSET_LIB.SKX_EXT_B(CHIPS)':
 'DDR0_DQS_DN'<0>: CDS_PINID='DDR0_DQS_DN(0)';
NODE_NAME     J1G1 152
 '@BASEBOARD_FAB2_LIB.BASEBOARD_FAB2(SCH_1):PAGE77_I66@MSTR_SCONN.SCONN288_H44441004(CHIPS)':
 'DQS0N': CDS_PINID='DQS0N';
NODE_NAME     J9T1 152
 '@BASEBOARD_FAB2_LIB.BASEBOARD_FAB2(SCH_1):PAGE78_I120@MSTR_SCONN.SCONN288_H44441003(CHIPS)':
 'DQS0N': CDS_PINID='DQS0N';
NET_NAME
'M_G_DQS_DN<10>'
 '@BASEBOARD_FAB2_LIB.BASEBOARD_FAB2(SCH_1):M_G_DQS_DN'<10>:
 C_SIGNAL='@baseboard_fab2_lib.baseboard_fab2(sch_1):m_g_dqs_dn(10)';
NODE_NAME     U2D1 U84
 '@BASEBOARD_FAB2_LIB.BASEBOARD_FAB2(SCH_1):PAGE57_I172@CHPSET_LIB.SKX_EXT_B(CHIPS)':
 'DDR0_DQS_DN'<10>: CDS_PINID='DDR0_DQS_DN(10)';
NODE_NAME     J1G1 19
 '@BASEBOARD_FAB2_LIB.BASEBOARD_FAB2(SCH_1):PAGE77_I66@MSTR_SCONN.SCONN288_H44441004(CHIPS)':
 'DQS10N': CDS_PINID='DQS10N';
NODE_NAME     J9T1 19
 '@BASEBOARD_FAB2_LIB.BASEBOARD_FAB2(SCH_1):PAGE78_I120@MSTR_SCONN.SCONN288_H44441003(CHIPS)':
 'DQS10N': CDS_PINID='DQS10N';
NET_NAME
'M_G_DQS_DN<11>'
 '@BASEBOARD_FAB2_LIB.BASEBOARD_FAB2(SCH_1):M_G_DQS_DN'<11>:
 C_SIGNAL='@baseboard_fab2_lib.baseboard_fab2(sch_1):m_g_dqs_dn(11)';
NODE_NAME     U2D1 U82
 '@BASEBOARD_FAB2_LIB.BASEBOARD_FAB2(SCH_1):PAGE57_I172@CHPSET_LIB.SKX_EXT_B(CHIPS)':
 'DDR0_DQS_DN'<11>: CDS_PINID='DDR0_DQS_DN(11)';
NODE_NAME     J1G1 30
 '@BASEBOARD_FAB2_LIB.BASEBOARD_FAB2(SCH_1):PAGE77_I66@MSTR_SCONN.SCONN288_H44441004(CHIPS)':
 'DQS11N': CDS_PINID='DQS11N';
NODE_NAME     J9T1 30
 '@BASEBOARD_FAB2_LIB.BASEBOARD_FAB2(SCH_1):PAGE78_I120@MSTR_SCONN.SCONN288_H44441003(CHIPS)':
 'DQS11N': CDS_PINID='DQS11N';
NET_NAME
'M_G_DQS_DN<12>'
 '@BASEBOARD_FAB2_LIB.BASEBOARD_FAB2(SCH_1):M_G_DQS_DN'<12>:
 C_SIGNAL='@baseboard_fab2_lib.baseboard_fab2(sch_1):m_g_dqs_dn(12)';
NODE_NAME     U2D1 K75
 '@BASEBOARD_FAB2_LIB.BASEBOARD_FAB2(SCH_1):PAGE57_I172@CHPSET_LIB.SKX_EXT_B(CHIPS)':
 'DDR0_DQS_DN'<12>: CDS_PINID='DDR0_DQS_DN(12)';
NODE_NAME     J1G1 41
 '@BASEBOARD_FAB2_LIB.BASEBOARD_FAB2(SCH_1):PAGE77_I66@MSTR_SCONN.SCONN288_H44441004(CHIPS)':
 'DQS12N': CDS_PINID='DQS12N';
NODE_NAME     J9T1 41
 '@BASEBOARD_FAB2_LIB.BASEBOARD_FAB2(SCH_1):PAGE78_I120@MSTR_SCONN.SCONN288_H44441003(CHIPS)':
 'DQS12N': CDS_PINID='DQS12N';
NET_NAME
'M_G_DQS_DN<13>'
 '@BASEBOARD_FAB2_LIB.BASEBOARD_FAB2(SCH_1):M_G_DQS_DN'<13>:
 C_SIGNAL='@baseboard_fab2_lib.baseboard_fab2(sch_1):m_g_dqs_dn(13)';
NODE_NAME     U2D1 A40
 '@BASEBOARD_FAB2_LIB.BASEBOARD_FAB2(SCH_1):PAGE57_I172@CHPSET_LIB.SKX_EXT_B(CHIPS)':
 'DDR0_DQS_DN'<13>: CDS_PINID='DDR0_DQS_DN(13)';
NODE_NAME     J1G1 100
 '@BASEBOARD_FAB2_LIB.BASEBOARD_FAB2(SCH_1):PAGE77_I66@MSTR_SCONN.SCONN288_H44441004(CHIPS)':
 'DQS13N': CDS_PINID='DQS13N';
NODE_NAME     J9T1 100
 '@BASEBOARD_FAB2_LIB.BASEBOARD_FAB2(SCH_1):PAGE78_I120@MSTR_SCONN.SCONN288_H44441003(CHIPS)':
 'DQS13N': CDS_PINID='DQS13N';
NET_NAME
'M_G_DQS_DN<14>'
 '@BASEBOARD_FAB2_LIB.BASEBOARD_FAB2(SCH_1):M_G_DQS_DN'<14>:
 C_SIGNAL='@baseboard_fab2_lib.baseboard_fab2(sch_1):m_g_dqs_dn(14)';
NODE_NAME     U2D1 J36
 '@BASEBOARD_FAB2_LIB.BASEBOARD_FAB2(SCH_1):PAGE57_I172@CHPSET_LIB.SKX_EXT_B(CHIPS)':
 'DDR0_DQS_DN'<14>: CDS_PINID='DDR0_DQS_DN(14)';
NODE_NAME     J1G1 111
 '@BASEBOARD_FAB2_LIB.BASEBOARD_FAB2(SCH_1):PAGE77_I66@MSTR_SCONN.SCONN288_H44441004(CHIPS)':
 'DQS14N': CDS_PINID='DQS14N';
NODE_NAME     J9T1 111
 '@BASEBOARD_FAB2_LIB.BASEBOARD_FAB2(SCH_1):PAGE78_I120@MSTR_SCONN.SCONN288_H44441003(CHIPS)':
 'DQS14N': CDS_PINID='DQS14N';
NET_NAME
'M_G_DQS_DN<15>'
 '@BASEBOARD_FAB2_LIB.BASEBOARD_FAB2(SCH_1):M_G_DQS_DN'<15>:
 C_SIGNAL='@baseboard_fab2_lib.baseboard_fab2(sch_1):m_g_dqs_dn(15)';
NODE_NAME     U2D1 J30
 '@BASEBOARD_FAB2_LIB.BASEBOARD_FAB2(SCH_1):PAGE57_I172@CHPSET_LIB.SKX_EXT_B(CHIPS)':
 'DDR0_DQS_DN'<15>: CDS_PINID='DDR0_DQS_DN(15)';
NODE_NAME     J1G1 122
 '@BASEBOARD_FAB2_LIB.BASEBOARD_FAB2(SCH_1):PAGE77_I66@MSTR_SCONN.SCONN288_H44441004(CHIPS)':
 'DQS15N': CDS_PINID='DQS15N';
NODE_NAME     J9T1 122
 '@BASEBOARD_FAB2_LIB.BASEBOARD_FAB2(SCH_1):PAGE78_I120@MSTR_SCONN.SCONN288_H44441003(CHIPS)':
 'DQS15N': CDS_PINID='DQS15N';
NET_NAME
'M_G_DQS_DN<16>'
 '@BASEBOARD_FAB2_LIB.BASEBOARD_FAB2(SCH_1):M_G_DQS_DN'<16>:
 C_SIGNAL='@baseboard_fab2_lib.baseboard_fab2(sch_1):m_g_dqs_dn(16)';
NODE_NAME     U2D1 J24
 '@BASEBOARD_FAB2_LIB.BASEBOARD_FAB2(SCH_1):PAGE57_I172@CHPSET_LIB.SKX_EXT_B(CHIPS)':
 'DDR0_DQS_DN'<16>: CDS_PINID='DDR0_DQS_DN(16)';
NODE_NAME     J1G1 133
 '@BASEBOARD_FAB2_LIB.BASEBOARD_FAB2(SCH_1):PAGE77_I66@MSTR_SCONN.SCONN288_H44441004(CHIPS)':
 'DQS16N': CDS_PINID='DQS16N';
NODE_NAME     J9T1 133
 '@BASEBOARD_FAB2_LIB.BASEBOARD_FAB2(SCH_1):PAGE78_I120@MSTR_SCONN.SCONN288_H44441003(CHIPS)':
 'DQS16N': CDS_PINID='DQS16N';
NET_NAME
'M_G_DQS_DN<17>'
 '@BASEBOARD_FAB2_LIB.BASEBOARD_FAB2(SCH_1):M_G_DQS_DN'<17>:
 C_SIGNAL='@baseboard_fab2_lib.baseboard_fab2(sch_1):m_g_dqs_dn(17)';
NODE_NAME     U2D1 AB67
 '@BASEBOARD_FAB2_LIB.BASEBOARD_FAB2(SCH_1):PAGE57_I172@CHPSET_LIB.SKX_EXT_B(CHIPS)':
 'DDR0_DQS_DN'<17>: CDS_PINID='DDR0_DQS_DN(17)';
NODE_NAME     J1G1 52
 '@BASEBOARD_FAB2_LIB.BASEBOARD_FAB2(SCH_1):PAGE77_I66@MSTR_SCONN.SCONN288_H44441004(CHIPS)':
 'DQS17N': CDS_PINID='DQS17N';
NODE_NAME     J9T1 52
 '@BASEBOARD_FAB2_LIB.BASEBOARD_FAB2(SCH_1):PAGE78_I120@MSTR_SCONN.SCONN288_H44441003(CHIPS)':
 'DQS17N': CDS_PINID='DQS17N';
NET_NAME
'M_G_DQS_DN<1>'
 '@BASEBOARD_FAB2_LIB.BASEBOARD_FAB2(SCH_1):M_G_DQS_DN'<1>:
 C_SIGNAL='@baseboard_fab2_lib.baseboard_fab2(sch_1):m_g_dqs_dn(1)';
NODE_NAME     U2D1 R84
 '@BASEBOARD_FAB2_LIB.BASEBOARD_FAB2(SCH_1):PAGE57_I172@CHPSET_LIB.SKX_EXT_B(CHIPS)':
 'DDR0_DQS_DN'<1>: CDS_PINID='DDR0_DQS_DN(1)';
NODE_NAME     J1G1 163
 '@BASEBOARD_FAB2_LIB.BASEBOARD_FAB2(SCH_1):PAGE77_I66@MSTR_SCONN.SCONN288_H44441004(CHIPS)':
 'DQS1N': CDS_PINID='DQS1N';
NODE_NAME     J9T1 163
 '@BASEBOARD_FAB2_LIB.BASEBOARD_FAB2(SCH_1):PAGE78_I120@MSTR_SCONN.SCONN288_H44441003(CHIPS)':
 'DQS1N': CDS_PINID='DQS1N';
NET_NAME
'M_G_DQS_DN<2>'
 '@BASEBOARD_FAB2_LIB.BASEBOARD_FAB2(SCH_1):M_G_DQS_DN'<2>:
 C_SIGNAL='@baseboard_fab2_lib.baseboard_fab2(sch_1):m_g_dqs_dn(2)';
NODE_NAME     U2D1 P79
 '@BASEBOARD_FAB2_LIB.BASEBOARD_FAB2(SCH_1):PAGE57_I172@CHPSET_LIB.SKX_EXT_B(CHIPS)':
 'DDR0_DQS_DN'<2>: CDS_PINID='DDR0_DQS_DN(2)';
NODE_NAME     J1G1 174
 '@BASEBOARD_FAB2_LIB.BASEBOARD_FAB2(SCH_1):PAGE77_I66@MSTR_SCONN.SCONN288_H44441004(CHIPS)':
 'DQS2N': CDS_PINID='DQS2N';
NODE_NAME     J9T1 174
 '@BASEBOARD_FAB2_LIB.BASEBOARD_FAB2(SCH_1):PAGE78_I120@MSTR_SCONN.SCONN288_H44441003(CHIPS)':
 'DQS2N': CDS_PINID='DQS2N';
NET_NAME
'M_G_DQS_DN<3>'
 '@BASEBOARD_FAB2_LIB.BASEBOARD_FAB2(SCH_1):M_G_DQS_DN'<3>:
 C_SIGNAL='@baseboard_fab2_lib.baseboard_fab2(sch_1):m_g_dqs_dn(3)';
NODE_NAME     U2D1 T75
 '@BASEBOARD_FAB2_LIB.BASEBOARD_FAB2(SCH_1):PAGE57_I172@CHPSET_LIB.SKX_EXT_B(CHIPS)':
 'DDR0_DQS_DN'<3>: CDS_PINID='DDR0_DQS_DN(3)';
NODE_NAME     J1G1 185
 '@BASEBOARD_FAB2_LIB.BASEBOARD_FAB2(SCH_1):PAGE77_I66@MSTR_SCONN.SCONN288_H44441004(CHIPS)':
 'DQS3N': CDS_PINID='DQS3N';
NODE_NAME     J9T1 185
 '@BASEBOARD_FAB2_LIB.BASEBOARD_FAB2(SCH_1):PAGE78_I120@MSTR_SCONN.SCONN288_H44441003(CHIPS)':
 'DQS3N': CDS_PINID='DQS3N';
NET_NAME
'M_G_DQS_DN<4>'
 '@BASEBOARD_FAB2_LIB.BASEBOARD_FAB2(SCH_1):M_G_DQS_DN'<4>:
 C_SIGNAL='@baseboard_fab2_lib.baseboard_fab2(sch_1):m_g_dqs_dn(4)';
NODE_NAME     U2D1 G40
 '@BASEBOARD_FAB2_LIB.BASEBOARD_FAB2(SCH_1):PAGE57_I172@CHPSET_LIB.SKX_EXT_B(CHIPS)':
 'DDR0_DQS_DN'<4>: CDS_PINID='DDR0_DQS_DN(4)';
NODE_NAME     J1G1 244
 '@BASEBOARD_FAB2_LIB.BASEBOARD_FAB2(SCH_1):PAGE77_I66@MSTR_SCONN.SCONN288_H44441004(CHIPS)':
 'DQS4N': CDS_PINID='DQS4N';
NODE_NAME     J9T1 244
 '@BASEBOARD_FAB2_LIB.BASEBOARD_FAB2(SCH_1):PAGE78_I120@MSTR_SCONN.SCONN288_H44441003(CHIPS)':
 'DQS4N': CDS_PINID='DQS4N';
NET_NAME
'M_G_DQS_DN<5>'
 '@BASEBOARD_FAB2_LIB.BASEBOARD_FAB2(SCH_1):M_G_DQS_DN'<5>:
 C_SIGNAL='@baseboard_fab2_lib.baseboard_fab2(sch_1):m_g_dqs_dn(5)';
NODE_NAME     U2D1 R36
 '@BASEBOARD_FAB2_LIB.BASEBOARD_FAB2(SCH_1):PAGE57_I172@CHPSET_LIB.SKX_EXT_B(CHIPS)':
 'DDR0_DQS_DN'<5>: CDS_PINID='DDR0_DQS_DN(5)';
NODE_NAME     J1G1 255
 '@BASEBOARD_FAB2_LIB.BASEBOARD_FAB2(SCH_1):PAGE77_I66@MSTR_SCONN.SCONN288_H44441004(CHIPS)':
 'DQS5N': CDS_PINID='DQS5N';
NODE_NAME     J9T1 255
 '@BASEBOARD_FAB2_LIB.BASEBOARD_FAB2(SCH_1):PAGE78_I120@MSTR_SCONN.SCONN288_H44441003(CHIPS)':
 'DQS5N': CDS_PINID='DQS5N';
NET_NAME
'M_G_DQS_DN<6>'
 '@BASEBOARD_FAB2_LIB.BASEBOARD_FAB2(SCH_1):M_G_DQS_DN'<6>:
 C_SIGNAL='@baseboard_fab2_lib.baseboard_fab2(sch_1):m_g_dqs_dn(6)';
NODE_NAME     U2D1 R30
 '@BASEBOARD_FAB2_LIB.BASEBOARD_FAB2(SCH_1):PAGE57_I172@CHPSET_LIB.SKX_EXT_B(CHIPS)':
 'DDR0_DQS_DN'<6>: CDS_PINID='DDR0_DQS_DN(6)';
NODE_NAME     J1G1 266
 '@BASEBOARD_FAB2_LIB.BASEBOARD_FAB2(SCH_1):PAGE77_I66@MSTR_SCONN.SCONN288_H44441004(CHIPS)':
 'DQS6N': CDS_PINID='DQS6N';
NODE_NAME     J9T1 266
 '@BASEBOARD_FAB2_LIB.BASEBOARD_FAB2(SCH_1):PAGE78_I120@MSTR_SCONN.SCONN288_H44441003(CHIPS)':
 'DQS6N': CDS_PINID='DQS6N';
NET_NAME
'M_G_DQS_DN<7>'
 '@BASEBOARD_FAB2_LIB.BASEBOARD_FAB2(SCH_1):M_G_DQS_DN'<7>:
 C_SIGNAL='@baseboard_fab2_lib.baseboard_fab2(sch_1):m_g_dqs_dn(7)';
NODE_NAME     U2D1 N24
 '@BASEBOARD_FAB2_LIB.BASEBOARD_FAB2(SCH_1):PAGE57_I172@CHPSET_LIB.SKX_EXT_B(CHIPS)':
 'DDR0_DQS_DN'<7>: CDS_PINID='DDR0_DQS_DN(7)';
NODE_NAME     J1G1 277
 '@BASEBOARD_FAB2_LIB.BASEBOARD_FAB2(SCH_1):PAGE77_I66@MSTR_SCONN.SCONN288_H44441004(CHIPS)':
 'DQS7N': CDS_PINID='DQS7N';
NODE_NAME     J9T1 277
 '@BASEBOARD_FAB2_LIB.BASEBOARD_FAB2(SCH_1):PAGE78_I120@MSTR_SCONN.SCONN288_H44441003(CHIPS)':
 'DQS7N': CDS_PINID='DQS7N';
NET_NAME
'M_G_DQS_DN<8>'
 '@BASEBOARD_FAB2_LIB.BASEBOARD_FAB2(SCH_1):M_G_DQS_DN'<8>:
 C_SIGNAL='@baseboard_fab2_lib.baseboard_fab2(sch_1):m_g_dqs_dn(8)';
NODE_NAME     U2D1 AH67
 '@BASEBOARD_FAB2_LIB.BASEBOARD_FAB2(SCH_1):PAGE57_I172@CHPSET_LIB.SKX_EXT_B(CHIPS)':
 'DDR0_DQS_DN'<8>: CDS_PINID='DDR0_DQS_DN(8)';
NODE_NAME     J1G1 196
 '@BASEBOARD_FAB2_LIB.BASEBOARD_FAB2(SCH_1):PAGE77_I66@MSTR_SCONN.SCONN288_H44441004(CHIPS)':
 'DQS8N': CDS_PINID='DQS8N';
NODE_NAME     J9T1 196
 '@BASEBOARD_FAB2_LIB.BASEBOARD_FAB2(SCH_1):PAGE78_I120@MSTR_SCONN.SCONN288_H44441003(CHIPS)':
 'DQS8N': CDS_PINID='DQS8N';
NET_NAME
'M_G_DQS_DN<9>'
 '@BASEBOARD_FAB2_LIB.BASEBOARD_FAB2(SCH_1):M_G_DQS_DN'<9>:
 C_SIGNAL='@baseboard_fab2_lib.baseboard_fab2(sch_1):m_g_dqs_dn(9)';
NODE_NAME     U2D1 AL84
 '@BASEBOARD_FAB2_LIB.BASEBOARD_FAB2(SCH_1):PAGE57_I172@CHPSET_LIB.SKX_EXT_B(CHIPS)':
 'DDR0_DQS_DN'<9>: CDS_PINID='DDR0_DQS_DN(9)';
NODE_NAME     J1G1 8
 '@BASEBOARD_FAB2_LIB.BASEBOARD_FAB2(SCH_1):PAGE77_I66@MSTR_SCONN.SCONN288_H44441004(CHIPS)':
 'DQS9N': CDS_PINID='DQS9N';
NODE_NAME     J9T1 8
 '@BASEBOARD_FAB2_LIB.BASEBOARD_FAB2(SCH_1):PAGE78_I120@MSTR_SCONN.SCONN288_H44441003(CHIPS)':
 'DQS9N': CDS_PINID='DQS9N';
NET_NAME
'M_G_DQS_DP<0>'
 '@BASEBOARD_FAB2_LIB.BASEBOARD_FAB2(SCH_1):M_G_DQS_DP'<0>:
 C_SIGNAL='@baseboard_fab2_lib.baseboard_fab2(sch_1):m_g_dqs_dp(0)';
NODE_NAME     U2D1 AH85
 '@BASEBOARD_FAB2_LIB.BASEBOARD_FAB2(SCH_1):PAGE57_I172@CHPSET_LIB.SKX_EXT_B(CHIPS)':
 'DDR0_DQS_DP'<0>: CDS_PINID='DDR0_DQS_DP(0)';
NODE_NAME     J1G1 153
 '@BASEBOARD_FAB2_LIB.BASEBOARD_FAB2(SCH_1):PAGE77_I66@MSTR_SCONN.SCONN288_H44441004(CHIPS)':
 'DQS0P': CDS_PINID='DQS0P';
NODE_NAME     J9T1 153
 '@BASEBOARD_FAB2_LIB.BASEBOARD_FAB2(SCH_1):PAGE78_I120@MSTR_SCONN.SCONN288_H44441003(CHIPS)':
 'DQS0P': CDS_PINID='DQS0P';
NET_NAME
'M_G_DQS_DP<10>'
 '@BASEBOARD_FAB2_LIB.BASEBOARD_FAB2(SCH_1):M_G_DQS_DP'<10>:
 C_SIGNAL='@baseboard_fab2_lib.baseboard_fab2(sch_1):m_g_dqs_dp(10)';
NODE_NAME     U2D1 V85
 '@BASEBOARD_FAB2_LIB.BASEBOARD_FAB2(SCH_1):PAGE57_I172@CHPSET_LIB.SKX_EXT_B(CHIPS)':
 'DDR0_DQS_DP'<10>: CDS_PINID='DDR0_DQS_DP(10)';
NODE_NAME     J1G1 18
 '@BASEBOARD_FAB2_LIB.BASEBOARD_FAB2(SCH_1):PAGE77_I66@MSTR_SCONN.SCONN288_H44441004(CHIPS)':
 'DQS10P': CDS_PINID='DQS10P';
NODE_NAME     J9T1 18
 '@BASEBOARD_FAB2_LIB.BASEBOARD_FAB2(SCH_1):PAGE78_I120@MSTR_SCONN.SCONN288_H44441003(CHIPS)':
 'DQS10P': CDS_PINID='DQS10P';
NET_NAME
'M_G_DQS_DP<11>'
 '@BASEBOARD_FAB2_LIB.BASEBOARD_FAB2(SCH_1):M_G_DQS_DP'<11>:
 C_SIGNAL='@baseboard_fab2_lib.baseboard_fab2(sch_1):m_g_dqs_dp(11)';
NODE_NAME     U2D1 T81
 '@BASEBOARD_FAB2_LIB.BASEBOARD_FAB2(SCH_1):PAGE57_I172@CHPSET_LIB.SKX_EXT_B(CHIPS)':
 'DDR0_DQS_DP'<11>: CDS_PINID='DDR0_DQS_DP(11)';
NODE_NAME     J1G1 29
 '@BASEBOARD_FAB2_LIB.BASEBOARD_FAB2(SCH_1):PAGE77_I66@MSTR_SCONN.SCONN288_H44441004(CHIPS)':
 'DQS11P': CDS_PINID='DQS11P';
NODE_NAME     J9T1 29
 '@BASEBOARD_FAB2_LIB.BASEBOARD_FAB2(SCH_1):PAGE78_I120@MSTR_SCONN.SCONN288_H44441003(CHIPS)':
 'DQS11P': CDS_PINID='DQS11P';
NET_NAME
'M_G_DQS_DP<12>'
 '@BASEBOARD_FAB2_LIB.BASEBOARD_FAB2(SCH_1):M_G_DQS_DP'<12>:
 C_SIGNAL='@baseboard_fab2_lib.baseboard_fab2(sch_1):m_g_dqs_dp(12)';
NODE_NAME     U2D1 M75
 '@BASEBOARD_FAB2_LIB.BASEBOARD_FAB2(SCH_1):PAGE57_I172@CHPSET_LIB.SKX_EXT_B(CHIPS)':
 'DDR0_DQS_DP'<12>: CDS_PINID='DDR0_DQS_DP(12)';
NODE_NAME     J1G1 40
 '@BASEBOARD_FAB2_LIB.BASEBOARD_FAB2(SCH_1):PAGE77_I66@MSTR_SCONN.SCONN288_H44441004(CHIPS)':
 'DQS12P': CDS_PINID='DQS12P';
NODE_NAME     J9T1 40
 '@BASEBOARD_FAB2_LIB.BASEBOARD_FAB2(SCH_1):PAGE78_I120@MSTR_SCONN.SCONN288_H44441003(CHIPS)':
 'DQS12P': CDS_PINID='DQS12P';
NET_NAME
'M_G_DQS_DP<13>'
 '@BASEBOARD_FAB2_LIB.BASEBOARD_FAB2(SCH_1):M_G_DQS_DP'<13>:
 C_SIGNAL='@baseboard_fab2_lib.baseboard_fab2(sch_1):m_g_dqs_dp(13)';
NODE_NAME     U2D1 C40
 '@BASEBOARD_FAB2_LIB.BASEBOARD_FAB2(SCH_1):PAGE57_I172@CHPSET_LIB.SKX_EXT_B(CHIPS)':
 'DDR0_DQS_DP'<13>: CDS_PINID='DDR0_DQS_DP(13)';
NODE_NAME     J1G1 99
 '@BASEBOARD_FAB2_LIB.BASEBOARD_FAB2(SCH_1):PAGE77_I66@MSTR_SCONN.SCONN288_H44441004(CHIPS)':
 'DQS13P': CDS_PINID='DQS13P';
NODE_NAME     J9T1 99
 '@BASEBOARD_FAB2_LIB.BASEBOARD_FAB2(SCH_1):PAGE78_I120@MSTR_SCONN.SCONN288_H44441003(CHIPS)':
 'DQS13P': CDS_PINID='DQS13P';
NET_NAME
'M_G_DQS_DP<14>'
 '@BASEBOARD_FAB2_LIB.BASEBOARD_FAB2(SCH_1):M_G_DQS_DP'<14>:
 C_SIGNAL='@baseboard_fab2_lib.baseboard_fab2(sch_1):m_g_dqs_dp(14)';
NODE_NAME     U2D1 L36
 '@BASEBOARD_FAB2_LIB.BASEBOARD_FAB2(SCH_1):PAGE57_I172@CHPSET_LIB.SKX_EXT_B(CHIPS)':
 'DDR0_DQS_DP'<14>: CDS_PINID='DDR0_DQS_DP(14)';
NODE_NAME     J1G1 110
 '@BASEBOARD_FAB2_LIB.BASEBOARD_FAB2(SCH_1):PAGE77_I66@MSTR_SCONN.SCONN288_H44441004(CHIPS)':
 'DQS14P': CDS_PINID='DQS14P';
NODE_NAME     J9T1 110
 '@BASEBOARD_FAB2_LIB.BASEBOARD_FAB2(SCH_1):PAGE78_I120@MSTR_SCONN.SCONN288_H44441003(CHIPS)':
 'DQS14P': CDS_PINID='DQS14P';
NET_NAME
'M_G_DQS_DP<15>'
 '@BASEBOARD_FAB2_LIB.BASEBOARD_FAB2(SCH_1):M_G_DQS_DP'<15>:
 C_SIGNAL='@baseboard_fab2_lib.baseboard_fab2(sch_1):m_g_dqs_dp(15)';
NODE_NAME     U2D1 L30
 '@BASEBOARD_FAB2_LIB.BASEBOARD_FAB2(SCH_1):PAGE57_I172@CHPSET_LIB.SKX_EXT_B(CHIPS)':
 'DDR0_DQS_DP'<15>: CDS_PINID='DDR0_DQS_DP(15)';
NODE_NAME     J1G1 121
 '@BASEBOARD_FAB2_LIB.BASEBOARD_FAB2(SCH_1):PAGE77_I66@MSTR_SCONN.SCONN288_H44441004(CHIPS)':
 'DQS15P': CDS_PINID='DQS15P';
NODE_NAME     J9T1 121
 '@BASEBOARD_FAB2_LIB.BASEBOARD_FAB2(SCH_1):PAGE78_I120@MSTR_SCONN.SCONN288_H44441003(CHIPS)':
 'DQS15P': CDS_PINID='DQS15P';
NET_NAME
'M_G_DQS_DP<16>'
 '@BASEBOARD_FAB2_LIB.BASEBOARD_FAB2(SCH_1):M_G_DQS_DP'<16>:
 C_SIGNAL='@baseboard_fab2_lib.baseboard_fab2(sch_1):m_g_dqs_dp(16)';
NODE_NAME     U2D1 L24
 '@BASEBOARD_FAB2_LIB.BASEBOARD_FAB2(SCH_1):PAGE57_I172@CHPSET_LIB.SKX_EXT_B(CHIPS)':
 'DDR0_DQS_DP'<16>: CDS_PINID='DDR0_DQS_DP(16)';
NODE_NAME     J1G1 132
 '@BASEBOARD_FAB2_LIB.BASEBOARD_FAB2(SCH_1):PAGE77_I66@MSTR_SCONN.SCONN288_H44441004(CHIPS)':
 'DQS16P': CDS_PINID='DQS16P';
NODE_NAME     J9T1 132
 '@BASEBOARD_FAB2_LIB.BASEBOARD_FAB2(SCH_1):PAGE78_I120@MSTR_SCONN.SCONN288_H44441003(CHIPS)':
 'DQS16P': CDS_PINID='DQS16P';
NET_NAME
'M_G_DQS_DP<17>'
 '@BASEBOARD_FAB2_LIB.BASEBOARD_FAB2(SCH_1):M_G_DQS_DP'<17>:
 C_SIGNAL='@baseboard_fab2_lib.baseboard_fab2(sch_1):m_g_dqs_dp(17)';
NODE_NAME     U2D1 AD67
 '@BASEBOARD_FAB2_LIB.BASEBOARD_FAB2(SCH_1):PAGE57_I172@CHPSET_LIB.SKX_EXT_B(CHIPS)':
 'DDR0_DQS_DP'<17>: CDS_PINID='DDR0_DQS_DP(17)';
NODE_NAME     J1G1 51
 '@BASEBOARD_FAB2_LIB.BASEBOARD_FAB2(SCH_1):PAGE77_I66@MSTR_SCONN.SCONN288_H44441004(CHIPS)':
 'DQS17P': CDS_PINID='DQS17P';
NODE_NAME     J9T1 51
 '@BASEBOARD_FAB2_LIB.BASEBOARD_FAB2(SCH_1):PAGE78_I120@MSTR_SCONN.SCONN288_H44441003(CHIPS)':
 'DQS17P': CDS_PINID='DQS17P';
NET_NAME
'M_G_DQS_DP<1>'
 '@BASEBOARD_FAB2_LIB.BASEBOARD_FAB2(SCH_1):M_G_DQS_DP'<1>:
 C_SIGNAL='@baseboard_fab2_lib.baseboard_fab2(sch_1):m_g_dqs_dp(1)';
NODE_NAME     U2D1 P85
 '@BASEBOARD_FAB2_LIB.BASEBOARD_FAB2(SCH_1):PAGE57_I172@CHPSET_LIB.SKX_EXT_B(CHIPS)':
 'DDR0_DQS_DP'<1>: CDS_PINID='DDR0_DQS_DP(1)';
NODE_NAME     J1G1 164
 '@BASEBOARD_FAB2_LIB.BASEBOARD_FAB2(SCH_1):PAGE77_I66@MSTR_SCONN.SCONN288_H44441004(CHIPS)':
 'DQS1P': CDS_PINID='DQS1P';
NODE_NAME     J9T1 164
 '@BASEBOARD_FAB2_LIB.BASEBOARD_FAB2(SCH_1):PAGE78_I120@MSTR_SCONN.SCONN288_H44441003(CHIPS)':
 'DQS1P': CDS_PINID='DQS1P';
NET_NAME
'M_G_DQS_DP<2>'
 '@BASEBOARD_FAB2_LIB.BASEBOARD_FAB2(SCH_1):M_G_DQS_DP'<2>:
 C_SIGNAL='@baseboard_fab2_lib.baseboard_fab2(sch_1):m_g_dqs_dp(2)';
NODE_NAME     U2D1 R80
 '@BASEBOARD_FAB2_LIB.BASEBOARD_FAB2(SCH_1):PAGE57_I172@CHPSET_LIB.SKX_EXT_B(CHIPS)':
 'DDR0_DQS_DP'<2>: CDS_PINID='DDR0_DQS_DP(2)';
NODE_NAME     J1G1 175
 '@BASEBOARD_FAB2_LIB.BASEBOARD_FAB2(SCH_1):PAGE77_I66@MSTR_SCONN.SCONN288_H44441004(CHIPS)':
 'DQS2P': CDS_PINID='DQS2P';
NODE_NAME     J9T1 175
 '@BASEBOARD_FAB2_LIB.BASEBOARD_FAB2(SCH_1):PAGE78_I120@MSTR_SCONN.SCONN288_H44441003(CHIPS)':
 'DQS2P': CDS_PINID='DQS2P';
NET_NAME
'M_G_DQS_DP<3>'
 '@BASEBOARD_FAB2_LIB.BASEBOARD_FAB2(SCH_1):M_G_DQS_DP'<3>:
 C_SIGNAL='@baseboard_fab2_lib.baseboard_fab2(sch_1):m_g_dqs_dp(3)';
NODE_NAME     U2D1 P75
 '@BASEBOARD_FAB2_LIB.BASEBOARD_FAB2(SCH_1):PAGE57_I172@CHPSET_LIB.SKX_EXT_B(CHIPS)':
 'DDR0_DQS_DP'<3>: CDS_PINID='DDR0_DQS_DP(3)';
NODE_NAME     J1G1 186
 '@BASEBOARD_FAB2_LIB.BASEBOARD_FAB2(SCH_1):PAGE77_I66@MSTR_SCONN.SCONN288_H44441004(CHIPS)':
 'DQS3P': CDS_PINID='DQS3P';
NODE_NAME     J9T1 186
 '@BASEBOARD_FAB2_LIB.BASEBOARD_FAB2(SCH_1):PAGE78_I120@MSTR_SCONN.SCONN288_H44441003(CHIPS)':
 'DQS3P': CDS_PINID='DQS3P';
NET_NAME
'M_G_DQS_DP<4>'
 '@BASEBOARD_FAB2_LIB.BASEBOARD_FAB2(SCH_1):M_G_DQS_DP'<4>:
 C_SIGNAL='@baseboard_fab2_lib.baseboard_fab2(sch_1):m_g_dqs_dp(4)';
NODE_NAME     U2D1 E40
 '@BASEBOARD_FAB2_LIB.BASEBOARD_FAB2(SCH_1):PAGE57_I172@CHPSET_LIB.SKX_EXT_B(CHIPS)':
 'DDR0_DQS_DP'<4>: CDS_PINID='DDR0_DQS_DP(4)';
NODE_NAME     J1G1 245
 '@BASEBOARD_FAB2_LIB.BASEBOARD_FAB2(SCH_1):PAGE77_I66@MSTR_SCONN.SCONN288_H44441004(CHIPS)':
 'DQS4P': CDS_PINID='DQS4P';
NODE_NAME     J9T1 245
 '@BASEBOARD_FAB2_LIB.BASEBOARD_FAB2(SCH_1):PAGE78_I120@MSTR_SCONN.SCONN288_H44441003(CHIPS)':
 'DQS4P': CDS_PINID='DQS4P';
NET_NAME
'M_G_DQS_DP<5>'
 '@BASEBOARD_FAB2_LIB.BASEBOARD_FAB2(SCH_1):M_G_DQS_DP'<5>:
 C_SIGNAL='@baseboard_fab2_lib.baseboard_fab2(sch_1):m_g_dqs_dp(5)';
NODE_NAME     U2D1 N36
 '@BASEBOARD_FAB2_LIB.BASEBOARD_FAB2(SCH_1):PAGE57_I172@CHPSET_LIB.SKX_EXT_B(CHIPS)':
 'DDR0_DQS_DP'<5>: CDS_PINID='DDR0_DQS_DP(5)';
NODE_NAME     J1G1 256
 '@BASEBOARD_FAB2_LIB.BASEBOARD_FAB2(SCH_1):PAGE77_I66@MSTR_SCONN.SCONN288_H44441004(CHIPS)':
 'DQS5P': CDS_PINID='DQS5P';
NODE_NAME     J9T1 256
 '@BASEBOARD_FAB2_LIB.BASEBOARD_FAB2(SCH_1):PAGE78_I120@MSTR_SCONN.SCONN288_H44441003(CHIPS)':
 'DQS5P': CDS_PINID='DQS5P';
NET_NAME
'M_G_DQS_DP<6>'
 '@BASEBOARD_FAB2_LIB.BASEBOARD_FAB2(SCH_1):M_G_DQS_DP'<6>:
 C_SIGNAL='@baseboard_fab2_lib.baseboard_fab2(sch_1):m_g_dqs_dp(6)';
NODE_NAME     U2D1 N30
 '@BASEBOARD_FAB2_LIB.BASEBOARD_FAB2(SCH_1):PAGE57_I172@CHPSET_LIB.SKX_EXT_B(CHIPS)':
 'DDR0_DQS_DP'<6>: CDS_PINID='DDR0_DQS_DP(6)';
NODE_NAME     J1G1 267
 '@BASEBOARD_FAB2_LIB.BASEBOARD_FAB2(SCH_1):PAGE77_I66@MSTR_SCONN.SCONN288_H44441004(CHIPS)':
 'DQS6P': CDS_PINID='DQS6P';
NODE_NAME     J9T1 267
 '@BASEBOARD_FAB2_LIB.BASEBOARD_FAB2(SCH_1):PAGE78_I120@MSTR_SCONN.SCONN288_H44441003(CHIPS)':
 'DQS6P': CDS_PINID='DQS6P';
NET_NAME
'M_G_DQS_DP<7>'
 '@BASEBOARD_FAB2_LIB.BASEBOARD_FAB2(SCH_1):M_G_DQS_DP'<7>:
 C_SIGNAL='@baseboard_fab2_lib.baseboard_fab2(sch_1):m_g_dqs_dp(7)';
NODE_NAME     U2D1 R24
 '@BASEBOARD_FAB2_LIB.BASEBOARD_FAB2(SCH_1):PAGE57_I172@CHPSET_LIB.SKX_EXT_B(CHIPS)':
 'DDR0_DQS_DP'<7>: CDS_PINID='DDR0_DQS_DP(7)';
NODE_NAME     J1G1 278
 '@BASEBOARD_FAB2_LIB.BASEBOARD_FAB2(SCH_1):PAGE77_I66@MSTR_SCONN.SCONN288_H44441004(CHIPS)':
 'DQS7P': CDS_PINID='DQS7P';
NODE_NAME     J9T1 278
 '@BASEBOARD_FAB2_LIB.BASEBOARD_FAB2(SCH_1):PAGE78_I120@MSTR_SCONN.SCONN288_H44441003(CHIPS)':
 'DQS7P': CDS_PINID='DQS7P';
NET_NAME
'M_G_DQS_DP<8>'
 '@BASEBOARD_FAB2_LIB.BASEBOARD_FAB2(SCH_1):M_G_DQS_DP'<8>:
 C_SIGNAL='@baseboard_fab2_lib.baseboard_fab2(sch_1):m_g_dqs_dp(8)';
NODE_NAME     U2D1 AF67
 '@BASEBOARD_FAB2_LIB.BASEBOARD_FAB2(SCH_1):PAGE57_I172@CHPSET_LIB.SKX_EXT_B(CHIPS)':
 'DDR0_DQS_DP'<8>: CDS_PINID='DDR0_DQS_DP(8)';
NODE_NAME     J1G1 197
 '@BASEBOARD_FAB2_LIB.BASEBOARD_FAB2(SCH_1):PAGE77_I66@MSTR_SCONN.SCONN288_H44441004(CHIPS)':
 'DQS8P': CDS_PINID='DQS8P';
NODE_NAME     J9T1 197
 '@BASEBOARD_FAB2_LIB.BASEBOARD_FAB2(SCH_1):PAGE78_I120@MSTR_SCONN.SCONN288_H44441003(CHIPS)':
 'DQS8P': CDS_PINID='DQS8P';
NET_NAME
'M_G_DQS_DP<9>'
 '@BASEBOARD_FAB2_LIB.BASEBOARD_FAB2(SCH_1):M_G_DQS_DP'<9>:
 C_SIGNAL='@baseboard_fab2_lib.baseboard_fab2(sch_1):m_g_dqs_dp(9)';
NODE_NAME     U2D1 AM85
 '@BASEBOARD_FAB2_LIB.BASEBOARD_FAB2(SCH_1):PAGE57_I172@CHPSET_LIB.SKX_EXT_B(CHIPS)':
 'DDR0_DQS_DP'<9>: CDS_PINID='DDR0_DQS_DP(9)';
NODE_NAME     J1G1 7
 '@BASEBOARD_FAB2_LIB.BASEBOARD_FAB2(SCH_1):PAGE77_I66@MSTR_SCONN.SCONN288_H44441004(CHIPS)':
 'DQS9P': CDS_PINID='DQS9P';
NODE_NAME     J9T1 7
 '@BASEBOARD_FAB2_LIB.BASEBOARD_FAB2(SCH_1):PAGE78_I120@MSTR_SCONN.SCONN288_H44441003(CHIPS)':
 'DQS9P': CDS_PINID='DQS9P';
NET_NAME
'M_G_ECC<0>'
 '@BASEBOARD_FAB2_LIB.BASEBOARD_FAB2(SCH_1):M_G_ECC'<0>:
 C_SIGNAL='@baseboard_fab2_lib.baseboard_fab2(sch_1):m_g_ecc(0)';
NODE_NAME     U2D1 AC68
 '@BASEBOARD_FAB2_LIB.BASEBOARD_FAB2(SCH_1):PAGE57_I172@CHPSET_LIB.SKX_EXT_B(CHIPS)':
 'DDR0_ECC'<0>: CDS_PINID='DDR0_ECC(0)';
NODE_NAME     J1G1 194
 '@BASEBOARD_FAB2_LIB.BASEBOARD_FAB2(SCH_1):PAGE77_I111@MSTR_SCONN.SCONN288_H44441004(CHIPS)':
 'CB'<1>: CDS_PINID='CB(1)';
NODE_NAME     J9T1 49
 '@BASEBOARD_FAB2_LIB.BASEBOARD_FAB2(SCH_1):PAGE78_I13@MSTR_SCONN.SCONN288_H44441003(CHIPS)':
 'CB'<0>: CDS_PINID='CB(0)';
NET_NAME
'M_G_ECC<1>'
 '@BASEBOARD_FAB2_LIB.BASEBOARD_FAB2(SCH_1):M_G_ECC'<1>:
 C_SIGNAL='@baseboard_fab2_lib.baseboard_fab2(sch_1):m_g_ecc(1)';
NODE_NAME     U2D1 AG68
 '@BASEBOARD_FAB2_LIB.BASEBOARD_FAB2(SCH_1):PAGE57_I172@CHPSET_LIB.SKX_EXT_B(CHIPS)':
 'DDR0_ECC'<1>: CDS_PINID='DDR0_ECC(1)';
NODE_NAME     J1G1 49
 '@BASEBOARD_FAB2_LIB.BASEBOARD_FAB2(SCH_1):PAGE77_I111@MSTR_SCONN.SCONN288_H44441004(CHIPS)':
 'CB'<0>: CDS_PINID='CB(0)';
NODE_NAME     J9T1 194
 '@BASEBOARD_FAB2_LIB.BASEBOARD_FAB2(SCH_1):PAGE78_I13@MSTR_SCONN.SCONN288_H44441003(CHIPS)':
 'CB'<1>: CDS_PINID='CB(1)';
NET_NAME
'M_G_ECC<2>'
 '@BASEBOARD_FAB2_LIB.BASEBOARD_FAB2(SCH_1):M_G_ECC'<2>:
 C_SIGNAL='@baseboard_fab2_lib.baseboard_fab2(sch_1):m_g_ecc(2)';
NODE_NAME     U2D1 AD65
 '@BASEBOARD_FAB2_LIB.BASEBOARD_FAB2(SCH_1):PAGE57_I172@CHPSET_LIB.SKX_EXT_B(CHIPS)':
 'DDR0_ECC'<2>: CDS_PINID='DDR0_ECC(2)';
NODE_NAME     J1G1 201
 '@BASEBOARD_FAB2_LIB.BASEBOARD_FAB2(SCH_1):PAGE77_I111@MSTR_SCONN.SCONN288_H44441004(CHIPS)':
 'CB'<3>: CDS_PINID='CB(3)';
NODE_NAME     J9T1 56
 '@BASEBOARD_FAB2_LIB.BASEBOARD_FAB2(SCH_1):PAGE78_I13@MSTR_SCONN.SCONN288_H44441003(CHIPS)':
 'CB'<2>: CDS_PINID='CB(2)';
NET_NAME
'M_G_ECC<3>'
 '@BASEBOARD_FAB2_LIB.BASEBOARD_FAB2(SCH_1):M_G_ECC'<3>:
 C_SIGNAL='@baseboard_fab2_lib.baseboard_fab2(sch_1):m_g_ecc(3)';
NODE_NAME     U2D1 AF65
 '@BASEBOARD_FAB2_LIB.BASEBOARD_FAB2(SCH_1):PAGE57_I172@CHPSET_LIB.SKX_EXT_B(CHIPS)':
 'DDR0_ECC'<3>: CDS_PINID='DDR0_ECC(3)';
NODE_NAME     J1G1 56
 '@BASEBOARD_FAB2_LIB.BASEBOARD_FAB2(SCH_1):PAGE77_I111@MSTR_SCONN.SCONN288_H44441004(CHIPS)':
 'CB'<2>: CDS_PINID='CB(2)';
NODE_NAME     J9T1 201
 '@BASEBOARD_FAB2_LIB.BASEBOARD_FAB2(SCH_1):PAGE78_I13@MSTR_SCONN.SCONN288_H44441003(CHIPS)':
 'CB'<3>: CDS_PINID='CB(3)';
NET_NAME
'M_G_ECC<4>'
 '@BASEBOARD_FAB2_LIB.BASEBOARD_FAB2(SCH_1):M_G_ECC'<4>:
 C_SIGNAL='@baseboard_fab2_lib.baseboard_fab2(sch_1):m_g_ecc(4)';
NODE_NAME     U2D1 AD69
 '@BASEBOARD_FAB2_LIB.BASEBOARD_FAB2(SCH_1):PAGE57_I172@CHPSET_LIB.SKX_EXT_B(CHIPS)':
 'DDR0_ECC'<4>: CDS_PINID='DDR0_ECC(4)';
NODE_NAME     J1G1 192
 '@BASEBOARD_FAB2_LIB.BASEBOARD_FAB2(SCH_1):PAGE77_I111@MSTR_SCONN.SCONN288_H44441004(CHIPS)':
 'CB'<5>: CDS_PINID='CB(5)';
NODE_NAME     J9T1 47
 '@BASEBOARD_FAB2_LIB.BASEBOARD_FAB2(SCH_1):PAGE78_I13@MSTR_SCONN.SCONN288_H44441003(CHIPS)':
 'CB'<4>: CDS_PINID='CB(4)';
NET_NAME
'M_G_ECC<5>'
 '@BASEBOARD_FAB2_LIB.BASEBOARD_FAB2(SCH_1):M_G_ECC'<5>:
 C_SIGNAL='@baseboard_fab2_lib.baseboard_fab2(sch_1):m_g_ecc(5)';
NODE_NAME     U2D1 AF69
 '@BASEBOARD_FAB2_LIB.BASEBOARD_FAB2(SCH_1):PAGE57_I172@CHPSET_LIB.SKX_EXT_B(CHIPS)':
 'DDR0_ECC'<5>: CDS_PINID='DDR0_ECC(5)';
NODE_NAME     J1G1 47
 '@BASEBOARD_FAB2_LIB.BASEBOARD_FAB2(SCH_1):PAGE77_I111@MSTR_SCONN.SCONN288_H44441004(CHIPS)':
 'CB'<4>: CDS_PINID='CB(4)';
NODE_NAME     J9T1 192
 '@BASEBOARD_FAB2_LIB.BASEBOARD_FAB2(SCH_1):PAGE78_I13@MSTR_SCONN.SCONN288_H44441003(CHIPS)':
 'CB'<5>: CDS_PINID='CB(5)';
NET_NAME
'M_G_ECC<6>'
 '@BASEBOARD_FAB2_LIB.BASEBOARD_FAB2(SCH_1):M_G_ECC'<6>:
 C_SIGNAL='@baseboard_fab2_lib.baseboard_fab2(sch_1):m_g_ecc(6)';
NODE_NAME     U2D1 AC66
 '@BASEBOARD_FAB2_LIB.BASEBOARD_FAB2(SCH_1):PAGE57_I172@CHPSET_LIB.SKX_EXT_B(CHIPS)':
 'DDR0_ECC'<6>: CDS_PINID='DDR0_ECC(6)';
NODE_NAME     J1G1 199
 '@BASEBOARD_FAB2_LIB.BASEBOARD_FAB2(SCH_1):PAGE77_I111@MSTR_SCONN.SCONN288_H44441004(CHIPS)':
 'CB'<7>: CDS_PINID='CB(7)';
NODE_NAME     J9T1 54
 '@BASEBOARD_FAB2_LIB.BASEBOARD_FAB2(SCH_1):PAGE78_I13@MSTR_SCONN.SCONN288_H44441003(CHIPS)':
 'CB'<6>: CDS_PINID='CB(6)';
NET_NAME
'M_G_ECC<7>'
 '@BASEBOARD_FAB2_LIB.BASEBOARD_FAB2(SCH_1):M_G_ECC'<7>:
 C_SIGNAL='@baseboard_fab2_lib.baseboard_fab2(sch_1):m_g_ecc(7)';
NODE_NAME     U2D1 AG66
 '@BASEBOARD_FAB2_LIB.BASEBOARD_FAB2(SCH_1):PAGE57_I172@CHPSET_LIB.SKX_EXT_B(CHIPS)':
 'DDR0_ECC'<7>: CDS_PINID='DDR0_ECC(7)';
NODE_NAME     J1G1 54
 '@BASEBOARD_FAB2_LIB.BASEBOARD_FAB2(SCH_1):PAGE77_I111@MSTR_SCONN.SCONN288_H44441004(CHIPS)':
 'CB'<6>: CDS_PINID='CB(6)';
NODE_NAME     J9T1 199
 '@BASEBOARD_FAB2_LIB.BASEBOARD_FAB2(SCH_1):PAGE78_I13@MSTR_SCONN.SCONN288_H44441003(CHIPS)':
 'CB'<7>: CDS_PINID='CB(7)';
NET_NAME
'M_G_MA<0>'
 '@BASEBOARD_FAB2_LIB.BASEBOARD_FAB2(SCH_1):M_G_MA'<0>:
 C_SIGNAL='@baseboard_fab2_lib.baseboard_fab2(sch_1):m_g_ma(0)';
NODE_NAME     U2D1 F53
 '@BASEBOARD_FAB2_LIB.BASEBOARD_FAB2(SCH_1):PAGE57_I172@CHPSET_LIB.SKX_EXT_B(CHIPS)':
 'DDR0_MA'<0>: CDS_PINID='DDR0_MA(0)';
NODE_NAME     J1G1 79
 '@BASEBOARD_FAB2_LIB.BASEBOARD_FAB2(SCH_1):PAGE77_I111@MSTR_SCONN.SCONN288_H44441004(CHIPS)':
 'A0': CDS_PINID='A0';
NODE_NAME     J9T1 79
 '@BASEBOARD_FAB2_LIB.BASEBOARD_FAB2(SCH_1):PAGE78_I13@MSTR_SCONN.SCONN288_H44441003(CHIPS)':
 'A0': CDS_PINID='A0';
NET_NAME
'M_G_MA<10>'
 '@BASEBOARD_FAB2_LIB.BASEBOARD_FAB2(SCH_1):M_G_MA'<10>:
 C_SIGNAL='@baseboard_fab2_lib.baseboard_fab2(sch_1):m_g_ma(10)';
NODE_NAME     U2D1 J54
 '@BASEBOARD_FAB2_LIB.BASEBOARD_FAB2(SCH_1):PAGE57_I172@CHPSET_LIB.SKX_EXT_B(CHIPS)':
 'DDR0_MA'<10>: CDS_PINID='DDR0_MA(10)';
NODE_NAME     J1G1 225
 '@BASEBOARD_FAB2_LIB.BASEBOARD_FAB2(SCH_1):PAGE77_I111@MSTR_SCONN.SCONN288_H44441004(CHIPS)':
 'A10': CDS_PINID='A10';
NODE_NAME     J9T1 225
 '@BASEBOARD_FAB2_LIB.BASEBOARD_FAB2(SCH_1):PAGE78_I13@MSTR_SCONN.SCONN288_H44441003(CHIPS)':
 'A10': CDS_PINID='A10';
NET_NAME
'M_G_MA<11>'
 '@BASEBOARD_FAB2_LIB.BASEBOARD_FAB2(SCH_1):M_G_MA'<11>:
 C_SIGNAL='@baseboard_fab2_lib.baseboard_fab2(sch_1):m_g_ma(11)';
NODE_NAME     U2D1 G62
 '@BASEBOARD_FAB2_LIB.BASEBOARD_FAB2(SCH_1):PAGE57_I172@CHPSET_LIB.SKX_EXT_B(CHIPS)':
 'DDR0_MA'<11>: CDS_PINID='DDR0_MA(11)';
NODE_NAME     J1G1 210
 '@BASEBOARD_FAB2_LIB.BASEBOARD_FAB2(SCH_1):PAGE77_I111@MSTR_SCONN.SCONN288_H44441004(CHIPS)':
 'A11': CDS_PINID='A11';
NODE_NAME     J9T1 210
 '@BASEBOARD_FAB2_LIB.BASEBOARD_FAB2(SCH_1):PAGE78_I13@MSTR_SCONN.SCONN288_H44441003(CHIPS)':
 'A11': CDS_PINID='A11';
NET_NAME
'M_G_MA<12>'
 '@BASEBOARD_FAB2_LIB.BASEBOARD_FAB2(SCH_1):M_G_MA'<12>:
 C_SIGNAL='@baseboard_fab2_lib.baseboard_fab2(sch_1):m_g_ma(12)';
NODE_NAME     U2D1 J64
 '@BASEBOARD_FAB2_LIB.BASEBOARD_FAB2(SCH_1):PAGE57_I172@CHPSET_LIB.SKX_EXT_B(CHIPS)':
 'DDR0_MA'<12>: CDS_PINID='DDR0_MA(12)';
NODE_NAME     J1G1 65
 '@BASEBOARD_FAB2_LIB.BASEBOARD_FAB2(SCH_1):PAGE77_I111@MSTR_SCONN.SCONN288_H44441004(CHIPS)':
 'A12': CDS_PINID='A12';
NODE_NAME     J9T1 65
 '@BASEBOARD_FAB2_LIB.BASEBOARD_FAB2(SCH_1):PAGE78_I13@MSTR_SCONN.SCONN288_H44441003(CHIPS)':
 'A12': CDS_PINID='A12';
NET_NAME
'M_G_MA<13>'
 '@BASEBOARD_FAB2_LIB.BASEBOARD_FAB2(SCH_1):M_G_MA'<13>:
 C_SIGNAL='@baseboard_fab2_lib.baseboard_fab2(sch_1):m_g_ma(13)';
NODE_NAME     U2D1 J48
 '@BASEBOARD_FAB2_LIB.BASEBOARD_FAB2(SCH_1):PAGE57_I172@CHPSET_LIB.SKX_EXT_B(CHIPS)':
 'DDR0_MA'<13>: CDS_PINID='DDR0_MA(13)';
NODE_NAME     J1G1 232
 '@BASEBOARD_FAB2_LIB.BASEBOARD_FAB2(SCH_1):PAGE77_I111@MSTR_SCONN.SCONN288_H44441004(CHIPS)':
 'A13': CDS_PINID='A13';
NODE_NAME     J9T1 232
 '@BASEBOARD_FAB2_LIB.BASEBOARD_FAB2(SCH_1):PAGE78_I13@MSTR_SCONN.SCONN288_H44441003(CHIPS)':
 'A13': CDS_PINID='A13';
NET_NAME
'M_G_MA<14>'
 '@BASEBOARD_FAB2_LIB.BASEBOARD_FAB2(SCH_1):M_G_MA'<14>:
 C_SIGNAL='@baseboard_fab2_lib.baseboard_fab2(sch_1):m_g_ma(14)';
NODE_NAME     U2D1 F51
 '@BASEBOARD_FAB2_LIB.BASEBOARD_FAB2(SCH_1):PAGE57_I172@CHPSET_LIB.SKX_EXT_B(CHIPS)':
 'DDR0_MA'<14>: CDS_PINID='DDR0_MA(14)';
NODE_NAME     J1G1 228
 '@BASEBOARD_FAB2_LIB.BASEBOARD_FAB2(SCH_1):PAGE77_I111@MSTR_SCONN.SCONN288_H44441004(CHIPS)':
 'A14_WE_N': CDS_PINID='A14_WE_N';
NODE_NAME     J9T1 228
 '@BASEBOARD_FAB2_LIB.BASEBOARD_FAB2(SCH_1):PAGE78_I13@MSTR_SCONN.SCONN288_H44441003(CHIPS)':
 'A14_WE_N': CDS_PINID='A14_WE_N';
NET_NAME
'M_G_MA<15>'
 '@BASEBOARD_FAB2_LIB.BASEBOARD_FAB2(SCH_1):M_G_MA'<15>:
 C_SIGNAL='@baseboard_fab2_lib.baseboard_fab2(sch_1):m_g_ma(15)';
NODE_NAME     U2D1 K49
 '@BASEBOARD_FAB2_LIB.BASEBOARD_FAB2(SCH_1):PAGE57_I172@CHPSET_LIB.SKX_EXT_B(CHIPS)':
 'DDR0_MA'<15>: CDS_PINID='DDR0_MA(15)';
NODE_NAME     J1G1 86
 '@BASEBOARD_FAB2_LIB.BASEBOARD_FAB2(SCH_1):PAGE77_I111@MSTR_SCONN.SCONN288_H44441004(CHIPS)':
 'A15_CAS_N': CDS_PINID='A15_CAS_N';
NODE_NAME     J9T1 86
 '@BASEBOARD_FAB2_LIB.BASEBOARD_FAB2(SCH_1):PAGE78_I13@MSTR_SCONN.SCONN288_H44441003(CHIPS)':
 'A15_CAS_N': CDS_PINID='A15_CAS_N';
NET_NAME
'M_G_MA<16>'
 '@BASEBOARD_FAB2_LIB.BASEBOARD_FAB2(SCH_1):M_G_MA'<16>:
 C_SIGNAL='@baseboard_fab2_lib.baseboard_fab2(sch_1):m_g_ma(16)';
NODE_NAME     U2D1 D51
 '@BASEBOARD_FAB2_LIB.BASEBOARD_FAB2(SCH_1):PAGE57_I172@CHPSET_LIB.SKX_EXT_B(CHIPS)':
 'DDR0_MA'<16>: CDS_PINID='DDR0_MA(16)';
NODE_NAME     J1G1 82
 '@BASEBOARD_FAB2_LIB.BASEBOARD_FAB2(SCH_1):PAGE77_I111@MSTR_SCONN.SCONN288_H44441004(CHIPS)':
 'A16_RAS_N': CDS_PINID='A16_RAS_N';
NODE_NAME     J9T1 82
 '@BASEBOARD_FAB2_LIB.BASEBOARD_FAB2(SCH_1):PAGE78_I13@MSTR_SCONN.SCONN288_H44441003(CHIPS)':
 'A16_RAS_N': CDS_PINID='A16_RAS_N';
NET_NAME
'M_G_MA<17>'
 '@BASEBOARD_FAB2_LIB.BASEBOARD_FAB2(SCH_1):M_G_MA'<17>:
 C_SIGNAL='@baseboard_fab2_lib.baseboard_fab2(sch_1):m_g_ma(17)';
NODE_NAME     U2D1 K47
 '@BASEBOARD_FAB2_LIB.BASEBOARD_FAB2(SCH_1):PAGE57_I172@CHPSET_LIB.SKX_EXT_B(CHIPS)':
 'DDR0_MA'<17>: CDS_PINID='DDR0_MA(17)';
NODE_NAME     J1G1 234
 '@BASEBOARD_FAB2_LIB.BASEBOARD_FAB2(SCH_1):PAGE77_I111@MSTR_SCONN.SCONN288_H44441004(CHIPS)':
 'A17': CDS_PINID='A17';
NODE_NAME     J9T1 234
 '@BASEBOARD_FAB2_LIB.BASEBOARD_FAB2(SCH_1):PAGE78_I13@MSTR_SCONN.SCONN288_H44441003(CHIPS)':
 'A17': CDS_PINID='A17';
NET_NAME
'M_G_MA<1>'
 '@BASEBOARD_FAB2_LIB.BASEBOARD_FAB2(SCH_1):M_G_MA'<1>:
 C_SIGNAL='@baseboard_fab2_lib.baseboard_fab2(sch_1):m_g_ma(1)';
NODE_NAME     U2D1 F57
 '@BASEBOARD_FAB2_LIB.BASEBOARD_FAB2(SCH_1):PAGE57_I172@CHPSET_LIB.SKX_EXT_B(CHIPS)':
 'DDR0_MA'<1>: CDS_PINID='DDR0_MA(1)';
NODE_NAME     J1G1 72
 '@BASEBOARD_FAB2_LIB.BASEBOARD_FAB2(SCH_1):PAGE77_I111@MSTR_SCONN.SCONN288_H44441004(CHIPS)':
 'A1': CDS_PINID='A1';
NODE_NAME     J9T1 72
 '@BASEBOARD_FAB2_LIB.BASEBOARD_FAB2(SCH_1):PAGE78_I13@MSTR_SCONN.SCONN288_H44441003(CHIPS)':
 'A1': CDS_PINID='A1';
NET_NAME
'M_G_MA<2>'
 '@BASEBOARD_FAB2_LIB.BASEBOARD_FAB2(SCH_1):M_G_MA'<2>:
 C_SIGNAL='@baseboard_fab2_lib.baseboard_fab2(sch_1):m_g_ma(2)';
NODE_NAME     U2D1 D57
 '@BASEBOARD_FAB2_LIB.BASEBOARD_FAB2(SCH_1):PAGE57_I172@CHPSET_LIB.SKX_EXT_B(CHIPS)':
 'DDR0_MA'<2>: CDS_PINID='DDR0_MA(2)';
NODE_NAME     J1G1 216
 '@BASEBOARD_FAB2_LIB.BASEBOARD_FAB2(SCH_1):PAGE77_I111@MSTR_SCONN.SCONN288_H44441004(CHIPS)':
 'A2': CDS_PINID='A2';
NODE_NAME     J9T1 216
 '@BASEBOARD_FAB2_LIB.BASEBOARD_FAB2(SCH_1):PAGE78_I13@MSTR_SCONN.SCONN288_H44441003(CHIPS)':
 'A2': CDS_PINID='A2';
NET_NAME
'M_G_MA<3>'
 '@BASEBOARD_FAB2_LIB.BASEBOARD_FAB2(SCH_1):M_G_MA'<3>:
 C_SIGNAL='@baseboard_fab2_lib.baseboard_fab2(sch_1):m_g_ma(3)';
NODE_NAME     U2D1 C58
 '@BASEBOARD_FAB2_LIB.BASEBOARD_FAB2(SCH_1):PAGE57_I172@CHPSET_LIB.SKX_EXT_B(CHIPS)':
 'DDR0_MA'<3>: CDS_PINID='DDR0_MA(3)';
NODE_NAME     J1G1 71
 '@BASEBOARD_FAB2_LIB.BASEBOARD_FAB2(SCH_1):PAGE77_I111@MSTR_SCONN.SCONN288_H44441004(CHIPS)':
 'A3': CDS_PINID='A3';
NODE_NAME     J9T1 71
 '@BASEBOARD_FAB2_LIB.BASEBOARD_FAB2(SCH_1):PAGE78_I13@MSTR_SCONN.SCONN288_H44441003(CHIPS)':
 'A3': CDS_PINID='A3';
NET_NAME
'M_G_MA<4>'
 '@BASEBOARD_FAB2_LIB.BASEBOARD_FAB2(SCH_1):M_G_MA'<4>:
 C_SIGNAL='@baseboard_fab2_lib.baseboard_fab2(sch_1):m_g_ma(4)';
NODE_NAME     U2D1 G58
 '@BASEBOARD_FAB2_LIB.BASEBOARD_FAB2(SCH_1):PAGE57_I172@CHPSET_LIB.SKX_EXT_B(CHIPS)':
 'DDR0_MA'<4>: CDS_PINID='DDR0_MA(4)';
NODE_NAME     J1G1 214
 '@BASEBOARD_FAB2_LIB.BASEBOARD_FAB2(SCH_1):PAGE77_I111@MSTR_SCONN.SCONN288_H44441004(CHIPS)':
 'A4': CDS_PINID='A4';
NODE_NAME     J9T1 214
 '@BASEBOARD_FAB2_LIB.BASEBOARD_FAB2(SCH_1):PAGE78_I13@MSTR_SCONN.SCONN288_H44441003(CHIPS)':
 'A4': CDS_PINID='A4';
NET_NAME
'M_G_MA<5>'
 '@BASEBOARD_FAB2_LIB.BASEBOARD_FAB2(SCH_1):M_G_MA'<5>:
 C_SIGNAL='@baseboard_fab2_lib.baseboard_fab2(sch_1):m_g_ma(5)';
NODE_NAME     U2D1 F59
 '@BASEBOARD_FAB2_LIB.BASEBOARD_FAB2(SCH_1):PAGE57_I172@CHPSET_LIB.SKX_EXT_B(CHIPS)':
 'DDR0_MA'<5>: CDS_PINID='DDR0_MA(5)';
NODE_NAME     J1G1 213
 '@BASEBOARD_FAB2_LIB.BASEBOARD_FAB2(SCH_1):PAGE77_I111@MSTR_SCONN.SCONN288_H44441004(CHIPS)':
 'A5': CDS_PINID='A5';
NODE_NAME     J9T1 213
 '@BASEBOARD_FAB2_LIB.BASEBOARD_FAB2(SCH_1):PAGE78_I13@MSTR_SCONN.SCONN288_H44441003(CHIPS)':
 'A5': CDS_PINID='A5';
NET_NAME
'M_G_MA<6>'
 '@BASEBOARD_FAB2_LIB.BASEBOARD_FAB2(SCH_1):M_G_MA'<6>:
 C_SIGNAL='@baseboard_fab2_lib.baseboard_fab2(sch_1):m_g_ma(6)';
NODE_NAME     U2D1 D59
 '@BASEBOARD_FAB2_LIB.BASEBOARD_FAB2(SCH_1):PAGE57_I172@CHPSET_LIB.SKX_EXT_B(CHIPS)':
 'DDR0_MA'<6>: CDS_PINID='DDR0_MA(6)';
NODE_NAME     J1G1 69
 '@BASEBOARD_FAB2_LIB.BASEBOARD_FAB2(SCH_1):PAGE77_I111@MSTR_SCONN.SCONN288_H44441004(CHIPS)':
 'A6': CDS_PINID='A6';
NODE_NAME     J9T1 69
 '@BASEBOARD_FAB2_LIB.BASEBOARD_FAB2(SCH_1):PAGE78_I13@MSTR_SCONN.SCONN288_H44441003(CHIPS)':
 'A6': CDS_PINID='A6';
NET_NAME
'M_G_MA<7>'
 '@BASEBOARD_FAB2_LIB.BASEBOARD_FAB2(SCH_1):M_G_MA'<7>:
 C_SIGNAL='@baseboard_fab2_lib.baseboard_fab2(sch_1):m_g_ma(7)';
NODE_NAME     U2D1 G60
 '@BASEBOARD_FAB2_LIB.BASEBOARD_FAB2(SCH_1):PAGE57_I172@CHPSET_LIB.SKX_EXT_B(CHIPS)':
 'DDR0_MA'<7>: CDS_PINID='DDR0_MA(7)';
NODE_NAME     J1G1 211
 '@BASEBOARD_FAB2_LIB.BASEBOARD_FAB2(SCH_1):PAGE77_I111@MSTR_SCONN.SCONN288_H44441004(CHIPS)':
 'A7': CDS_PINID='A7';
NODE_NAME     J9T1 211
 '@BASEBOARD_FAB2_LIB.BASEBOARD_FAB2(SCH_1):PAGE78_I13@MSTR_SCONN.SCONN288_H44441003(CHIPS)':
 'A7': CDS_PINID='A7';
NET_NAME
'M_G_MA<8>'
 '@BASEBOARD_FAB2_LIB.BASEBOARD_FAB2(SCH_1):M_G_MA'<8>:
 C_SIGNAL='@baseboard_fab2_lib.baseboard_fab2(sch_1):m_g_ma(8)';
NODE_NAME     U2D1 C60
 '@BASEBOARD_FAB2_LIB.BASEBOARD_FAB2(SCH_1):PAGE57_I172@CHPSET_LIB.SKX_EXT_B(CHIPS)':
 'DDR0_MA'<8>: CDS_PINID='DDR0_MA(8)';
NODE_NAME     J1G1 68
 '@BASEBOARD_FAB2_LIB.BASEBOARD_FAB2(SCH_1):PAGE77_I111@MSTR_SCONN.SCONN288_H44441004(CHIPS)':
 'A8': CDS_PINID='A8';
NODE_NAME     J9T1 68
 '@BASEBOARD_FAB2_LIB.BASEBOARD_FAB2(SCH_1):PAGE78_I13@MSTR_SCONN.SCONN288_H44441003(CHIPS)':
 'A8': CDS_PINID='A8';
NET_NAME
'M_G_MA<9>'
 '@BASEBOARD_FAB2_LIB.BASEBOARD_FAB2(SCH_1):M_G_MA'<9>:
 C_SIGNAL='@baseboard_fab2_lib.baseboard_fab2(sch_1):m_g_ma(9)';
NODE_NAME     U2D1 F61
 '@BASEBOARD_FAB2_LIB.BASEBOARD_FAB2(SCH_1):PAGE57_I172@CHPSET_LIB.SKX_EXT_B(CHIPS)':
 'DDR0_MA'<9>: CDS_PINID='DDR0_MA(9)';
NODE_NAME     J1G1 66
 '@BASEBOARD_FAB2_LIB.BASEBOARD_FAB2(SCH_1):PAGE77_I111@MSTR_SCONN.SCONN288_H44441004(CHIPS)':
 'A9': CDS_PINID='A9';
NODE_NAME     J9T1 66
 '@BASEBOARD_FAB2_LIB.BASEBOARD_FAB2(SCH_1):PAGE78_I13@MSTR_SCONN.SCONN288_H44441003(CHIPS)':
 'A9': CDS_PINID='A9';
NET_NAME
'M_G_ODT<0>'
 '@BASEBOARD_FAB2_LIB.BASEBOARD_FAB2(SCH_1):M_G_ODT'<0>:
 C_SIGNAL='@baseboard_fab2_lib.baseboard_fab2(sch_1):m_g_odt(0)';
NODE_NAME     U2D1 C50
 '@BASEBOARD_FAB2_LIB.BASEBOARD_FAB2(SCH_1):PAGE57_I172@CHPSET_LIB.SKX_EXT_B(CHIPS)':
 'DDR0_ODT'<0>: CDS_PINID='DDR0_ODT(0)';
NODE_NAME     J1G1 87
 '@BASEBOARD_FAB2_LIB.BASEBOARD_FAB2(SCH_1):PAGE77_I111@MSTR_SCONN.SCONN288_H44441004(CHIPS)':
 'ODT'<0>: CDS_PINID='ODT(0)';
NET_NAME
'M_G_ODT<1>'
 '@BASEBOARD_FAB2_LIB.BASEBOARD_FAB2(SCH_1):M_G_ODT'<1>:
 C_SIGNAL='@baseboard_fab2_lib.baseboard_fab2(sch_1):m_g_odt(1)';
NODE_NAME     U2D1 C48
 '@BASEBOARD_FAB2_LIB.BASEBOARD_FAB2(SCH_1):PAGE57_I172@CHPSET_LIB.SKX_EXT_B(CHIPS)':
 'DDR0_ODT'<1>: CDS_PINID='DDR0_ODT(1)';
NODE_NAME     J1G1 91
 '@BASEBOARD_FAB2_LIB.BASEBOARD_FAB2(SCH_1):PAGE77_I111@MSTR_SCONN.SCONN288_H44441004(CHIPS)':
 'ODT'<1>: CDS_PINID='ODT(1)';
NET_NAME
'M_G_ODT<2>'
 '@BASEBOARD_FAB2_LIB.BASEBOARD_FAB2(SCH_1):M_G_ODT'<2>:
 C_SIGNAL='@baseboard_fab2_lib.baseboard_fab2(sch_1):m_g_odt(2)';
NODE_NAME     U2D1 G50
 '@BASEBOARD_FAB2_LIB.BASEBOARD_FAB2(SCH_1):PAGE57_I172@CHPSET_LIB.SKX_EXT_B(CHIPS)':
 'DDR0_ODT'<2>: CDS_PINID='DDR0_ODT(2)';
NODE_NAME     J9T1 87
 '@BASEBOARD_FAB2_LIB.BASEBOARD_FAB2(SCH_1):PAGE78_I13@MSTR_SCONN.SCONN288_H44441003(CHIPS)':
 'ODT'<0>: CDS_PINID='ODT(0)';
NET_NAME
'M_G_ODT<3>'
 '@BASEBOARD_FAB2_LIB.BASEBOARD_FAB2(SCH_1):M_G_ODT'<3>:
 C_SIGNAL='@baseboard_fab2_lib.baseboard_fab2(sch_1):m_g_odt(3)';
NODE_NAME     U2D1 G48
 '@BASEBOARD_FAB2_LIB.BASEBOARD_FAB2(SCH_1):PAGE57_I172@CHPSET_LIB.SKX_EXT_B(CHIPS)':
 'DDR0_ODT'<3>: CDS_PINID='DDR0_ODT(3)';
NODE_NAME     J9T1 91
 '@BASEBOARD_FAB2_LIB.BASEBOARD_FAB2(SCH_1):PAGE78_I13@MSTR_SCONN.SCONN288_H44441003(CHIPS)':
 'ODT'<1>: CDS_PINID='ODT(1)';
NET_NAME
'M_G_PAR'
 '@BASEBOARD_FAB2_LIB.BASEBOARD_FAB2(SCH_1):M_G_PAR':
 C_SIGNAL='@baseboard_fab2_lib.baseboard_fab2(sch_1):m_g_par';
NODE_NAME     U2D1 D53
 '@BASEBOARD_FAB2_LIB.BASEBOARD_FAB2(SCH_1):PAGE57_I172@CHPSET_LIB.SKX_EXT_B(CHIPS)':
 'DDR0_PAR': CDS_PINID='DDR0_PAR';
NODE_NAME     J1G1 222
 '@BASEBOARD_FAB2_LIB.BASEBOARD_FAB2(SCH_1):PAGE77_I111@MSTR_SCONN.SCONN288_H44441004(CHIPS)':
 'PAR': CDS_PINID='PAR';
NODE_NAME     J9T1 222
 '@BASEBOARD_FAB2_LIB.BASEBOARD_FAB2(SCH_1):PAGE78_I13@MSTR_SCONN.SCONN288_H44441003(CHIPS)':
 'PAR': CDS_PINID='PAR';
NET_NAME
'M_G_VREF'
 '@BASEBOARD_FAB2_LIB.BASEBOARD_FAB2(SCH_1):M_G_VREF':
 C_SIGNAL='@baseboard_fab2_lib.baseboard_fab2(sch_1):m_g_vref';
NODE_NAME     J1G1 146
 '@BASEBOARD_FAB2_LIB.BASEBOARD_FAB2(SCH_1):PAGE77_I111@MSTR_SCONN.SCONN288_H44441004(CHIPS)':
 'VREFCA': CDS_PINID='VREFCA';
NODE_NAME     C1F22 1
 '@BASEBOARD_FAB2_LIB.BASEBOARD_FAB2(SCH_1):PAGE77_I181@DEV_DISCRETE.CAP_A(CHIPS)':
 'A': CDS_PINID='A';
NODE_NAME     C9T7 1
 '@BASEBOARD_FAB2_LIB.BASEBOARD_FAB2(SCH_1):PAGE78_I2@DEV_DISCRETE.CAP_A(CHIPS)':
 'A': CDS_PINID='A';
NODE_NAME     J9T1 146
 '@BASEBOARD_FAB2_LIB.BASEBOARD_FAB2(SCH_1):PAGE78_I13@MSTR_SCONN.SCONN288_H44441003(CHIPS)':
 'VREFCA': CDS_PINID='VREFCA';
NODE_NAME     R1F6 1
 '@BASEBOARD_FAB2_LIB.BASEBOARD_FAB2(SCH_1):PAGE100_I2@MSTR_DISCRETE.RES(CHIPS)':
 'A': CDS_PINID='A';
NODE_NAME     R1F5 2
 '@BASEBOARD_FAB2_LIB.BASEBOARD_FAB2(SCH_1):PAGE100_I6@MSTR_DISCRETE.RES(CHIPS)':
 'B': CDS_PINID='B';
NODE_NAME     R1F4 2
 '@BASEBOARD_FAB2_LIB.BASEBOARD_FAB2(SCH_1):PAGE100_I7@MSTR_DISCRETE.RES(CHIPS)':
 'B': CDS_PINID='B';
NET_NAME
'M_H_ACT_N'
 '@BASEBOARD_FAB2_LIB.BASEBOARD_FAB2(SCH_1):M_H_ACT_N':
 C_SIGNAL='@baseboard_fab2_lib.baseboard_fab2(sch_1):m_h_act_n';
NODE_NAME     U2D1 T63
 '@BASEBOARD_FAB2_LIB.BASEBOARD_FAB2(SCH_1):PAGE58_I172@CHPSET_LIB.SKX_EXT_B(CHIPS)':
 'DDR1_ACT_N': CDS_PINID='DDR1_ACT_N';
NODE_NAME     J1G2 62
 '@BASEBOARD_FAB2_LIB.BASEBOARD_FAB2(SCH_1):PAGE79_I111@MSTR_SCONN.SCONN288_H44441004(CHIPS)':
 'ACT_N': CDS_PINID='ACT_N';
NODE_NAME     J9U1 62
 '@BASEBOARD_FAB2_LIB.BASEBOARD_FAB2(SCH_1):PAGE80_I24@MSTR_SCONN.SCONN288_H44441003(CHIPS)':
 'ACT_N': CDS_PINID='ACT_N';
NET_NAME
'M_H_ALERT_N'
 '@BASEBOARD_FAB2_LIB.BASEBOARD_FAB2(SCH_1):M_H_ALERT_N':
 C_SIGNAL='@baseboard_fab2_lib.baseboard_fab2(sch_1):m_h_alert_n';
NODE_NAME     U2D1 W62
 '@BASEBOARD_FAB2_LIB.BASEBOARD_FAB2(SCH_1):PAGE58_I172@CHPSET_LIB.SKX_EXT_B(CHIPS)':
 'DDR1_ALERT_N': CDS_PINID='DDR1_ALERT_N';
NODE_NAME     J1G2 208
 '@BASEBOARD_FAB2_LIB.BASEBOARD_FAB2(SCH_1):PAGE79_I111@MSTR_SCONN.SCONN288_H44441004(CHIPS)':
 'ALERT_N': CDS_PINID='ALERT_N';
NODE_NAME     J9U1 208
 '@BASEBOARD_FAB2_LIB.BASEBOARD_FAB2(SCH_1):PAGE80_I24@MSTR_SCONN.SCONN288_H44441003(CHIPS)':
 'ALERT_N': CDS_PINID='ALERT_N';
NET_NAME
'M_H_BA<0>'
 '@BASEBOARD_FAB2_LIB.BASEBOARD_FAB2(SCH_1):M_H_BA'<0>:
 C_SIGNAL='@baseboard_fab2_lib.baseboard_fab2(sch_1):m_h_ba(0)';
NODE_NAME     U2D1 T53
 '@BASEBOARD_FAB2_LIB.BASEBOARD_FAB2(SCH_1):PAGE58_I172@CHPSET_LIB.SKX_EXT_B(CHIPS)':
 'DDR1_BA'<0>: CDS_PINID='DDR1_BA(0)';
NODE_NAME     J1G2 81
 '@BASEBOARD_FAB2_LIB.BASEBOARD_FAB2(SCH_1):PAGE79_I111@MSTR_SCONN.SCONN288_H44441004(CHIPS)':
 'BA'<0>: CDS_PINID='BA(0)';
NODE_NAME     J9U1 81
 '@BASEBOARD_FAB2_LIB.BASEBOARD_FAB2(SCH_1):PAGE80_I24@MSTR_SCONN.SCONN288_H44441003(CHIPS)':
 'BA'<0>: CDS_PINID='BA(0)';
NET_NAME
'M_H_BA<1>'
 '@BASEBOARD_FAB2_LIB.BASEBOARD_FAB2(SCH_1):M_H_BA'<1>:
 C_SIGNAL='@baseboard_fab2_lib.baseboard_fab2(sch_1):m_h_ba(1)';
NODE_NAME     U2D1 K55
 '@BASEBOARD_FAB2_LIB.BASEBOARD_FAB2(SCH_1):PAGE58_I172@CHPSET_LIB.SKX_EXT_B(CHIPS)':
 'DDR1_BA'<1>: CDS_PINID='DDR1_BA(1)';
NODE_NAME     J1G2 224
 '@BASEBOARD_FAB2_LIB.BASEBOARD_FAB2(SCH_1):PAGE79_I111@MSTR_SCONN.SCONN288_H44441004(CHIPS)':
 'BA'<1>: CDS_PINID='BA(1)';
NODE_NAME     J9U1 224
 '@BASEBOARD_FAB2_LIB.BASEBOARD_FAB2(SCH_1):PAGE80_I24@MSTR_SCONN.SCONN288_H44441003(CHIPS)':
 'BA'<1>: CDS_PINID='BA(1)';
NET_NAME
'M_H_BG<0>'
 '@BASEBOARD_FAB2_LIB.BASEBOARD_FAB2(SCH_1):M_H_BG'<0>:
 C_SIGNAL='@baseboard_fab2_lib.baseboard_fab2(sch_1):m_h_bg(0)';
NODE_NAME     U2D1 M61
 '@BASEBOARD_FAB2_LIB.BASEBOARD_FAB2(SCH_1):PAGE58_I172@CHPSET_LIB.SKX_EXT_B(CHIPS)':
 'DDR1_BG'<0>: CDS_PINID='DDR1_BG(0)';
NODE_NAME     J1G2 63
 '@BASEBOARD_FAB2_LIB.BASEBOARD_FAB2(SCH_1):PAGE79_I111@MSTR_SCONN.SCONN288_H44441004(CHIPS)':
 'BG'<0>: CDS_PINID='BG(0)';
NODE_NAME     J9U1 63
 '@BASEBOARD_FAB2_LIB.BASEBOARD_FAB2(SCH_1):PAGE80_I24@MSTR_SCONN.SCONN288_H44441003(CHIPS)':
 'BG'<0>: CDS_PINID='BG(0)';
NET_NAME
'M_H_BG<1>'
 '@BASEBOARD_FAB2_LIB.BASEBOARD_FAB2(SCH_1):M_H_BG'<1>:
 C_SIGNAL='@baseboard_fab2_lib.baseboard_fab2(sch_1):m_h_bg(1)';
NODE_NAME     U2D1 N60
 '@BASEBOARD_FAB2_LIB.BASEBOARD_FAB2(SCH_1):PAGE58_I172@CHPSET_LIB.SKX_EXT_B(CHIPS)':
 'DDR1_BG'<1>: CDS_PINID='DDR1_BG(1)';
NODE_NAME     J1G2 207
 '@BASEBOARD_FAB2_LIB.BASEBOARD_FAB2(SCH_1):PAGE79_I111@MSTR_SCONN.SCONN288_H44441004(CHIPS)':
 'BG'<1>: CDS_PINID='BG(1)';
NODE_NAME     J9U1 207
 '@BASEBOARD_FAB2_LIB.BASEBOARD_FAB2(SCH_1):PAGE80_I24@MSTR_SCONN.SCONN288_H44441003(CHIPS)':
 'BG'<1>: CDS_PINID='BG(1)';
NET_NAME
'M_H_C<2>'
 '@BASEBOARD_FAB2_LIB.BASEBOARD_FAB2(SCH_1):M_H_C'<2>:
 C_SIGNAL='@baseboard_fab2_lib.baseboard_fab2(sch_1):m_h_c(2)';
NODE_NAME     U2D1 M47
 '@BASEBOARD_FAB2_LIB.BASEBOARD_FAB2(SCH_1):PAGE58_I172@CHPSET_LIB.SKX_EXT_B(CHIPS)':
 'DDR1_CID'<2>: CDS_PINID='DDR1_CID(2)';
NODE_NAME     J1G2 235
 '@BASEBOARD_FAB2_LIB.BASEBOARD_FAB2(SCH_1):PAGE79_I111@MSTR_SCONN.SCONN288_H44441004(CHIPS)':
 'C'<2>: CDS_PINID='C(2)';
NODE_NAME     J9U1 235
 '@BASEBOARD_FAB2_LIB.BASEBOARD_FAB2(SCH_1):PAGE80_I24@MSTR_SCONN.SCONN288_H44441003(CHIPS)':
 'C'<2>: CDS_PINID='C(2)';
NET_NAME
'M_H_CKE<0>'
 '@BASEBOARD_FAB2_LIB.BASEBOARD_FAB2(SCH_1):M_H_CKE'<0>:
 C_SIGNAL='@baseboard_fab2_lib.baseboard_fab2(sch_1):m_h_cke(0)';
NODE_NAME     U2D1 N62
 '@BASEBOARD_FAB2_LIB.BASEBOARD_FAB2(SCH_1):PAGE58_I172@CHPSET_LIB.SKX_EXT_B(CHIPS)':
 'DDR1_CKE'<0>: CDS_PINID='DDR1_CKE(0)';
NODE_NAME     J1G2 60
 '@BASEBOARD_FAB2_LIB.BASEBOARD_FAB2(SCH_1):PAGE79_I111@MSTR_SCONN.SCONN288_H44441004(CHIPS)':
 'CKE'<0>: CDS_PINID='CKE(0)';
NET_NAME
'M_H_CKE<1>'
 '@BASEBOARD_FAB2_LIB.BASEBOARD_FAB2(SCH_1):M_H_CKE'<1>:
 C_SIGNAL='@baseboard_fab2_lib.baseboard_fab2(sch_1):m_h_cke(1)';
NODE_NAME     U2D1 R64
 '@BASEBOARD_FAB2_LIB.BASEBOARD_FAB2(SCH_1):PAGE58_I172@CHPSET_LIB.SKX_EXT_B(CHIPS)':
 'DDR1_CKE'<1>: CDS_PINID='DDR1_CKE(1)';
NODE_NAME     J1G2 203
 '@BASEBOARD_FAB2_LIB.BASEBOARD_FAB2(SCH_1):PAGE79_I111@MSTR_SCONN.SCONN288_H44441004(CHIPS)':
 'CKE'<1>: CDS_PINID='CKE(1)';
NET_NAME
'M_H_CKE<2>'
 '@BASEBOARD_FAB2_LIB.BASEBOARD_FAB2(SCH_1):M_H_CKE'<2>:
 C_SIGNAL='@baseboard_fab2_lib.baseboard_fab2(sch_1):m_h_cke(2)';
NODE_NAME     U2D1 K63
 '@BASEBOARD_FAB2_LIB.BASEBOARD_FAB2(SCH_1):PAGE58_I172@CHPSET_LIB.SKX_EXT_B(CHIPS)':
 'DDR1_CKE'<2>: CDS_PINID='DDR1_CKE(2)';
NODE_NAME     J9U1 60
 '@BASEBOARD_FAB2_LIB.BASEBOARD_FAB2(SCH_1):PAGE80_I24@MSTR_SCONN.SCONN288_H44441003(CHIPS)':
 'CKE'<0>: CDS_PINID='CKE(0)';
NET_NAME
'M_H_CKE<3>'
 '@BASEBOARD_FAB2_LIB.BASEBOARD_FAB2(SCH_1):M_H_CKE'<3>:
 C_SIGNAL='@baseboard_fab2_lib.baseboard_fab2(sch_1):m_h_cke(3)';
NODE_NAME     U2D1 L64
 '@BASEBOARD_FAB2_LIB.BASEBOARD_FAB2(SCH_1):PAGE58_I172@CHPSET_LIB.SKX_EXT_B(CHIPS)':
 'DDR1_CKE'<3>: CDS_PINID='DDR1_CKE(3)';
NODE_NAME     J9U1 203
 '@BASEBOARD_FAB2_LIB.BASEBOARD_FAB2(SCH_1):PAGE80_I24@MSTR_SCONN.SCONN288_H44441003(CHIPS)':
 'CKE'<1>: CDS_PINID='CKE(1)';
NET_NAME
'M_H_CLK_DN<0>'
 '@BASEBOARD_FAB2_LIB.BASEBOARD_FAB2(SCH_1):M_H_CLK_DN'<0>:
 C_SIGNAL='@baseboard_fab2_lib.baseboard_fab2(sch_1):m_h_clk_dn(0)';
NODE_NAME     U2D1 M53
 '@BASEBOARD_FAB2_LIB.BASEBOARD_FAB2(SCH_1):PAGE58_I172@CHPSET_LIB.SKX_EXT_B(CHIPS)':
 'DDR1_CLK_DN'<0>: CDS_PINID='DDR1_CLK_DN(0)';
NODE_NAME     J1G2 75
 '@BASEBOARD_FAB2_LIB.BASEBOARD_FAB2(SCH_1):PAGE79_I111@MSTR_SCONN.SCONN288_H44441004(CHIPS)':
 'CK0N': CDS_PINID='CK0N';
NET_NAME
'M_H_CLK_DN<1>'
 '@BASEBOARD_FAB2_LIB.BASEBOARD_FAB2(SCH_1):M_H_CLK_DN'<1>:
 C_SIGNAL='@baseboard_fab2_lib.baseboard_fab2(sch_1):m_h_clk_dn(1)';
NODE_NAME     U2D1 R54
 '@BASEBOARD_FAB2_LIB.BASEBOARD_FAB2(SCH_1):PAGE58_I172@CHPSET_LIB.SKX_EXT_B(CHIPS)':
 'DDR1_CLK_DN'<1>: CDS_PINID='DDR1_CLK_DN(1)';
NODE_NAME     J1G2 219
 '@BASEBOARD_FAB2_LIB.BASEBOARD_FAB2(SCH_1):PAGE79_I111@MSTR_SCONN.SCONN288_H44441004(CHIPS)':
 'CK1N': CDS_PINID='CK1N';
NET_NAME
'M_H_CLK_DN<2>'
 '@BASEBOARD_FAB2_LIB.BASEBOARD_FAB2(SCH_1):M_H_CLK_DN'<2>:
 C_SIGNAL='@baseboard_fab2_lib.baseboard_fab2(sch_1):m_h_clk_dn(2)';
NODE_NAME     U2D1 N56
 '@BASEBOARD_FAB2_LIB.BASEBOARD_FAB2(SCH_1):PAGE58_I172@CHPSET_LIB.SKX_EXT_B(CHIPS)':
 'DDR1_CLK_DN'<2>: CDS_PINID='DDR1_CLK_DN(2)';
NODE_NAME     J9U1 75
 '@BASEBOARD_FAB2_LIB.BASEBOARD_FAB2(SCH_1):PAGE80_I24@MSTR_SCONN.SCONN288_H44441003(CHIPS)':
 'CK0N': CDS_PINID='CK0N';
NET_NAME
'M_H_CLK_DN<3>'
 '@BASEBOARD_FAB2_LIB.BASEBOARD_FAB2(SCH_1):M_H_CLK_DN'<3>:
 C_SIGNAL='@baseboard_fab2_lib.baseboard_fab2(sch_1):m_h_clk_dn(3)';
NODE_NAME     U2D1 R56
 '@BASEBOARD_FAB2_LIB.BASEBOARD_FAB2(SCH_1):PAGE58_I172@CHPSET_LIB.SKX_EXT_B(CHIPS)':
 'DDR1_CLK_DN'<3>: CDS_PINID='DDR1_CLK_DN(3)';
NODE_NAME     J9U1 219
 '@BASEBOARD_FAB2_LIB.BASEBOARD_FAB2(SCH_1):PAGE80_I24@MSTR_SCONN.SCONN288_H44441003(CHIPS)':
 'CK1N': CDS_PINID='CK1N';
NET_NAME
'M_H_CLK_DP<0>'
 '@BASEBOARD_FAB2_LIB.BASEBOARD_FAB2(SCH_1):M_H_CLK_DP'<0>:
 C_SIGNAL='@baseboard_fab2_lib.baseboard_fab2(sch_1):m_h_clk_dp(0)';
NODE_NAME     U2D1 N54
 '@BASEBOARD_FAB2_LIB.BASEBOARD_FAB2(SCH_1):PAGE58_I172@CHPSET_LIB.SKX_EXT_B(CHIPS)':
 'DDR1_CLK_DP'<0>: CDS_PINID='DDR1_CLK_DP(0)';
NODE_NAME     J1G2 74
 '@BASEBOARD_FAB2_LIB.BASEBOARD_FAB2(SCH_1):PAGE79_I111@MSTR_SCONN.SCONN288_H44441004(CHIPS)':
 'CK0P': CDS_PINID='CK0P';
NET_NAME
'M_H_CLK_DP<1>'
 '@BASEBOARD_FAB2_LIB.BASEBOARD_FAB2(SCH_1):M_H_CLK_DP'<1>:
 C_SIGNAL='@baseboard_fab2_lib.baseboard_fab2(sch_1):m_h_clk_dp(1)';
NODE_NAME     U2D1 T55
 '@BASEBOARD_FAB2_LIB.BASEBOARD_FAB2(SCH_1):PAGE58_I172@CHPSET_LIB.SKX_EXT_B(CHIPS)':
 'DDR1_CLK_DP'<1>: CDS_PINID='DDR1_CLK_DP(1)';
NODE_NAME     J1G2 218
 '@BASEBOARD_FAB2_LIB.BASEBOARD_FAB2(SCH_1):PAGE79_I111@MSTR_SCONN.SCONN288_H44441004(CHIPS)':
 'CK1P': CDS_PINID='CK1P';
NET_NAME
'M_H_CLK_DP<2>'
 '@BASEBOARD_FAB2_LIB.BASEBOARD_FAB2(SCH_1):M_H_CLK_DP'<2>:
 C_SIGNAL='@baseboard_fab2_lib.baseboard_fab2(sch_1):m_h_clk_dp(2)';
NODE_NAME     U2D1 M57
 '@BASEBOARD_FAB2_LIB.BASEBOARD_FAB2(SCH_1):PAGE58_I172@CHPSET_LIB.SKX_EXT_B(CHIPS)':
 'DDR1_CLK_DP'<2>: CDS_PINID='DDR1_CLK_DP(2)';
NODE_NAME     J9U1 74
 '@BASEBOARD_FAB2_LIB.BASEBOARD_FAB2(SCH_1):PAGE80_I24@MSTR_SCONN.SCONN288_H44441003(CHIPS)':
 'CK0P': CDS_PINID='CK0P';
NET_NAME
'M_H_CLK_DP<3>'
 '@BASEBOARD_FAB2_LIB.BASEBOARD_FAB2(SCH_1):M_H_CLK_DP'<3>:
 C_SIGNAL='@baseboard_fab2_lib.baseboard_fab2(sch_1):m_h_clk_dp(3)';
NODE_NAME     U2D1 T57
 '@BASEBOARD_FAB2_LIB.BASEBOARD_FAB2(SCH_1):PAGE58_I172@CHPSET_LIB.SKX_EXT_B(CHIPS)':
 'DDR1_CLK_DP'<3>: CDS_PINID='DDR1_CLK_DP(3)';
NODE_NAME     J9U1 218
 '@BASEBOARD_FAB2_LIB.BASEBOARD_FAB2(SCH_1):PAGE80_I24@MSTR_SCONN.SCONN288_H44441003(CHIPS)':
 'CK1P': CDS_PINID='CK1P';
NET_NAME
'M_H_CPU_VREF'
 '@BASEBOARD_FAB2_LIB.BASEBOARD_FAB2(SCH_1):M_H_CPU_VREF':
 C_SIGNAL='@baseboard_fab2_lib.baseboard_fab2(sch_1):m_h_cpu_vref';
NODE_NAME     U2D1 AK63
 '@BASEBOARD_FAB2_LIB.BASEBOARD_FAB2(SCH_1):PAGE55_I172@CHPSET_LIB.SKX_EXT_B(CHIPS)':
 'DDR1_CAVREF': CDS_PINID='DDR1_CAVREF';
NODE_NAME     R1G1 1
 '@BASEBOARD_FAB2_LIB.BASEBOARD_FAB2(SCH_1):PAGE100_I25@MSTR_DISCRETE.RES(CHIPS)':
 'A': CDS_PINID='A';
NODE_NAME     C1G8 1
 '@BASEBOARD_FAB2_LIB.BASEBOARD_FAB2(SCH_1):PAGE100_I26@DEV_DISCRETE.CAP_A(CHIPS)':
 'A': CDS_PINID='A';
NET_NAME
'M_H_CS_N<0>'
 '@BASEBOARD_FAB2_LIB.BASEBOARD_FAB2(SCH_1):M_H_CS_N'<0>:
 C_SIGNAL='@baseboard_fab2_lib.baseboard_fab2(sch_1):m_h_cs_n(0)';
NODE_NAME     U2D1 K51
 '@BASEBOARD_FAB2_LIB.BASEBOARD_FAB2(SCH_1):PAGE58_I172@CHPSET_LIB.SKX_EXT_B(CHIPS)':
 'DDR1_CS_N'<0>: CDS_PINID='DDR1_CS_N(0)';
NODE_NAME     J1G2 84
 '@BASEBOARD_FAB2_LIB.BASEBOARD_FAB2(SCH_1):PAGE79_I111@MSTR_SCONN.SCONN288_H44441004(CHIPS)':
 'S0_N': CDS_PINID='S0_N';
NET_NAME
'M_H_CS_N<1>'
 '@BASEBOARD_FAB2_LIB.BASEBOARD_FAB2(SCH_1):M_H_CS_N'<1>:
 C_SIGNAL='@baseboard_fab2_lib.baseboard_fab2(sch_1):m_h_cs_n(1)';
NODE_NAME     U2D1 R50
 '@BASEBOARD_FAB2_LIB.BASEBOARD_FAB2(SCH_1):PAGE58_I172@CHPSET_LIB.SKX_EXT_B(CHIPS)':
 'DDR1_CS_N'<1>: CDS_PINID='DDR1_CS_N(1)';
NODE_NAME     J1G2 89
 '@BASEBOARD_FAB2_LIB.BASEBOARD_FAB2(SCH_1):PAGE79_I111@MSTR_SCONN.SCONN288_H44441004(CHIPS)':
 'S1_N': CDS_PINID='S1_N';
NET_NAME
'M_H_CS_N<2>'
 '@BASEBOARD_FAB2_LIB.BASEBOARD_FAB2(SCH_1):M_H_CS_N'<2>:
 C_SIGNAL='@baseboard_fab2_lib.baseboard_fab2(sch_1):m_h_cs_n(2)';
NODE_NAME     U2D1 N46
 '@BASEBOARD_FAB2_LIB.BASEBOARD_FAB2(SCH_1):PAGE58_I172@CHPSET_LIB.SKX_EXT_B(CHIPS)':
 'DDR1_CS_N'<2>: CDS_PINID='DDR1_CS_N(2)';
NODE_NAME     J1G2 93
 '@BASEBOARD_FAB2_LIB.BASEBOARD_FAB2(SCH_1):PAGE79_I111@MSTR_SCONN.SCONN288_H44441004(CHIPS)':
 'S2_N_C'<0>: CDS_PINID='S2_N_C(0)';
NET_NAME
'M_H_CS_N<3>'
 '@BASEBOARD_FAB2_LIB.BASEBOARD_FAB2(SCH_1):M_H_CS_N'<3>:
 C_SIGNAL='@baseboard_fab2_lib.baseboard_fab2(sch_1):m_h_cs_n(3)';
NODE_NAME     U2D1 V47
 '@BASEBOARD_FAB2_LIB.BASEBOARD_FAB2(SCH_1):PAGE58_I172@CHPSET_LIB.SKX_EXT_B(CHIPS)':
 'DDR1_CS_N'<3>: CDS_PINID='DDR1_CS_N(3)';
NODE_NAME     J1G2 237
 '@BASEBOARD_FAB2_LIB.BASEBOARD_FAB2(SCH_1):PAGE79_I111@MSTR_SCONN.SCONN288_H44441004(CHIPS)':
 'S3_N_C'<1>: CDS_PINID='S3_N_C(1)';
NET_NAME
'M_H_CS_N<4>'
 '@BASEBOARD_FAB2_LIB.BASEBOARD_FAB2(SCH_1):M_H_CS_N'<4>:
 C_SIGNAL='@baseboard_fab2_lib.baseboard_fab2(sch_1):m_h_cs_n(4)';
NODE_NAME     U2D1 J50
 '@BASEBOARD_FAB2_LIB.BASEBOARD_FAB2(SCH_1):PAGE58_I172@CHPSET_LIB.SKX_EXT_B(CHIPS)':
 'DDR1_CS_N'<4>: CDS_PINID='DDR1_CS_N(4)';
NODE_NAME     J9U1 84
 '@BASEBOARD_FAB2_LIB.BASEBOARD_FAB2(SCH_1):PAGE80_I24@MSTR_SCONN.SCONN288_H44441003(CHIPS)':
 'S0_N': CDS_PINID='S0_N';
NET_NAME
'M_H_CS_N<5>'
 '@BASEBOARD_FAB2_LIB.BASEBOARD_FAB2(SCH_1):M_H_CS_N'<5>:
 C_SIGNAL='@baseboard_fab2_lib.baseboard_fab2(sch_1):m_h_cs_n(5)';
NODE_NAME     U2D1 T49
 '@BASEBOARD_FAB2_LIB.BASEBOARD_FAB2(SCH_1):PAGE58_I172@CHPSET_LIB.SKX_EXT_B(CHIPS)':
 'DDR1_CS_N'<5>: CDS_PINID='DDR1_CS_N(5)';
NODE_NAME     J9U1 89
 '@BASEBOARD_FAB2_LIB.BASEBOARD_FAB2(SCH_1):PAGE80_I24@MSTR_SCONN.SCONN288_H44441003(CHIPS)':
 'S1_N': CDS_PINID='S1_N';
NET_NAME
'M_H_CS_N<6>'
 '@BASEBOARD_FAB2_LIB.BASEBOARD_FAB2(SCH_1):M_H_CS_N'<6>:
 C_SIGNAL='@baseboard_fab2_lib.baseboard_fab2(sch_1):m_h_cs_n(6)';
NODE_NAME     U2D1 M45
 '@BASEBOARD_FAB2_LIB.BASEBOARD_FAB2(SCH_1):PAGE58_I172@CHPSET_LIB.SKX_EXT_B(CHIPS)':
 'DDR1_CS_N'<6>: CDS_PINID='DDR1_CS_N(6)';
NODE_NAME     J9U1 93
 '@BASEBOARD_FAB2_LIB.BASEBOARD_FAB2(SCH_1):PAGE80_I24@MSTR_SCONN.SCONN288_H44441003(CHIPS)':
 'S2_N_C'<0>: CDS_PINID='S2_N_C(0)';
NET_NAME
'M_H_CS_N<7>'
 '@BASEBOARD_FAB2_LIB.BASEBOARD_FAB2(SCH_1):M_H_CS_N'<7>:
 C_SIGNAL='@baseboard_fab2_lib.baseboard_fab2(sch_1):m_h_cs_n(7)';
NODE_NAME     U2D1 R46
 '@BASEBOARD_FAB2_LIB.BASEBOARD_FAB2(SCH_1):PAGE58_I172@CHPSET_LIB.SKX_EXT_B(CHIPS)':
 'DDR1_CS_N'<7>: CDS_PINID='DDR1_CS_N(7)';
NODE_NAME     J9U1 237
 '@BASEBOARD_FAB2_LIB.BASEBOARD_FAB2(SCH_1):PAGE80_I24@MSTR_SCONN.SCONN288_H44441003(CHIPS)':
 'S3_N_C'<1>: CDS_PINID='S3_N_C(1)';
NET_NAME
'M_H_DQ<0>'
 '@BASEBOARD_FAB2_LIB.BASEBOARD_FAB2(SCH_1):M_H_DQ'<0>:
 C_SIGNAL='@baseboard_fab2_lib.baseboard_fab2(sch_1):m_h_dq(0)';
NODE_NAME     U2D1 AV81
 '@BASEBOARD_FAB2_LIB.BASEBOARD_FAB2(SCH_1):PAGE58_I172@CHPSET_LIB.SKX_EXT_B(CHIPS)':
 'DDR1_DQ'<0>: CDS_PINID='DDR1_DQ(0)';
NODE_NAME     J1G2 150
 '@BASEBOARD_FAB2_LIB.BASEBOARD_FAB2(SCH_1):PAGE79_I111@MSTR_SCONN.SCONN288_H44441004(CHIPS)':
 'DQ'<1>: CDS_PINID='DQ(1)';
NODE_NAME     J9U1 5
 '@BASEBOARD_FAB2_LIB.BASEBOARD_FAB2(SCH_1):PAGE80_I24@MSTR_SCONN.SCONN288_H44441003(CHIPS)':
 'DQ'<0>: CDS_PINID='DQ(0)';
NET_NAME
'M_H_DQ<10>'
 '@BASEBOARD_FAB2_LIB.BASEBOARD_FAB2(SCH_1):M_H_DQ'<10>:
 C_SIGNAL='@baseboard_fab2_lib.baseboard_fab2(sch_1):m_h_dq(10)';
NODE_NAME     U2D1 AC82
 '@BASEBOARD_FAB2_LIB.BASEBOARD_FAB2(SCH_1):PAGE58_I172@CHPSET_LIB.SKX_EXT_B(CHIPS)':
 'DDR1_DQ'<10>: CDS_PINID='DDR1_DQ(10)';
NODE_NAME     J1G2 168
 '@BASEBOARD_FAB2_LIB.BASEBOARD_FAB2(SCH_1):PAGE79_I111@MSTR_SCONN.SCONN288_H44441004(CHIPS)':
 'DQ'<11>: CDS_PINID='DQ(11)';
NODE_NAME     J9U1 23
 '@BASEBOARD_FAB2_LIB.BASEBOARD_FAB2(SCH_1):PAGE80_I24@MSTR_SCONN.SCONN288_H44441003(CHIPS)':
 'DQ'<10>: CDS_PINID='DQ(10)';
NET_NAME
'M_H_DQ<11>'
 '@BASEBOARD_FAB2_LIB.BASEBOARD_FAB2(SCH_1):M_H_DQ'<11>:
 C_SIGNAL='@baseboard_fab2_lib.baseboard_fab2(sch_1):m_h_dq(11)';
NODE_NAME     U2D1 AB81
 '@BASEBOARD_FAB2_LIB.BASEBOARD_FAB2(SCH_1):PAGE58_I172@CHPSET_LIB.SKX_EXT_B(CHIPS)':
 'DDR1_DQ'<11>: CDS_PINID='DDR1_DQ(11)';
NODE_NAME     J1G2 23
 '@BASEBOARD_FAB2_LIB.BASEBOARD_FAB2(SCH_1):PAGE79_I111@MSTR_SCONN.SCONN288_H44441004(CHIPS)':
 'DQ'<10>: CDS_PINID='DQ(10)';
NODE_NAME     J9U1 168
 '@BASEBOARD_FAB2_LIB.BASEBOARD_FAB2(SCH_1):PAGE80_I24@MSTR_SCONN.SCONN288_H44441003(CHIPS)':
 'DQ'<11>: CDS_PINID='DQ(11)';
NET_NAME
'M_H_DQ<12>'
 '@BASEBOARD_FAB2_LIB.BASEBOARD_FAB2(SCH_1):M_H_DQ'<12>:
 C_SIGNAL='@baseboard_fab2_lib.baseboard_fab2(sch_1):m_h_dq(12)';
NODE_NAME     U2D1 AJ80
 '@BASEBOARD_FAB2_LIB.BASEBOARD_FAB2(SCH_1):PAGE58_I172@CHPSET_LIB.SKX_EXT_B(CHIPS)':
 'DDR1_DQ'<12>: CDS_PINID='DDR1_DQ(12)';
NODE_NAME     J1G2 159
 '@BASEBOARD_FAB2_LIB.BASEBOARD_FAB2(SCH_1):PAGE79_I111@MSTR_SCONN.SCONN288_H44441004(CHIPS)':
 'DQ'<13>: CDS_PINID='DQ(13)';
NODE_NAME     J9U1 14
 '@BASEBOARD_FAB2_LIB.BASEBOARD_FAB2(SCH_1):PAGE80_I24@MSTR_SCONN.SCONN288_H44441003(CHIPS)':
 'DQ'<12>: CDS_PINID='DQ(12)';
NET_NAME
'M_H_DQ<13>'
 '@BASEBOARD_FAB2_LIB.BASEBOARD_FAB2(SCH_1):M_H_DQ'<13>:
 C_SIGNAL='@baseboard_fab2_lib.baseboard_fab2(sch_1):m_h_dq(13)';
NODE_NAME     U2D1 AH79
 '@BASEBOARD_FAB2_LIB.BASEBOARD_FAB2(SCH_1):PAGE58_I172@CHPSET_LIB.SKX_EXT_B(CHIPS)':
 'DDR1_DQ'<13>: CDS_PINID='DDR1_DQ(13)';
NODE_NAME     J1G2 14
 '@BASEBOARD_FAB2_LIB.BASEBOARD_FAB2(SCH_1):PAGE79_I111@MSTR_SCONN.SCONN288_H44441004(CHIPS)':
 'DQ'<12>: CDS_PINID='DQ(12)';
NODE_NAME     J9U1 159
 '@BASEBOARD_FAB2_LIB.BASEBOARD_FAB2(SCH_1):PAGE80_I24@MSTR_SCONN.SCONN288_H44441003(CHIPS)':
 'DQ'<13>: CDS_PINID='DQ(13)';
NET_NAME
'M_H_DQ<14>'
 '@BASEBOARD_FAB2_LIB.BASEBOARD_FAB2(SCH_1):M_H_DQ'<14>:
 C_SIGNAL='@baseboard_fab2_lib.baseboard_fab2(sch_1):m_h_dq(14)';
NODE_NAME     U2D1 AE82
 '@BASEBOARD_FAB2_LIB.BASEBOARD_FAB2(SCH_1):PAGE58_I172@CHPSET_LIB.SKX_EXT_B(CHIPS)':
 'DDR1_DQ'<14>: CDS_PINID='DDR1_DQ(14)';
NODE_NAME     J1G2 166
 '@BASEBOARD_FAB2_LIB.BASEBOARD_FAB2(SCH_1):PAGE79_I111@MSTR_SCONN.SCONN288_H44441004(CHIPS)':
 'DQ'<15>: CDS_PINID='DQ(15)';
NODE_NAME     J9U1 21
 '@BASEBOARD_FAB2_LIB.BASEBOARD_FAB2(SCH_1):PAGE80_I24@MSTR_SCONN.SCONN288_H44441003(CHIPS)':
 'DQ'<14>: CDS_PINID='DQ(14)';
NET_NAME
'M_H_DQ<15>'
 '@BASEBOARD_FAB2_LIB.BASEBOARD_FAB2(SCH_1):M_H_DQ'<15>:
 C_SIGNAL='@baseboard_fab2_lib.baseboard_fab2(sch_1):m_h_dq(15)';
NODE_NAME     U2D1 AC80
 '@BASEBOARD_FAB2_LIB.BASEBOARD_FAB2(SCH_1):PAGE58_I172@CHPSET_LIB.SKX_EXT_B(CHIPS)':
 'DDR1_DQ'<15>: CDS_PINID='DDR1_DQ(15)';
NODE_NAME     J1G2 21
 '@BASEBOARD_FAB2_LIB.BASEBOARD_FAB2(SCH_1):PAGE79_I111@MSTR_SCONN.SCONN288_H44441004(CHIPS)':
 'DQ'<14>: CDS_PINID='DQ(14)';
NODE_NAME     J9U1 166
 '@BASEBOARD_FAB2_LIB.BASEBOARD_FAB2(SCH_1):PAGE80_I24@MSTR_SCONN.SCONN288_H44441003(CHIPS)':
 'DQ'<15>: CDS_PINID='DQ(15)';
NET_NAME
'M_H_DQ<16>'
 '@BASEBOARD_FAB2_LIB.BASEBOARD_FAB2(SCH_1):M_H_DQ'<16>:
 C_SIGNAL='@baseboard_fab2_lib.baseboard_fab2(sch_1):m_h_dq(16)';
NODE_NAME     U2D1 E80
 '@BASEBOARD_FAB2_LIB.BASEBOARD_FAB2(SCH_1):PAGE58_I172@CHPSET_LIB.SKX_EXT_B(CHIPS)':
 'DDR1_DQ'<16>: CDS_PINID='DDR1_DQ(16)';
NODE_NAME     J1G2 172
 '@BASEBOARD_FAB2_LIB.BASEBOARD_FAB2(SCH_1):PAGE79_I111@MSTR_SCONN.SCONN288_H44441004(CHIPS)':
 'DQ'<17>: CDS_PINID='DQ(17)';
NODE_NAME     J9U1 27
 '@BASEBOARD_FAB2_LIB.BASEBOARD_FAB2(SCH_1):PAGE80_I24@MSTR_SCONN.SCONN288_H44441003(CHIPS)':
 'DQ'<16>: CDS_PINID='DQ(16)';
NET_NAME
'M_H_DQ<17>'
 '@BASEBOARD_FAB2_LIB.BASEBOARD_FAB2(SCH_1):M_H_DQ'<17>:
 C_SIGNAL='@baseboard_fab2_lib.baseboard_fab2(sch_1):m_h_dq(17)';
NODE_NAME     U2D1 J80
 '@BASEBOARD_FAB2_LIB.BASEBOARD_FAB2(SCH_1):PAGE58_I172@CHPSET_LIB.SKX_EXT_B(CHIPS)':
 'DDR1_DQ'<17>: CDS_PINID='DDR1_DQ(17)';
NODE_NAME     J1G2 27
 '@BASEBOARD_FAB2_LIB.BASEBOARD_FAB2(SCH_1):PAGE79_I111@MSTR_SCONN.SCONN288_H44441004(CHIPS)':
 'DQ'<16>: CDS_PINID='DQ(16)';
NODE_NAME     J9U1 172
 '@BASEBOARD_FAB2_LIB.BASEBOARD_FAB2(SCH_1):PAGE80_I24@MSTR_SCONN.SCONN288_H44441003(CHIPS)':
 'DQ'<17>: CDS_PINID='DQ(17)';
NET_NAME
'M_H_DQ<18>'
 '@BASEBOARD_FAB2_LIB.BASEBOARD_FAB2(SCH_1):M_H_DQ'<18>:
 C_SIGNAL='@baseboard_fab2_lib.baseboard_fab2(sch_1):m_h_dq(18)';
NODE_NAME     U2D1 F77
 '@BASEBOARD_FAB2_LIB.BASEBOARD_FAB2(SCH_1):PAGE58_I172@CHPSET_LIB.SKX_EXT_B(CHIPS)':
 'DDR1_DQ'<18>: CDS_PINID='DDR1_DQ(18)';
NODE_NAME     J1G2 179
 '@BASEBOARD_FAB2_LIB.BASEBOARD_FAB2(SCH_1):PAGE79_I111@MSTR_SCONN.SCONN288_H44441004(CHIPS)':
 'DQ'<19>: CDS_PINID='DQ(19)';
NODE_NAME     J9U1 34
 '@BASEBOARD_FAB2_LIB.BASEBOARD_FAB2(SCH_1):PAGE80_I24@MSTR_SCONN.SCONN288_H44441003(CHIPS)':
 'DQ'<18>: CDS_PINID='DQ(18)';
NET_NAME
'M_H_DQ<19>'
 '@BASEBOARD_FAB2_LIB.BASEBOARD_FAB2(SCH_1):M_H_DQ'<19>:
 C_SIGNAL='@baseboard_fab2_lib.baseboard_fab2(sch_1):m_h_dq(19)';
NODE_NAME     U2D1 H77
 '@BASEBOARD_FAB2_LIB.BASEBOARD_FAB2(SCH_1):PAGE58_I172@CHPSET_LIB.SKX_EXT_B(CHIPS)':
 'DDR1_DQ'<19>: CDS_PINID='DDR1_DQ(19)';
NODE_NAME     J1G2 34
 '@BASEBOARD_FAB2_LIB.BASEBOARD_FAB2(SCH_1):PAGE79_I111@MSTR_SCONN.SCONN288_H44441004(CHIPS)':
 'DQ'<18>: CDS_PINID='DQ(18)';
NODE_NAME     J9U1 179
 '@BASEBOARD_FAB2_LIB.BASEBOARD_FAB2(SCH_1):PAGE80_I24@MSTR_SCONN.SCONN288_H44441003(CHIPS)':
 'DQ'<19>: CDS_PINID='DQ(19)';
NET_NAME
'M_H_DQ<1>'
 '@BASEBOARD_FAB2_LIB.BASEBOARD_FAB2(SCH_1):M_H_DQ'<1>:
 C_SIGNAL='@baseboard_fab2_lib.baseboard_fab2(sch_1):m_h_dq(1)';
NODE_NAME     U2D1 AT79
 '@BASEBOARD_FAB2_LIB.BASEBOARD_FAB2(SCH_1):PAGE58_I172@CHPSET_LIB.SKX_EXT_B(CHIPS)':
 'DDR1_DQ'<1>: CDS_PINID='DDR1_DQ(1)';
NODE_NAME     J1G2 5
 '@BASEBOARD_FAB2_LIB.BASEBOARD_FAB2(SCH_1):PAGE79_I111@MSTR_SCONN.SCONN288_H44441004(CHIPS)':
 'DQ'<0>: CDS_PINID='DQ(0)';
NODE_NAME     J9U1 150
 '@BASEBOARD_FAB2_LIB.BASEBOARD_FAB2(SCH_1):PAGE80_I24@MSTR_SCONN.SCONN288_H44441003(CHIPS)':
 'DQ'<1>: CDS_PINID='DQ(1)';
NET_NAME
'M_H_DQ<20>'
 '@BASEBOARD_FAB2_LIB.BASEBOARD_FAB2(SCH_1):M_H_DQ'<20>:
 C_SIGNAL='@baseboard_fab2_lib.baseboard_fab2(sch_1):m_h_dq(20)';
NODE_NAME     U2D1 F81
 '@BASEBOARD_FAB2_LIB.BASEBOARD_FAB2(SCH_1):PAGE58_I172@CHPSET_LIB.SKX_EXT_B(CHIPS)':
 'DDR1_DQ'<20>: CDS_PINID='DDR1_DQ(20)';
NODE_NAME     J1G2 170
 '@BASEBOARD_FAB2_LIB.BASEBOARD_FAB2(SCH_1):PAGE79_I111@MSTR_SCONN.SCONN288_H44441004(CHIPS)':
 'DQ'<21>: CDS_PINID='DQ(21)';
NODE_NAME     J9U1 25
 '@BASEBOARD_FAB2_LIB.BASEBOARD_FAB2(SCH_1):PAGE80_I24@MSTR_SCONN.SCONN288_H44441003(CHIPS)':
 'DQ'<20>: CDS_PINID='DQ(20)';
NET_NAME
'M_H_DQ<21>'
 '@BASEBOARD_FAB2_LIB.BASEBOARD_FAB2(SCH_1):M_H_DQ'<21>:
 C_SIGNAL='@baseboard_fab2_lib.baseboard_fab2(sch_1):m_h_dq(21)';
NODE_NAME     U2D1 H81
 '@BASEBOARD_FAB2_LIB.BASEBOARD_FAB2(SCH_1):PAGE58_I172@CHPSET_LIB.SKX_EXT_B(CHIPS)':
 'DDR1_DQ'<21>: CDS_PINID='DDR1_DQ(21)';
NODE_NAME     J1G2 25
 '@BASEBOARD_FAB2_LIB.BASEBOARD_FAB2(SCH_1):PAGE79_I111@MSTR_SCONN.SCONN288_H44441004(CHIPS)':
 'DQ'<20>: CDS_PINID='DQ(20)';
NODE_NAME     J9U1 170
 '@BASEBOARD_FAB2_LIB.BASEBOARD_FAB2(SCH_1):PAGE80_I24@MSTR_SCONN.SCONN288_H44441003(CHIPS)':
 'DQ'<21>: CDS_PINID='DQ(21)';
NET_NAME
'M_H_DQ<22>'
 '@BASEBOARD_FAB2_LIB.BASEBOARD_FAB2(SCH_1):M_H_DQ'<22>:
 C_SIGNAL='@baseboard_fab2_lib.baseboard_fab2(sch_1):m_h_dq(22)';
NODE_NAME     U2D1 E78
 '@BASEBOARD_FAB2_LIB.BASEBOARD_FAB2(SCH_1):PAGE58_I172@CHPSET_LIB.SKX_EXT_B(CHIPS)':
 'DDR1_DQ'<22>: CDS_PINID='DDR1_DQ(22)';
NODE_NAME     J1G2 177
 '@BASEBOARD_FAB2_LIB.BASEBOARD_FAB2(SCH_1):PAGE79_I111@MSTR_SCONN.SCONN288_H44441004(CHIPS)':
 'DQ'<23>: CDS_PINID='DQ(23)';
NODE_NAME     J9U1 32
 '@BASEBOARD_FAB2_LIB.BASEBOARD_FAB2(SCH_1):PAGE80_I24@MSTR_SCONN.SCONN288_H44441003(CHIPS)':
 'DQ'<22>: CDS_PINID='DQ(22)';
NET_NAME
'M_H_DQ<23>'
 '@BASEBOARD_FAB2_LIB.BASEBOARD_FAB2(SCH_1):M_H_DQ'<23>:
 C_SIGNAL='@baseboard_fab2_lib.baseboard_fab2(sch_1):m_h_dq(23)';
NODE_NAME     U2D1 J78
 '@BASEBOARD_FAB2_LIB.BASEBOARD_FAB2(SCH_1):PAGE58_I172@CHPSET_LIB.SKX_EXT_B(CHIPS)':
 'DDR1_DQ'<23>: CDS_PINID='DDR1_DQ(23)';
NODE_NAME     J1G2 32
 '@BASEBOARD_FAB2_LIB.BASEBOARD_FAB2(SCH_1):PAGE79_I111@MSTR_SCONN.SCONN288_H44441004(CHIPS)':
 'DQ'<22>: CDS_PINID='DQ(22)';
NODE_NAME     J9U1 177
 '@BASEBOARD_FAB2_LIB.BASEBOARD_FAB2(SCH_1):PAGE80_I24@MSTR_SCONN.SCONN288_H44441003(CHIPS)':
 'DQ'<23>: CDS_PINID='DQ(23)';
NET_NAME
'M_H_DQ<24>'
 '@BASEBOARD_FAB2_LIB.BASEBOARD_FAB2(SCH_1):M_H_DQ'<24>:
 C_SIGNAL='@baseboard_fab2_lib.baseboard_fab2(sch_1):m_h_dq(24)';
NODE_NAME     U2D1 D75
 '@BASEBOARD_FAB2_LIB.BASEBOARD_FAB2(SCH_1):PAGE58_I172@CHPSET_LIB.SKX_EXT_B(CHIPS)':
 'DDR1_DQ'<24>: CDS_PINID='DDR1_DQ(24)';
NODE_NAME     J1G2 183
 '@BASEBOARD_FAB2_LIB.BASEBOARD_FAB2(SCH_1):PAGE79_I111@MSTR_SCONN.SCONN288_H44441004(CHIPS)':
 'DQ'<25>: CDS_PINID='DQ(25)';
NODE_NAME     J9U1 38
 '@BASEBOARD_FAB2_LIB.BASEBOARD_FAB2(SCH_1):PAGE80_I24@MSTR_SCONN.SCONN288_H44441003(CHIPS)':
 'DQ'<24>: CDS_PINID='DQ(24)';
NET_NAME
'M_H_DQ<25>'
 '@BASEBOARD_FAB2_LIB.BASEBOARD_FAB2(SCH_1):M_H_DQ'<25>:
 C_SIGNAL='@baseboard_fab2_lib.baseboard_fab2(sch_1):m_h_dq(25)';
NODE_NAME     U2D1 C74
 '@BASEBOARD_FAB2_LIB.BASEBOARD_FAB2(SCH_1):PAGE58_I172@CHPSET_LIB.SKX_EXT_B(CHIPS)':
 'DDR1_DQ'<25>: CDS_PINID='DDR1_DQ(25)';
NODE_NAME     J1G2 38
 '@BASEBOARD_FAB2_LIB.BASEBOARD_FAB2(SCH_1):PAGE79_I111@MSTR_SCONN.SCONN288_H44441004(CHIPS)':
 'DQ'<24>: CDS_PINID='DQ(24)';
NODE_NAME     J9U1 183
 '@BASEBOARD_FAB2_LIB.BASEBOARD_FAB2(SCH_1):PAGE80_I24@MSTR_SCONN.SCONN288_H44441003(CHIPS)':
 'DQ'<25>: CDS_PINID='DQ(25)';
NET_NAME
'M_H_DQ<26>'
 '@BASEBOARD_FAB2_LIB.BASEBOARD_FAB2(SCH_1):M_H_DQ'<26>:
 C_SIGNAL='@baseboard_fab2_lib.baseboard_fab2(sch_1):m_h_dq(26)';
NODE_NAME     U2D1 D71
 '@BASEBOARD_FAB2_LIB.BASEBOARD_FAB2(SCH_1):PAGE58_I172@CHPSET_LIB.SKX_EXT_B(CHIPS)':
 'DDR1_DQ'<26>: CDS_PINID='DDR1_DQ(26)';
NODE_NAME     J1G2 190
 '@BASEBOARD_FAB2_LIB.BASEBOARD_FAB2(SCH_1):PAGE79_I111@MSTR_SCONN.SCONN288_H44441004(CHIPS)':
 'DQ'<27>: CDS_PINID='DQ(27)';
NODE_NAME     J9U1 45
 '@BASEBOARD_FAB2_LIB.BASEBOARD_FAB2(SCH_1):PAGE80_I24@MSTR_SCONN.SCONN288_H44441003(CHIPS)':
 'DQ'<26>: CDS_PINID='DQ(26)';
NET_NAME
'M_H_DQ<27>'
 '@BASEBOARD_FAB2_LIB.BASEBOARD_FAB2(SCH_1):M_H_DQ'<27>:
 C_SIGNAL='@baseboard_fab2_lib.baseboard_fab2(sch_1):m_h_dq(27)';
NODE_NAME     U2D1 F71
 '@BASEBOARD_FAB2_LIB.BASEBOARD_FAB2(SCH_1):PAGE58_I172@CHPSET_LIB.SKX_EXT_B(CHIPS)':
 'DDR1_DQ'<27>: CDS_PINID='DDR1_DQ(27)';
NODE_NAME     J1G2 45
 '@BASEBOARD_FAB2_LIB.BASEBOARD_FAB2(SCH_1):PAGE79_I111@MSTR_SCONN.SCONN288_H44441004(CHIPS)':
 'DQ'<26>: CDS_PINID='DQ(26)';
NODE_NAME     J9U1 190
 '@BASEBOARD_FAB2_LIB.BASEBOARD_FAB2(SCH_1):PAGE80_I24@MSTR_SCONN.SCONN288_H44441003(CHIPS)':
 'DQ'<27>: CDS_PINID='DQ(27)';
NET_NAME
'M_H_DQ<28>'
 '@BASEBOARD_FAB2_LIB.BASEBOARD_FAB2(SCH_1):M_H_DQ'<28>:
 C_SIGNAL='@baseboard_fab2_lib.baseboard_fab2(sch_1):m_h_dq(28)';
NODE_NAME     U2D1 F75
 '@BASEBOARD_FAB2_LIB.BASEBOARD_FAB2(SCH_1):PAGE58_I172@CHPSET_LIB.SKX_EXT_B(CHIPS)':
 'DDR1_DQ'<28>: CDS_PINID='DDR1_DQ(28)';
NODE_NAME     J1G2 181
 '@BASEBOARD_FAB2_LIB.BASEBOARD_FAB2(SCH_1):PAGE79_I111@MSTR_SCONN.SCONN288_H44441004(CHIPS)':
 'DQ'<29>: CDS_PINID='DQ(29)';
NODE_NAME     J9U1 36
 '@BASEBOARD_FAB2_LIB.BASEBOARD_FAB2(SCH_1):PAGE80_I24@MSTR_SCONN.SCONN288_H44441003(CHIPS)':
 'DQ'<28>: CDS_PINID='DQ(28)';
NET_NAME
'M_H_DQ<29>'
 '@BASEBOARD_FAB2_LIB.BASEBOARD_FAB2(SCH_1):M_H_DQ'<29>:
 C_SIGNAL='@baseboard_fab2_lib.baseboard_fab2(sch_1):m_h_dq(29)';
NODE_NAME     U2D1 G74
 '@BASEBOARD_FAB2_LIB.BASEBOARD_FAB2(SCH_1):PAGE58_I172@CHPSET_LIB.SKX_EXT_B(CHIPS)':
 'DDR1_DQ'<29>: CDS_PINID='DDR1_DQ(29)';
NODE_NAME     J1G2 36
 '@BASEBOARD_FAB2_LIB.BASEBOARD_FAB2(SCH_1):PAGE79_I111@MSTR_SCONN.SCONN288_H44441004(CHIPS)':
 'DQ'<28>: CDS_PINID='DQ(28)';
NODE_NAME     J9U1 181
 '@BASEBOARD_FAB2_LIB.BASEBOARD_FAB2(SCH_1):PAGE80_I24@MSTR_SCONN.SCONN288_H44441003(CHIPS)':
 'DQ'<29>: CDS_PINID='DQ(29)';
NET_NAME
'M_H_DQ<2>'
 '@BASEBOARD_FAB2_LIB.BASEBOARD_FAB2(SCH_1):M_H_DQ'<2>:
 C_SIGNAL='@baseboard_fab2_lib.baseboard_fab2(sch_1):m_h_dq(2)';
NODE_NAME     U2D1 AN82
 '@BASEBOARD_FAB2_LIB.BASEBOARD_FAB2(SCH_1):PAGE58_I172@CHPSET_LIB.SKX_EXT_B(CHIPS)':
 'DDR1_DQ'<2>: CDS_PINID='DDR1_DQ(2)';
NODE_NAME     J1G2 157
 '@BASEBOARD_FAB2_LIB.BASEBOARD_FAB2(SCH_1):PAGE79_I111@MSTR_SCONN.SCONN288_H44441004(CHIPS)':
 'DQ'<3>: CDS_PINID='DQ(3)';
NODE_NAME     J9U1 12
 '@BASEBOARD_FAB2_LIB.BASEBOARD_FAB2(SCH_1):PAGE80_I24@MSTR_SCONN.SCONN288_H44441003(CHIPS)':
 'DQ'<2>: CDS_PINID='DQ(2)';
NET_NAME
'M_H_DQ<30>'
 '@BASEBOARD_FAB2_LIB.BASEBOARD_FAB2(SCH_1):M_H_DQ'<30>:
 C_SIGNAL='@baseboard_fab2_lib.baseboard_fab2(sch_1):m_h_dq(30)';
NODE_NAME     U2D1 C72
 '@BASEBOARD_FAB2_LIB.BASEBOARD_FAB2(SCH_1):PAGE58_I172@CHPSET_LIB.SKX_EXT_B(CHIPS)':
 'DDR1_DQ'<30>: CDS_PINID='DDR1_DQ(30)';
NODE_NAME     J1G2 188
 '@BASEBOARD_FAB2_LIB.BASEBOARD_FAB2(SCH_1):PAGE79_I111@MSTR_SCONN.SCONN288_H44441004(CHIPS)':
 'DQ'<31>: CDS_PINID='DQ(31)';
NODE_NAME     J9U1 43
 '@BASEBOARD_FAB2_LIB.BASEBOARD_FAB2(SCH_1):PAGE80_I24@MSTR_SCONN.SCONN288_H44441003(CHIPS)':
 'DQ'<30>: CDS_PINID='DQ(30)';
NET_NAME
'M_H_DQ<31>'
 '@BASEBOARD_FAB2_LIB.BASEBOARD_FAB2(SCH_1):M_H_DQ'<31>:
 C_SIGNAL='@baseboard_fab2_lib.baseboard_fab2(sch_1):m_h_dq(31)';
NODE_NAME     U2D1 G72
 '@BASEBOARD_FAB2_LIB.BASEBOARD_FAB2(SCH_1):PAGE58_I172@CHPSET_LIB.SKX_EXT_B(CHIPS)':
 'DDR1_DQ'<31>: CDS_PINID='DDR1_DQ(31)';
NODE_NAME     J1G2 43
 '@BASEBOARD_FAB2_LIB.BASEBOARD_FAB2(SCH_1):PAGE79_I111@MSTR_SCONN.SCONN288_H44441004(CHIPS)':
 'DQ'<30>: CDS_PINID='DQ(30)';
NODE_NAME     J9U1 188
 '@BASEBOARD_FAB2_LIB.BASEBOARD_FAB2(SCH_1):PAGE80_I24@MSTR_SCONN.SCONN288_H44441003(CHIPS)':
 'DQ'<31>: CDS_PINID='DQ(31)';
NET_NAME
'M_H_DQ<32>'
 '@BASEBOARD_FAB2_LIB.BASEBOARD_FAB2(SCH_1):M_H_DQ'<32>:
 C_SIGNAL='@baseboard_fab2_lib.baseboard_fab2(sch_1):m_h_dq(32)';
NODE_NAME     U2D1 K43
 '@BASEBOARD_FAB2_LIB.BASEBOARD_FAB2(SCH_1):PAGE58_I172@CHPSET_LIB.SKX_EXT_B(CHIPS)':
 'DDR1_DQ'<32>: CDS_PINID='DDR1_DQ(32)';
NODE_NAME     J1G2 242
 '@BASEBOARD_FAB2_LIB.BASEBOARD_FAB2(SCH_1):PAGE79_I111@MSTR_SCONN.SCONN288_H44441004(CHIPS)':
 'DQ'<33>: CDS_PINID='DQ(33)';
NODE_NAME     J9U1 97
 '@BASEBOARD_FAB2_LIB.BASEBOARD_FAB2(SCH_1):PAGE80_I24@MSTR_SCONN.SCONN288_H44441003(CHIPS)':
 'DQ'<32>: CDS_PINID='DQ(32)';
NET_NAME
'M_H_DQ<33>'
 '@BASEBOARD_FAB2_LIB.BASEBOARD_FAB2(SCH_1):M_H_DQ'<33>:
 C_SIGNAL='@baseboard_fab2_lib.baseboard_fab2(sch_1):m_h_dq(33)';
NODE_NAME     U2D1 H43
 '@BASEBOARD_FAB2_LIB.BASEBOARD_FAB2(SCH_1):PAGE58_I172@CHPSET_LIB.SKX_EXT_B(CHIPS)':
 'DDR1_DQ'<33>: CDS_PINID='DDR1_DQ(33)';
NODE_NAME     J1G2 97
 '@BASEBOARD_FAB2_LIB.BASEBOARD_FAB2(SCH_1):PAGE79_I111@MSTR_SCONN.SCONN288_H44441004(CHIPS)':
 'DQ'<32>: CDS_PINID='DQ(32)';
NODE_NAME     J9U1 242
 '@BASEBOARD_FAB2_LIB.BASEBOARD_FAB2(SCH_1):PAGE80_I24@MSTR_SCONN.SCONN288_H44441003(CHIPS)':
 'DQ'<33>: CDS_PINID='DQ(33)';
NET_NAME
'M_H_DQ<34>'
 '@BASEBOARD_FAB2_LIB.BASEBOARD_FAB2(SCH_1):M_H_DQ'<34>:
 C_SIGNAL='@baseboard_fab2_lib.baseboard_fab2(sch_1):m_h_dq(34)';
NODE_NAME     U2D1 L40
 '@BASEBOARD_FAB2_LIB.BASEBOARD_FAB2(SCH_1):PAGE58_I172@CHPSET_LIB.SKX_EXT_B(CHIPS)':
 'DDR1_DQ'<34>: CDS_PINID='DDR1_DQ(34)';
NODE_NAME     J1G2 249
 '@BASEBOARD_FAB2_LIB.BASEBOARD_FAB2(SCH_1):PAGE79_I111@MSTR_SCONN.SCONN288_H44441004(CHIPS)':
 'DQ'<35>: CDS_PINID='DQ(35)';
NODE_NAME     J9U1 104
 '@BASEBOARD_FAB2_LIB.BASEBOARD_FAB2(SCH_1):PAGE80_I24@MSTR_SCONN.SCONN288_H44441003(CHIPS)':
 'DQ'<34>: CDS_PINID='DQ(34)';
NET_NAME
'M_H_DQ<35>'
 '@BASEBOARD_FAB2_LIB.BASEBOARD_FAB2(SCH_1):M_H_DQ'<35>:
 C_SIGNAL='@baseboard_fab2_lib.baseboard_fab2(sch_1):m_h_dq(35)';
NODE_NAME     U2D1 N40
 '@BASEBOARD_FAB2_LIB.BASEBOARD_FAB2(SCH_1):PAGE58_I172@CHPSET_LIB.SKX_EXT_B(CHIPS)':
 'DDR1_DQ'<35>: CDS_PINID='DDR1_DQ(35)';
NODE_NAME     J1G2 104
 '@BASEBOARD_FAB2_LIB.BASEBOARD_FAB2(SCH_1):PAGE79_I111@MSTR_SCONN.SCONN288_H44441004(CHIPS)':
 'DQ'<34>: CDS_PINID='DQ(34)';
NODE_NAME     J9U1 249
 '@BASEBOARD_FAB2_LIB.BASEBOARD_FAB2(SCH_1):PAGE80_I24@MSTR_SCONN.SCONN288_H44441003(CHIPS)':
 'DQ'<35>: CDS_PINID='DQ(35)';
NET_NAME
'M_H_DQ<36>'
 '@BASEBOARD_FAB2_LIB.BASEBOARD_FAB2(SCH_1):M_H_DQ'<36>:
 C_SIGNAL='@baseboard_fab2_lib.baseboard_fab2(sch_1):m_h_dq(36)';
NODE_NAME     U2D1 P43
 '@BASEBOARD_FAB2_LIB.BASEBOARD_FAB2(SCH_1):PAGE58_I172@CHPSET_LIB.SKX_EXT_B(CHIPS)':
 'DDR1_DQ'<36>: CDS_PINID='DDR1_DQ(36)';
NODE_NAME     J1G2 240
 '@BASEBOARD_FAB2_LIB.BASEBOARD_FAB2(SCH_1):PAGE79_I111@MSTR_SCONN.SCONN288_H44441004(CHIPS)':
 'DQ'<37>: CDS_PINID='DQ(37)';
NODE_NAME     J9U1 95
 '@BASEBOARD_FAB2_LIB.BASEBOARD_FAB2(SCH_1):PAGE80_I24@MSTR_SCONN.SCONN288_H44441003(CHIPS)':
 'DQ'<36>: CDS_PINID='DQ(36)';
NET_NAME
'M_H_DQ<37>'
 '@BASEBOARD_FAB2_LIB.BASEBOARD_FAB2(SCH_1):M_H_DQ'<37>:
 C_SIGNAL='@baseboard_fab2_lib.baseboard_fab2(sch_1):m_h_dq(37)';
NODE_NAME     U2D1 T43
 '@BASEBOARD_FAB2_LIB.BASEBOARD_FAB2(SCH_1):PAGE58_I172@CHPSET_LIB.SKX_EXT_B(CHIPS)':
 'DDR1_DQ'<37>: CDS_PINID='DDR1_DQ(37)';
NODE_NAME     J1G2 95
 '@BASEBOARD_FAB2_LIB.BASEBOARD_FAB2(SCH_1):PAGE79_I111@MSTR_SCONN.SCONN288_H44441004(CHIPS)':
 'DQ'<36>: CDS_PINID='DQ(36)';
NODE_NAME     J9U1 240
 '@BASEBOARD_FAB2_LIB.BASEBOARD_FAB2(SCH_1):PAGE80_I24@MSTR_SCONN.SCONN288_H44441003(CHIPS)':
 'DQ'<37>: CDS_PINID='DQ(37)';
NET_NAME
'M_H_DQ<38>'
 '@BASEBOARD_FAB2_LIB.BASEBOARD_FAB2(SCH_1):M_H_DQ'<38>:
 C_SIGNAL='@baseboard_fab2_lib.baseboard_fab2(sch_1):m_h_dq(38)';
NODE_NAME     U2D1 K41
 '@BASEBOARD_FAB2_LIB.BASEBOARD_FAB2(SCH_1):PAGE58_I172@CHPSET_LIB.SKX_EXT_B(CHIPS)':
 'DDR1_DQ'<38>: CDS_PINID='DDR1_DQ(38)';
NODE_NAME     J1G2 247
 '@BASEBOARD_FAB2_LIB.BASEBOARD_FAB2(SCH_1):PAGE79_I111@MSTR_SCONN.SCONN288_H44441004(CHIPS)':
 'DQ'<39>: CDS_PINID='DQ(39)';
NODE_NAME     J9U1 102
 '@BASEBOARD_FAB2_LIB.BASEBOARD_FAB2(SCH_1):PAGE80_I24@MSTR_SCONN.SCONN288_H44441003(CHIPS)':
 'DQ'<38>: CDS_PINID='DQ(38)';
NET_NAME
'M_H_DQ<39>'
 '@BASEBOARD_FAB2_LIB.BASEBOARD_FAB2(SCH_1):M_H_DQ'<39>:
 C_SIGNAL='@baseboard_fab2_lib.baseboard_fab2(sch_1):m_h_dq(39)';
NODE_NAME     U2D1 P41
 '@BASEBOARD_FAB2_LIB.BASEBOARD_FAB2(SCH_1):PAGE58_I172@CHPSET_LIB.SKX_EXT_B(CHIPS)':
 'DDR1_DQ'<39>: CDS_PINID='DDR1_DQ(39)';
NODE_NAME     J1G2 102
 '@BASEBOARD_FAB2_LIB.BASEBOARD_FAB2(SCH_1):PAGE79_I111@MSTR_SCONN.SCONN288_H44441004(CHIPS)':
 'DQ'<38>: CDS_PINID='DQ(38)';
NODE_NAME     J9U1 247
 '@BASEBOARD_FAB2_LIB.BASEBOARD_FAB2(SCH_1):PAGE80_I24@MSTR_SCONN.SCONN288_H44441003(CHIPS)':
 'DQ'<39>: CDS_PINID='DQ(39)';
NET_NAME
'M_H_DQ<3>'
 '@BASEBOARD_FAB2_LIB.BASEBOARD_FAB2(SCH_1):M_H_DQ'<3>:
 C_SIGNAL='@baseboard_fab2_lib.baseboard_fab2(sch_1):m_h_dq(3)';
NODE_NAME     U2D1 AM81
 '@BASEBOARD_FAB2_LIB.BASEBOARD_FAB2(SCH_1):PAGE58_I172@CHPSET_LIB.SKX_EXT_B(CHIPS)':
 'DDR1_DQ'<3>: CDS_PINID='DDR1_DQ(3)';
NODE_NAME     J1G2 12
 '@BASEBOARD_FAB2_LIB.BASEBOARD_FAB2(SCH_1):PAGE79_I111@MSTR_SCONN.SCONN288_H44441004(CHIPS)':
 'DQ'<2>: CDS_PINID='DQ(2)';
NODE_NAME     J9U1 157
 '@BASEBOARD_FAB2_LIB.BASEBOARD_FAB2(SCH_1):PAGE80_I24@MSTR_SCONN.SCONN288_H44441003(CHIPS)':
 'DQ'<3>: CDS_PINID='DQ(3)';
NET_NAME
'M_H_DQ<40>'
 '@BASEBOARD_FAB2_LIB.BASEBOARD_FAB2(SCH_1):M_H_DQ'<40>:
 C_SIGNAL='@baseboard_fab2_lib.baseboard_fab2(sch_1):m_h_dq(40)';
NODE_NAME     U2D1 C36
 '@BASEBOARD_FAB2_LIB.BASEBOARD_FAB2(SCH_1):PAGE58_I172@CHPSET_LIB.SKX_EXT_B(CHIPS)':
 'DDR1_DQ'<40>: CDS_PINID='DDR1_DQ(40)';
NODE_NAME     J1G2 253
 '@BASEBOARD_FAB2_LIB.BASEBOARD_FAB2(SCH_1):PAGE79_I111@MSTR_SCONN.SCONN288_H44441004(CHIPS)':
 'DQ'<41>: CDS_PINID='DQ(41)';
NODE_NAME     J9U1 108
 '@BASEBOARD_FAB2_LIB.BASEBOARD_FAB2(SCH_1):PAGE80_I24@MSTR_SCONN.SCONN288_H44441003(CHIPS)':
 'DQ'<40>: CDS_PINID='DQ(40)';
NET_NAME
'M_H_DQ<41>'
 '@BASEBOARD_FAB2_LIB.BASEBOARD_FAB2(SCH_1):M_H_DQ'<41>:
 C_SIGNAL='@baseboard_fab2_lib.baseboard_fab2(sch_1):m_h_dq(41)';
NODE_NAME     U2D1 B35
 '@BASEBOARD_FAB2_LIB.BASEBOARD_FAB2(SCH_1):PAGE58_I172@CHPSET_LIB.SKX_EXT_B(CHIPS)':
 'DDR1_DQ'<41>: CDS_PINID='DDR1_DQ(41)';
NODE_NAME     J1G2 108
 '@BASEBOARD_FAB2_LIB.BASEBOARD_FAB2(SCH_1):PAGE79_I111@MSTR_SCONN.SCONN288_H44441004(CHIPS)':
 'DQ'<40>: CDS_PINID='DQ(40)';
NODE_NAME     J9U1 253
 '@BASEBOARD_FAB2_LIB.BASEBOARD_FAB2(SCH_1):PAGE80_I24@MSTR_SCONN.SCONN288_H44441003(CHIPS)':
 'DQ'<41>: CDS_PINID='DQ(41)';
NET_NAME
'M_H_DQ<42>'
 '@BASEBOARD_FAB2_LIB.BASEBOARD_FAB2(SCH_1):M_H_DQ'<42>:
 C_SIGNAL='@baseboard_fab2_lib.baseboard_fab2(sch_1):m_h_dq(42)';
NODE_NAME     U2D1 C32
 '@BASEBOARD_FAB2_LIB.BASEBOARD_FAB2(SCH_1):PAGE58_I172@CHPSET_LIB.SKX_EXT_B(CHIPS)':
 'DDR1_DQ'<42>: CDS_PINID='DDR1_DQ(42)';
NODE_NAME     J1G2 260
 '@BASEBOARD_FAB2_LIB.BASEBOARD_FAB2(SCH_1):PAGE79_I111@MSTR_SCONN.SCONN288_H44441004(CHIPS)':
 'DQ'<43>: CDS_PINID='DQ(43)';
NODE_NAME     J9U1 115
 '@BASEBOARD_FAB2_LIB.BASEBOARD_FAB2(SCH_1):PAGE80_I24@MSTR_SCONN.SCONN288_H44441003(CHIPS)':
 'DQ'<42>: CDS_PINID='DQ(42)';
NET_NAME
'M_H_DQ<43>'
 '@BASEBOARD_FAB2_LIB.BASEBOARD_FAB2(SCH_1):M_H_DQ'<43>:
 C_SIGNAL='@baseboard_fab2_lib.baseboard_fab2(sch_1):m_h_dq(43)';
NODE_NAME     U2D1 E32
 '@BASEBOARD_FAB2_LIB.BASEBOARD_FAB2(SCH_1):PAGE58_I172@CHPSET_LIB.SKX_EXT_B(CHIPS)':
 'DDR1_DQ'<43>: CDS_PINID='DDR1_DQ(43)';
NODE_NAME     J1G2 115
 '@BASEBOARD_FAB2_LIB.BASEBOARD_FAB2(SCH_1):PAGE79_I111@MSTR_SCONN.SCONN288_H44441004(CHIPS)':
 'DQ'<42>: CDS_PINID='DQ(42)';
NODE_NAME     J9U1 260
 '@BASEBOARD_FAB2_LIB.BASEBOARD_FAB2(SCH_1):PAGE80_I24@MSTR_SCONN.SCONN288_H44441003(CHIPS)':
 'DQ'<43>: CDS_PINID='DQ(43)';
NET_NAME
'M_H_DQ<44>'
 '@BASEBOARD_FAB2_LIB.BASEBOARD_FAB2(SCH_1):M_H_DQ'<44>:
 C_SIGNAL='@baseboard_fab2_lib.baseboard_fab2(sch_1):m_h_dq(44)';
NODE_NAME     U2D1 E36
 '@BASEBOARD_FAB2_LIB.BASEBOARD_FAB2(SCH_1):PAGE58_I172@CHPSET_LIB.SKX_EXT_B(CHIPS)':
 'DDR1_DQ'<44>: CDS_PINID='DDR1_DQ(44)';
NODE_NAME     J1G2 251
 '@BASEBOARD_FAB2_LIB.BASEBOARD_FAB2(SCH_1):PAGE79_I111@MSTR_SCONN.SCONN288_H44441004(CHIPS)':
 'DQ'<45>: CDS_PINID='DQ(45)';
NODE_NAME     J9U1 106
 '@BASEBOARD_FAB2_LIB.BASEBOARD_FAB2(SCH_1):PAGE80_I24@MSTR_SCONN.SCONN288_H44441003(CHIPS)':
 'DQ'<44>: CDS_PINID='DQ(44)';
NET_NAME
'M_H_DQ<45>'
 '@BASEBOARD_FAB2_LIB.BASEBOARD_FAB2(SCH_1):M_H_DQ'<45>:
 C_SIGNAL='@baseboard_fab2_lib.baseboard_fab2(sch_1):m_h_dq(45)';
NODE_NAME     U2D1 F35
 '@BASEBOARD_FAB2_LIB.BASEBOARD_FAB2(SCH_1):PAGE58_I172@CHPSET_LIB.SKX_EXT_B(CHIPS)':
 'DDR1_DQ'<45>: CDS_PINID='DDR1_DQ(45)';
NODE_NAME     J1G2 106
 '@BASEBOARD_FAB2_LIB.BASEBOARD_FAB2(SCH_1):PAGE79_I111@MSTR_SCONN.SCONN288_H44441004(CHIPS)':
 'DQ'<44>: CDS_PINID='DQ(44)';
NODE_NAME     J9U1 251
 '@BASEBOARD_FAB2_LIB.BASEBOARD_FAB2(SCH_1):PAGE80_I24@MSTR_SCONN.SCONN288_H44441003(CHIPS)':
 'DQ'<45>: CDS_PINID='DQ(45)';
NET_NAME
'M_H_DQ<46>'
 '@BASEBOARD_FAB2_LIB.BASEBOARD_FAB2(SCH_1):M_H_DQ'<46>:
 C_SIGNAL='@baseboard_fab2_lib.baseboard_fab2(sch_1):m_h_dq(46)';
NODE_NAME     U2D1 B33
 '@BASEBOARD_FAB2_LIB.BASEBOARD_FAB2(SCH_1):PAGE58_I172@CHPSET_LIB.SKX_EXT_B(CHIPS)':
 'DDR1_DQ'<46>: CDS_PINID='DDR1_DQ(46)';
NODE_NAME     J1G2 258
 '@BASEBOARD_FAB2_LIB.BASEBOARD_FAB2(SCH_1):PAGE79_I111@MSTR_SCONN.SCONN288_H44441004(CHIPS)':
 'DQ'<47>: CDS_PINID='DQ(47)';
NODE_NAME     J9U1 113
 '@BASEBOARD_FAB2_LIB.BASEBOARD_FAB2(SCH_1):PAGE80_I24@MSTR_SCONN.SCONN288_H44441003(CHIPS)':
 'DQ'<46>: CDS_PINID='DQ(46)';
NET_NAME
'M_H_DQ<47>'
 '@BASEBOARD_FAB2_LIB.BASEBOARD_FAB2(SCH_1):M_H_DQ'<47>:
 C_SIGNAL='@baseboard_fab2_lib.baseboard_fab2(sch_1):m_h_dq(47)';
NODE_NAME     U2D1 F33
 '@BASEBOARD_FAB2_LIB.BASEBOARD_FAB2(SCH_1):PAGE58_I172@CHPSET_LIB.SKX_EXT_B(CHIPS)':
 'DDR1_DQ'<47>: CDS_PINID='DDR1_DQ(47)';
NODE_NAME     J1G2 113
 '@BASEBOARD_FAB2_LIB.BASEBOARD_FAB2(SCH_1):PAGE79_I111@MSTR_SCONN.SCONN288_H44441004(CHIPS)':
 'DQ'<46>: CDS_PINID='DQ(46)';
NODE_NAME     J9U1 258
 '@BASEBOARD_FAB2_LIB.BASEBOARD_FAB2(SCH_1):PAGE80_I24@MSTR_SCONN.SCONN288_H44441003(CHIPS)':
 'DQ'<47>: CDS_PINID='DQ(47)';
NET_NAME
'M_H_DQ<48>'
 '@BASEBOARD_FAB2_LIB.BASEBOARD_FAB2(SCH_1):M_H_DQ'<48>:
 C_SIGNAL='@baseboard_fab2_lib.baseboard_fab2(sch_1):m_h_dq(48)';
NODE_NAME     U2D1 C30
 '@BASEBOARD_FAB2_LIB.BASEBOARD_FAB2(SCH_1):PAGE58_I172@CHPSET_LIB.SKX_EXT_B(CHIPS)':
 'DDR1_DQ'<48>: CDS_PINID='DDR1_DQ(48)';
NODE_NAME     J1G2 264
 '@BASEBOARD_FAB2_LIB.BASEBOARD_FAB2(SCH_1):PAGE79_I111@MSTR_SCONN.SCONN288_H44441004(CHIPS)':
 'DQ'<49>: CDS_PINID='DQ(49)';
NODE_NAME     J9U1 119
 '@BASEBOARD_FAB2_LIB.BASEBOARD_FAB2(SCH_1):PAGE80_I24@MSTR_SCONN.SCONN288_H44441003(CHIPS)':
 'DQ'<48>: CDS_PINID='DQ(48)';
NET_NAME
'M_H_DQ<49>'
 '@BASEBOARD_FAB2_LIB.BASEBOARD_FAB2(SCH_1):M_H_DQ'<49>:
 C_SIGNAL='@baseboard_fab2_lib.baseboard_fab2(sch_1):m_h_dq(49)';
NODE_NAME     U2D1 B29
 '@BASEBOARD_FAB2_LIB.BASEBOARD_FAB2(SCH_1):PAGE58_I172@CHPSET_LIB.SKX_EXT_B(CHIPS)':
 'DDR1_DQ'<49>: CDS_PINID='DDR1_DQ(49)';
NODE_NAME     J1G2 119
 '@BASEBOARD_FAB2_LIB.BASEBOARD_FAB2(SCH_1):PAGE79_I111@MSTR_SCONN.SCONN288_H44441004(CHIPS)':
 'DQ'<48>: CDS_PINID='DQ(48)';
NODE_NAME     J9U1 264
 '@BASEBOARD_FAB2_LIB.BASEBOARD_FAB2(SCH_1):PAGE80_I24@MSTR_SCONN.SCONN288_H44441003(CHIPS)':
 'DQ'<49>: CDS_PINID='DQ(49)';
NET_NAME
'M_H_DQ<4>'
 '@BASEBOARD_FAB2_LIB.BASEBOARD_FAB2(SCH_1):M_H_DQ'<4>:
 C_SIGNAL='@baseboard_fab2_lib.baseboard_fab2(sch_1):m_h_dq(4)';
NODE_NAME     U2D1 AW80
 '@BASEBOARD_FAB2_LIB.BASEBOARD_FAB2(SCH_1):PAGE58_I172@CHPSET_LIB.SKX_EXT_B(CHIPS)':
 'DDR1_DQ'<4>: CDS_PINID='DDR1_DQ(4)';
NODE_NAME     J1G2 148
 '@BASEBOARD_FAB2_LIB.BASEBOARD_FAB2(SCH_1):PAGE79_I111@MSTR_SCONN.SCONN288_H44441004(CHIPS)':
 'DQ'<5>: CDS_PINID='DQ(5)';
NODE_NAME     J9U1 3
 '@BASEBOARD_FAB2_LIB.BASEBOARD_FAB2(SCH_1):PAGE80_I24@MSTR_SCONN.SCONN288_H44441003(CHIPS)':
 'DQ'<4>: CDS_PINID='DQ(4)';
NET_NAME
'M_H_DQ<50>'
 '@BASEBOARD_FAB2_LIB.BASEBOARD_FAB2(SCH_1):M_H_DQ'<50>:
 C_SIGNAL='@baseboard_fab2_lib.baseboard_fab2(sch_1):m_h_dq(50)';
NODE_NAME     U2D1 C26
 '@BASEBOARD_FAB2_LIB.BASEBOARD_FAB2(SCH_1):PAGE58_I172@CHPSET_LIB.SKX_EXT_B(CHIPS)':
 'DDR1_DQ'<50>: CDS_PINID='DDR1_DQ(50)';
NODE_NAME     J1G2 271
 '@BASEBOARD_FAB2_LIB.BASEBOARD_FAB2(SCH_1):PAGE79_I111@MSTR_SCONN.SCONN288_H44441004(CHIPS)':
 'DQ'<51>: CDS_PINID='DQ(51)';
NODE_NAME     J9U1 126
 '@BASEBOARD_FAB2_LIB.BASEBOARD_FAB2(SCH_1):PAGE80_I24@MSTR_SCONN.SCONN288_H44441003(CHIPS)':
 'DQ'<50>: CDS_PINID='DQ(50)';
NET_NAME
'M_H_DQ<51>'
 '@BASEBOARD_FAB2_LIB.BASEBOARD_FAB2(SCH_1):M_H_DQ'<51>:
 C_SIGNAL='@baseboard_fab2_lib.baseboard_fab2(sch_1):m_h_dq(51)';
NODE_NAME     U2D1 E26
 '@BASEBOARD_FAB2_LIB.BASEBOARD_FAB2(SCH_1):PAGE58_I172@CHPSET_LIB.SKX_EXT_B(CHIPS)':
 'DDR1_DQ'<51>: CDS_PINID='DDR1_DQ(51)';
NODE_NAME     J1G2 126
 '@BASEBOARD_FAB2_LIB.BASEBOARD_FAB2(SCH_1):PAGE79_I111@MSTR_SCONN.SCONN288_H44441004(CHIPS)':
 'DQ'<50>: CDS_PINID='DQ(50)';
NODE_NAME     J9U1 271
 '@BASEBOARD_FAB2_LIB.BASEBOARD_FAB2(SCH_1):PAGE80_I24@MSTR_SCONN.SCONN288_H44441003(CHIPS)':
 'DQ'<51>: CDS_PINID='DQ(51)';
NET_NAME
'M_H_DQ<52>'
 '@BASEBOARD_FAB2_LIB.BASEBOARD_FAB2(SCH_1):M_H_DQ'<52>:
 C_SIGNAL='@baseboard_fab2_lib.baseboard_fab2(sch_1):m_h_dq(52)';
NODE_NAME     U2D1 E30
 '@BASEBOARD_FAB2_LIB.BASEBOARD_FAB2(SCH_1):PAGE58_I172@CHPSET_LIB.SKX_EXT_B(CHIPS)':
 'DDR1_DQ'<52>: CDS_PINID='DDR1_DQ(52)';
NODE_NAME     J1G2 262
 '@BASEBOARD_FAB2_LIB.BASEBOARD_FAB2(SCH_1):PAGE79_I111@MSTR_SCONN.SCONN288_H44441004(CHIPS)':
 'DQ'<53>: CDS_PINID='DQ(53)';
NODE_NAME     J9U1 117
 '@BASEBOARD_FAB2_LIB.BASEBOARD_FAB2(SCH_1):PAGE80_I24@MSTR_SCONN.SCONN288_H44441003(CHIPS)':
 'DQ'<52>: CDS_PINID='DQ(52)';
NET_NAME
'M_H_DQ<53>'
 '@BASEBOARD_FAB2_LIB.BASEBOARD_FAB2(SCH_1):M_H_DQ'<53>:
 C_SIGNAL='@baseboard_fab2_lib.baseboard_fab2(sch_1):m_h_dq(53)';
NODE_NAME     U2D1 F29
 '@BASEBOARD_FAB2_LIB.BASEBOARD_FAB2(SCH_1):PAGE58_I172@CHPSET_LIB.SKX_EXT_B(CHIPS)':
 'DDR1_DQ'<53>: CDS_PINID='DDR1_DQ(53)';
NODE_NAME     J1G2 117
 '@BASEBOARD_FAB2_LIB.BASEBOARD_FAB2(SCH_1):PAGE79_I111@MSTR_SCONN.SCONN288_H44441004(CHIPS)':
 'DQ'<52>: CDS_PINID='DQ(52)';
NODE_NAME     J9U1 262
 '@BASEBOARD_FAB2_LIB.BASEBOARD_FAB2(SCH_1):PAGE80_I24@MSTR_SCONN.SCONN288_H44441003(CHIPS)':
 'DQ'<53>: CDS_PINID='DQ(53)';
NET_NAME
'M_H_DQ<54>'
 '@BASEBOARD_FAB2_LIB.BASEBOARD_FAB2(SCH_1):M_H_DQ'<54>:
 C_SIGNAL='@baseboard_fab2_lib.baseboard_fab2(sch_1):m_h_dq(54)';
NODE_NAME     U2D1 B27
 '@BASEBOARD_FAB2_LIB.BASEBOARD_FAB2(SCH_1):PAGE58_I172@CHPSET_LIB.SKX_EXT_B(CHIPS)':
 'DDR1_DQ'<54>: CDS_PINID='DDR1_DQ(54)';
NODE_NAME     J1G2 269
 '@BASEBOARD_FAB2_LIB.BASEBOARD_FAB2(SCH_1):PAGE79_I111@MSTR_SCONN.SCONN288_H44441004(CHIPS)':
 'DQ'<55>: CDS_PINID='DQ(55)';
NODE_NAME     J9U1 124
 '@BASEBOARD_FAB2_LIB.BASEBOARD_FAB2(SCH_1):PAGE80_I24@MSTR_SCONN.SCONN288_H44441003(CHIPS)':
 'DQ'<54>: CDS_PINID='DQ(54)';
NET_NAME
'M_H_DQ<55>'
 '@BASEBOARD_FAB2_LIB.BASEBOARD_FAB2(SCH_1):M_H_DQ'<55>:
 C_SIGNAL='@baseboard_fab2_lib.baseboard_fab2(sch_1):m_h_dq(55)';
NODE_NAME     U2D1 F27
 '@BASEBOARD_FAB2_LIB.BASEBOARD_FAB2(SCH_1):PAGE58_I172@CHPSET_LIB.SKX_EXT_B(CHIPS)':
 'DDR1_DQ'<55>: CDS_PINID='DDR1_DQ(55)';
NODE_NAME     J1G2 124
 '@BASEBOARD_FAB2_LIB.BASEBOARD_FAB2(SCH_1):PAGE79_I111@MSTR_SCONN.SCONN288_H44441004(CHIPS)':
 'DQ'<54>: CDS_PINID='DQ(54)';
NODE_NAME     J9U1 269
 '@BASEBOARD_FAB2_LIB.BASEBOARD_FAB2(SCH_1):PAGE80_I24@MSTR_SCONN.SCONN288_H44441003(CHIPS)':
 'DQ'<55>: CDS_PINID='DQ(55)';
NET_NAME
'M_H_DQ<56>'
 '@BASEBOARD_FAB2_LIB.BASEBOARD_FAB2(SCH_1):M_H_DQ'<56>:
 C_SIGNAL='@baseboard_fab2_lib.baseboard_fab2(sch_1):m_h_dq(56)';
NODE_NAME     U2D1 U28
 '@BASEBOARD_FAB2_LIB.BASEBOARD_FAB2(SCH_1):PAGE58_I172@CHPSET_LIB.SKX_EXT_B(CHIPS)':
 'DDR1_DQ'<56>: CDS_PINID='DDR1_DQ(56)';
NODE_NAME     J1G2 275
 '@BASEBOARD_FAB2_LIB.BASEBOARD_FAB2(SCH_1):PAGE79_I111@MSTR_SCONN.SCONN288_H44441004(CHIPS)':
 'DQ'<57>: CDS_PINID='DQ(57)';
NODE_NAME     J9U1 130
 '@BASEBOARD_FAB2_LIB.BASEBOARD_FAB2(SCH_1):PAGE80_I24@MSTR_SCONN.SCONN288_H44441003(CHIPS)':
 'DQ'<56>: CDS_PINID='DQ(56)';
NET_NAME
'M_H_DQ<57>'
 '@BASEBOARD_FAB2_LIB.BASEBOARD_FAB2(SCH_1):M_H_DQ'<57>:
 C_SIGNAL='@baseboard_fab2_lib.baseboard_fab2(sch_1):m_h_dq(57)';
NODE_NAME     U2D1 AA28
 '@BASEBOARD_FAB2_LIB.BASEBOARD_FAB2(SCH_1):PAGE58_I172@CHPSET_LIB.SKX_EXT_B(CHIPS)':
 'DDR1_DQ'<57>: CDS_PINID='DDR1_DQ(57)';
NODE_NAME     J1G2 130
 '@BASEBOARD_FAB2_LIB.BASEBOARD_FAB2(SCH_1):PAGE79_I111@MSTR_SCONN.SCONN288_H44441004(CHIPS)':
 'DQ'<56>: CDS_PINID='DQ(56)';
NODE_NAME     J9U1 275
 '@BASEBOARD_FAB2_LIB.BASEBOARD_FAB2(SCH_1):PAGE80_I24@MSTR_SCONN.SCONN288_H44441003(CHIPS)':
 'DQ'<57>: CDS_PINID='DQ(57)';
NET_NAME
'M_H_DQ<58>'
 '@BASEBOARD_FAB2_LIB.BASEBOARD_FAB2(SCH_1):M_H_DQ'<58>:
 C_SIGNAL='@baseboard_fab2_lib.baseboard_fab2(sch_1):m_h_dq(58)';
NODE_NAME     U2D1 V25
 '@BASEBOARD_FAB2_LIB.BASEBOARD_FAB2(SCH_1):PAGE58_I172@CHPSET_LIB.SKX_EXT_B(CHIPS)':
 'DDR1_DQ'<58>: CDS_PINID='DDR1_DQ(58)';
NODE_NAME     J1G2 282
 '@BASEBOARD_FAB2_LIB.BASEBOARD_FAB2(SCH_1):PAGE79_I111@MSTR_SCONN.SCONN288_H44441004(CHIPS)':
 'DQ'<59>: CDS_PINID='DQ(59)';
NODE_NAME     J9U1 137
 '@BASEBOARD_FAB2_LIB.BASEBOARD_FAB2(SCH_1):PAGE80_I24@MSTR_SCONN.SCONN288_H44441003(CHIPS)':
 'DQ'<58>: CDS_PINID='DQ(58)';
NET_NAME
'M_H_DQ<59>'
 '@BASEBOARD_FAB2_LIB.BASEBOARD_FAB2(SCH_1):M_H_DQ'<59>:
 C_SIGNAL='@baseboard_fab2_lib.baseboard_fab2(sch_1):m_h_dq(59)';
NODE_NAME     U2D1 Y25
 '@BASEBOARD_FAB2_LIB.BASEBOARD_FAB2(SCH_1):PAGE58_I172@CHPSET_LIB.SKX_EXT_B(CHIPS)':
 'DDR1_DQ'<59>: CDS_PINID='DDR1_DQ(59)';
NODE_NAME     J1G2 137
 '@BASEBOARD_FAB2_LIB.BASEBOARD_FAB2(SCH_1):PAGE79_I111@MSTR_SCONN.SCONN288_H44441004(CHIPS)':
 'DQ'<58>: CDS_PINID='DQ(58)';
NODE_NAME     J9U1 282
 '@BASEBOARD_FAB2_LIB.BASEBOARD_FAB2(SCH_1):PAGE80_I24@MSTR_SCONN.SCONN288_H44441003(CHIPS)':
 'DQ'<59>: CDS_PINID='DQ(59)';
NET_NAME
'M_H_DQ<5>'
 '@BASEBOARD_FAB2_LIB.BASEBOARD_FAB2(SCH_1):M_H_DQ'<5>:
 C_SIGNAL='@baseboard_fab2_lib.baseboard_fab2(sch_1):m_h_dq(5)';
NODE_NAME     U2D1 AV79
 '@BASEBOARD_FAB2_LIB.BASEBOARD_FAB2(SCH_1):PAGE58_I172@CHPSET_LIB.SKX_EXT_B(CHIPS)':
 'DDR1_DQ'<5>: CDS_PINID='DDR1_DQ(5)';
NODE_NAME     J1G2 3
 '@BASEBOARD_FAB2_LIB.BASEBOARD_FAB2(SCH_1):PAGE79_I111@MSTR_SCONN.SCONN288_H44441004(CHIPS)':
 'DQ'<4>: CDS_PINID='DQ(4)';
NODE_NAME     J9U1 148
 '@BASEBOARD_FAB2_LIB.BASEBOARD_FAB2(SCH_1):PAGE80_I24@MSTR_SCONN.SCONN288_H44441003(CHIPS)':
 'DQ'<5>: CDS_PINID='DQ(5)';
NET_NAME
'M_H_DQ<60>'
 '@BASEBOARD_FAB2_LIB.BASEBOARD_FAB2(SCH_1):M_H_DQ'<60>:
 C_SIGNAL='@baseboard_fab2_lib.baseboard_fab2(sch_1):m_h_dq(60)';
NODE_NAME     U2D1 V29
 '@BASEBOARD_FAB2_LIB.BASEBOARD_FAB2(SCH_1):PAGE58_I172@CHPSET_LIB.SKX_EXT_B(CHIPS)':
 'DDR1_DQ'<60>: CDS_PINID='DDR1_DQ(60)';
NODE_NAME     J1G2 273
 '@BASEBOARD_FAB2_LIB.BASEBOARD_FAB2(SCH_1):PAGE79_I111@MSTR_SCONN.SCONN288_H44441004(CHIPS)':
 'DQ'<61>: CDS_PINID='DQ(61)';
NODE_NAME     J9U1 128
 '@BASEBOARD_FAB2_LIB.BASEBOARD_FAB2(SCH_1):PAGE80_I24@MSTR_SCONN.SCONN288_H44441003(CHIPS)':
 'DQ'<60>: CDS_PINID='DQ(60)';
NET_NAME
'M_H_DQ<61>'
 '@BASEBOARD_FAB2_LIB.BASEBOARD_FAB2(SCH_1):M_H_DQ'<61>:
 C_SIGNAL='@baseboard_fab2_lib.baseboard_fab2(sch_1):m_h_dq(61)';
NODE_NAME     U2D1 Y29
 '@BASEBOARD_FAB2_LIB.BASEBOARD_FAB2(SCH_1):PAGE58_I172@CHPSET_LIB.SKX_EXT_B(CHIPS)':
 'DDR1_DQ'<61>: CDS_PINID='DDR1_DQ(61)';
NODE_NAME     J1G2 128
 '@BASEBOARD_FAB2_LIB.BASEBOARD_FAB2(SCH_1):PAGE79_I111@MSTR_SCONN.SCONN288_H44441004(CHIPS)':
 'DQ'<60>: CDS_PINID='DQ(60)';
NODE_NAME     J9U1 273
 '@BASEBOARD_FAB2_LIB.BASEBOARD_FAB2(SCH_1):PAGE80_I24@MSTR_SCONN.SCONN288_H44441003(CHIPS)':
 'DQ'<61>: CDS_PINID='DQ(61)';
NET_NAME
'M_H_DQ<62>'
 '@BASEBOARD_FAB2_LIB.BASEBOARD_FAB2(SCH_1):M_H_DQ'<62>:
 C_SIGNAL='@baseboard_fab2_lib.baseboard_fab2(sch_1):m_h_dq(62)';
NODE_NAME     U2D1 U26
 '@BASEBOARD_FAB2_LIB.BASEBOARD_FAB2(SCH_1):PAGE58_I172@CHPSET_LIB.SKX_EXT_B(CHIPS)':
 'DDR1_DQ'<62>: CDS_PINID='DDR1_DQ(62)';
NODE_NAME     J1G2 280
 '@BASEBOARD_FAB2_LIB.BASEBOARD_FAB2(SCH_1):PAGE79_I111@MSTR_SCONN.SCONN288_H44441004(CHIPS)':
 'DQ'<63>: CDS_PINID='DQ(63)';
NODE_NAME     J9U1 135
 '@BASEBOARD_FAB2_LIB.BASEBOARD_FAB2(SCH_1):PAGE80_I24@MSTR_SCONN.SCONN288_H44441003(CHIPS)':
 'DQ'<62>: CDS_PINID='DQ(62)';
NET_NAME
'M_H_DQ<63>'
 '@BASEBOARD_FAB2_LIB.BASEBOARD_FAB2(SCH_1):M_H_DQ'<63>:
 C_SIGNAL='@baseboard_fab2_lib.baseboard_fab2(sch_1):m_h_dq(63)';
NODE_NAME     U2D1 AA26
 '@BASEBOARD_FAB2_LIB.BASEBOARD_FAB2(SCH_1):PAGE58_I172@CHPSET_LIB.SKX_EXT_B(CHIPS)':
 'DDR1_DQ'<63>: CDS_PINID='DDR1_DQ(63)';
NODE_NAME     J1G2 135
 '@BASEBOARD_FAB2_LIB.BASEBOARD_FAB2(SCH_1):PAGE79_I111@MSTR_SCONN.SCONN288_H44441004(CHIPS)':
 'DQ'<62>: CDS_PINID='DQ(62)';
NODE_NAME     J9U1 280
 '@BASEBOARD_FAB2_LIB.BASEBOARD_FAB2(SCH_1):PAGE80_I24@MSTR_SCONN.SCONN288_H44441003(CHIPS)':
 'DQ'<63>: CDS_PINID='DQ(63)';
NET_NAME
'M_H_DQ<6>'
 '@BASEBOARD_FAB2_LIB.BASEBOARD_FAB2(SCH_1):M_H_DQ'<6>:
 C_SIGNAL='@baseboard_fab2_lib.baseboard_fab2(sch_1):m_h_dq(6)';
NODE_NAME     U2D1 AR82
 '@BASEBOARD_FAB2_LIB.BASEBOARD_FAB2(SCH_1):PAGE58_I172@CHPSET_LIB.SKX_EXT_B(CHIPS)':
 'DDR1_DQ'<6>: CDS_PINID='DDR1_DQ(6)';
NODE_NAME     J1G2 155
 '@BASEBOARD_FAB2_LIB.BASEBOARD_FAB2(SCH_1):PAGE79_I111@MSTR_SCONN.SCONN288_H44441004(CHIPS)':
 'DQ'<7>: CDS_PINID='DQ(7)';
NODE_NAME     J9U1 10
 '@BASEBOARD_FAB2_LIB.BASEBOARD_FAB2(SCH_1):PAGE80_I24@MSTR_SCONN.SCONN288_H44441003(CHIPS)':
 'DQ'<6>: CDS_PINID='DQ(6)';
NET_NAME
'M_H_DQ<7>'
 '@BASEBOARD_FAB2_LIB.BASEBOARD_FAB2(SCH_1):M_H_DQ'<7>:
 C_SIGNAL='@baseboard_fab2_lib.baseboard_fab2(sch_1):m_h_dq(7)';
NODE_NAME     U2D1 AN80
 '@BASEBOARD_FAB2_LIB.BASEBOARD_FAB2(SCH_1):PAGE58_I172@CHPSET_LIB.SKX_EXT_B(CHIPS)':
 'DDR1_DQ'<7>: CDS_PINID='DDR1_DQ(7)';
NODE_NAME     J1G2 10
 '@BASEBOARD_FAB2_LIB.BASEBOARD_FAB2(SCH_1):PAGE79_I111@MSTR_SCONN.SCONN288_H44441004(CHIPS)':
 'DQ'<6>: CDS_PINID='DQ(6)';
NODE_NAME     J9U1 155
 '@BASEBOARD_FAB2_LIB.BASEBOARD_FAB2(SCH_1):PAGE80_I24@MSTR_SCONN.SCONN288_H44441003(CHIPS)':
 'DQ'<7>: CDS_PINID='DQ(7)';
NET_NAME
'M_H_DQ<8>'
 '@BASEBOARD_FAB2_LIB.BASEBOARD_FAB2(SCH_1):M_H_DQ'<8>:
 C_SIGNAL='@baseboard_fab2_lib.baseboard_fab2(sch_1):m_h_dq(8)';
NODE_NAME     U2D1 AH81
 '@BASEBOARD_FAB2_LIB.BASEBOARD_FAB2(SCH_1):PAGE58_I172@CHPSET_LIB.SKX_EXT_B(CHIPS)':
 'DDR1_DQ'<8>: CDS_PINID='DDR1_DQ(8)';
NODE_NAME     J1G2 161
 '@BASEBOARD_FAB2_LIB.BASEBOARD_FAB2(SCH_1):PAGE79_I111@MSTR_SCONN.SCONN288_H44441004(CHIPS)':
 'DQ'<9>: CDS_PINID='DQ(9)';
NODE_NAME     J9U1 16
 '@BASEBOARD_FAB2_LIB.BASEBOARD_FAB2(SCH_1):PAGE80_I24@MSTR_SCONN.SCONN288_H44441003(CHIPS)':
 'DQ'<8>: CDS_PINID='DQ(8)';
NET_NAME
'M_H_DQ<9>'
 '@BASEBOARD_FAB2_LIB.BASEBOARD_FAB2(SCH_1):M_H_DQ'<9>:
 C_SIGNAL='@baseboard_fab2_lib.baseboard_fab2(sch_1):m_h_dq(9)';
NODE_NAME     U2D1 AF79
 '@BASEBOARD_FAB2_LIB.BASEBOARD_FAB2(SCH_1):PAGE58_I172@CHPSET_LIB.SKX_EXT_B(CHIPS)':
 'DDR1_DQ'<9>: CDS_PINID='DDR1_DQ(9)';
NODE_NAME     J1G2 16
 '@BASEBOARD_FAB2_LIB.BASEBOARD_FAB2(SCH_1):PAGE79_I111@MSTR_SCONN.SCONN288_H44441004(CHIPS)':
 'DQ'<8>: CDS_PINID='DQ(8)';
NODE_NAME     J9U1 161
 '@BASEBOARD_FAB2_LIB.BASEBOARD_FAB2(SCH_1):PAGE80_I24@MSTR_SCONN.SCONN288_H44441003(CHIPS)':
 'DQ'<9>: CDS_PINID='DQ(9)';
NET_NAME
'M_H_DQS_DN<0>'
 '@BASEBOARD_FAB2_LIB.BASEBOARD_FAB2(SCH_1):M_H_DQS_DN'<0>:
 C_SIGNAL='@baseboard_fab2_lib.baseboard_fab2(sch_1):m_h_dqs_dn(0)';
NODE_NAME     U2D1 AP79
 '@BASEBOARD_FAB2_LIB.BASEBOARD_FAB2(SCH_1):PAGE58_I172@CHPSET_LIB.SKX_EXT_B(CHIPS)':
 'DDR1_DQS_DN'<0>: CDS_PINID='DDR1_DQS_DN(0)';
NODE_NAME     J1G2 152
 '@BASEBOARD_FAB2_LIB.BASEBOARD_FAB2(SCH_1):PAGE79_I64@MSTR_SCONN.SCONN288_H44441004(CHIPS)':
 'DQS0N': CDS_PINID='DQS0N';
NODE_NAME     J9U1 152
 '@BASEBOARD_FAB2_LIB.BASEBOARD_FAB2(SCH_1):PAGE80_I101@MSTR_SCONN.SCONN288_H44441003(CHIPS)':
 'DQS0N': CDS_PINID='DQS0N';
NET_NAME
'M_H_DQS_DN<10>'
 '@BASEBOARD_FAB2_LIB.BASEBOARD_FAB2(SCH_1):M_H_DQS_DN'<10>:
 C_SIGNAL='@baseboard_fab2_lib.baseboard_fab2(sch_1):m_h_dqs_dn(10)';
NODE_NAME     U2D1 AG82
 '@BASEBOARD_FAB2_LIB.BASEBOARD_FAB2(SCH_1):PAGE58_I172@CHPSET_LIB.SKX_EXT_B(CHIPS)':
 'DDR1_DQS_DN'<10>: CDS_PINID='DDR1_DQS_DN(10)';
NODE_NAME     J1G2 19
 '@BASEBOARD_FAB2_LIB.BASEBOARD_FAB2(SCH_1):PAGE79_I64@MSTR_SCONN.SCONN288_H44441004(CHIPS)':
 'DQS10N': CDS_PINID='DQS10N';
NODE_NAME     J9U1 19
 '@BASEBOARD_FAB2_LIB.BASEBOARD_FAB2(SCH_1):PAGE80_I101@MSTR_SCONN.SCONN288_H44441003(CHIPS)':
 'DQS10N': CDS_PINID='DQS10N';
NET_NAME
'M_H_DQS_DN<11>'
 '@BASEBOARD_FAB2_LIB.BASEBOARD_FAB2(SCH_1):M_H_DQS_DN'<11>:
 C_SIGNAL='@baseboard_fab2_lib.baseboard_fab2(sch_1):m_h_dqs_dn(11)';
NODE_NAME     U2D1 D79
 '@BASEBOARD_FAB2_LIB.BASEBOARD_FAB2(SCH_1):PAGE58_I172@CHPSET_LIB.SKX_EXT_B(CHIPS)':
 'DDR1_DQS_DN'<11>: CDS_PINID='DDR1_DQS_DN(11)';
NODE_NAME     J1G2 30
 '@BASEBOARD_FAB2_LIB.BASEBOARD_FAB2(SCH_1):PAGE79_I64@MSTR_SCONN.SCONN288_H44441004(CHIPS)':
 'DQS11N': CDS_PINID='DQS11N';
NODE_NAME     J9U1 30
 '@BASEBOARD_FAB2_LIB.BASEBOARD_FAB2(SCH_1):PAGE80_I101@MSTR_SCONN.SCONN288_H44441003(CHIPS)':
 'DQS11N': CDS_PINID='DQS11N';
NET_NAME
'M_H_DQS_DN<12>'
 '@BASEBOARD_FAB2_LIB.BASEBOARD_FAB2(SCH_1):M_H_DQS_DN'<12>:
 C_SIGNAL='@baseboard_fab2_lib.baseboard_fab2(sch_1):m_h_dqs_dn(12)';
NODE_NAME     U2D1 B73
 '@BASEBOARD_FAB2_LIB.BASEBOARD_FAB2(SCH_1):PAGE58_I172@CHPSET_LIB.SKX_EXT_B(CHIPS)':
 'DDR1_DQS_DN'<12>: CDS_PINID='DDR1_DQS_DN(12)';
NODE_NAME     J1G2 41
 '@BASEBOARD_FAB2_LIB.BASEBOARD_FAB2(SCH_1):PAGE79_I64@MSTR_SCONN.SCONN288_H44441004(CHIPS)':
 'DQS12N': CDS_PINID='DQS12N';
NODE_NAME     J9U1 41
 '@BASEBOARD_FAB2_LIB.BASEBOARD_FAB2(SCH_1):PAGE80_I101@MSTR_SCONN.SCONN288_H44441003(CHIPS)':
 'DQS12N': CDS_PINID='DQS12N';
NET_NAME
'M_H_DQS_DN<13>'
 '@BASEBOARD_FAB2_LIB.BASEBOARD_FAB2(SCH_1):M_H_DQS_DN'<13>:
 C_SIGNAL='@baseboard_fab2_lib.baseboard_fab2(sch_1):m_h_dqs_dn(13)';
NODE_NAME     U2D1 J42
 '@BASEBOARD_FAB2_LIB.BASEBOARD_FAB2(SCH_1):PAGE58_I172@CHPSET_LIB.SKX_EXT_B(CHIPS)':
 'DDR1_DQS_DN'<13>: CDS_PINID='DDR1_DQS_DN(13)';
NODE_NAME     J1G2 100
 '@BASEBOARD_FAB2_LIB.BASEBOARD_FAB2(SCH_1):PAGE79_I64@MSTR_SCONN.SCONN288_H44441004(CHIPS)':
 'DQS13N': CDS_PINID='DQS13N';
NODE_NAME     J9U1 100
 '@BASEBOARD_FAB2_LIB.BASEBOARD_FAB2(SCH_1):PAGE80_I101@MSTR_SCONN.SCONN288_H44441003(CHIPS)':
 'DQS13N': CDS_PINID='DQS13N';
NET_NAME
'M_H_DQS_DN<14>'
 '@BASEBOARD_FAB2_LIB.BASEBOARD_FAB2(SCH_1):M_H_DQS_DN'<14>:
 C_SIGNAL='@baseboard_fab2_lib.baseboard_fab2(sch_1):m_h_dqs_dn(14)';
NODE_NAME     U2D1 A34
 '@BASEBOARD_FAB2_LIB.BASEBOARD_FAB2(SCH_1):PAGE58_I172@CHPSET_LIB.SKX_EXT_B(CHIPS)':
 'DDR1_DQS_DN'<14>: CDS_PINID='DDR1_DQS_DN(14)';
NODE_NAME     J1G2 111
 '@BASEBOARD_FAB2_LIB.BASEBOARD_FAB2(SCH_1):PAGE79_I64@MSTR_SCONN.SCONN288_H44441004(CHIPS)':
 'DQS14N': CDS_PINID='DQS14N';
NODE_NAME     J9U1 111
 '@BASEBOARD_FAB2_LIB.BASEBOARD_FAB2(SCH_1):PAGE80_I101@MSTR_SCONN.SCONN288_H44441003(CHIPS)':
 'DQS14N': CDS_PINID='DQS14N';
NET_NAME
'M_H_DQS_DN<15>'
 '@BASEBOARD_FAB2_LIB.BASEBOARD_FAB2(SCH_1):M_H_DQS_DN'<15>:
 C_SIGNAL='@baseboard_fab2_lib.baseboard_fab2(sch_1):m_h_dqs_dn(15)';
NODE_NAME     U2D1 A28
 '@BASEBOARD_FAB2_LIB.BASEBOARD_FAB2(SCH_1):PAGE58_I172@CHPSET_LIB.SKX_EXT_B(CHIPS)':
 'DDR1_DQS_DN'<15>: CDS_PINID='DDR1_DQS_DN(15)';
NODE_NAME     J1G2 122
 '@BASEBOARD_FAB2_LIB.BASEBOARD_FAB2(SCH_1):PAGE79_I64@MSTR_SCONN.SCONN288_H44441004(CHIPS)':
 'DQS15N': CDS_PINID='DQS15N';
NODE_NAME     J9U1 122
 '@BASEBOARD_FAB2_LIB.BASEBOARD_FAB2(SCH_1):PAGE80_I101@MSTR_SCONN.SCONN288_H44441003(CHIPS)':
 'DQS15N': CDS_PINID='DQS15N';
NET_NAME
'M_H_DQS_DN<16>'
 '@BASEBOARD_FAB2_LIB.BASEBOARD_FAB2(SCH_1):M_H_DQS_DN'<16>:
 C_SIGNAL='@baseboard_fab2_lib.baseboard_fab2(sch_1):m_h_dqs_dn(16)';
NODE_NAME     U2D1 T27
 '@BASEBOARD_FAB2_LIB.BASEBOARD_FAB2(SCH_1):PAGE58_I172@CHPSET_LIB.SKX_EXT_B(CHIPS)':
 'DDR1_DQS_DN'<16>: CDS_PINID='DDR1_DQS_DN(16)';
NODE_NAME     J1G2 133
 '@BASEBOARD_FAB2_LIB.BASEBOARD_FAB2(SCH_1):PAGE79_I64@MSTR_SCONN.SCONN288_H44441004(CHIPS)':
 'DQS16N': CDS_PINID='DQS16N';
NODE_NAME     J9U1 133
 '@BASEBOARD_FAB2_LIB.BASEBOARD_FAB2(SCH_1):PAGE80_I101@MSTR_SCONN.SCONN288_H44441003(CHIPS)':
 'DQS16N': CDS_PINID='DQS16N';
NET_NAME
'M_H_DQS_DN<17>'
 '@BASEBOARD_FAB2_LIB.BASEBOARD_FAB2(SCH_1):M_H_DQS_DN'<17>:
 C_SIGNAL='@baseboard_fab2_lib.baseboard_fab2(sch_1):m_h_dqs_dn(17)';
NODE_NAME     U2D1 G68
 '@BASEBOARD_FAB2_LIB.BASEBOARD_FAB2(SCH_1):PAGE58_I172@CHPSET_LIB.SKX_EXT_B(CHIPS)':
 'DDR1_DQS_DN'<17>: CDS_PINID='DDR1_DQS_DN(17)';
NODE_NAME     J1G2 52
 '@BASEBOARD_FAB2_LIB.BASEBOARD_FAB2(SCH_1):PAGE79_I64@MSTR_SCONN.SCONN288_H44441004(CHIPS)':
 'DQS17N': CDS_PINID='DQS17N';
NODE_NAME     J9U1 52
 '@BASEBOARD_FAB2_LIB.BASEBOARD_FAB2(SCH_1):PAGE80_I101@MSTR_SCONN.SCONN288_H44441003(CHIPS)':
 'DQS17N': CDS_PINID='DQS17N';
NET_NAME
'M_H_DQS_DN<1>'
 '@BASEBOARD_FAB2_LIB.BASEBOARD_FAB2(SCH_1):M_H_DQS_DN'<1>:
 C_SIGNAL='@baseboard_fab2_lib.baseboard_fab2(sch_1):m_h_dqs_dn(1)';
NODE_NAME     U2D1 AD79
 '@BASEBOARD_FAB2_LIB.BASEBOARD_FAB2(SCH_1):PAGE58_I172@CHPSET_LIB.SKX_EXT_B(CHIPS)':
 'DDR1_DQS_DN'<1>: CDS_PINID='DDR1_DQS_DN(1)';
NODE_NAME     J1G2 163
 '@BASEBOARD_FAB2_LIB.BASEBOARD_FAB2(SCH_1):PAGE79_I64@MSTR_SCONN.SCONN288_H44441004(CHIPS)':
 'DQS1N': CDS_PINID='DQS1N';
NODE_NAME     J9U1 163
 '@BASEBOARD_FAB2_LIB.BASEBOARD_FAB2(SCH_1):PAGE80_I101@MSTR_SCONN.SCONN288_H44441003(CHIPS)':
 'DQS1N': CDS_PINID='DQS1N';
NET_NAME
'M_H_DQS_DN<2>'
 '@BASEBOARD_FAB2_LIB.BASEBOARD_FAB2(SCH_1):M_H_DQS_DN'<2>:
 C_SIGNAL='@baseboard_fab2_lib.baseboard_fab2(sch_1):m_h_dqs_dn(2)';
NODE_NAME     U2D1 K79
 '@BASEBOARD_FAB2_LIB.BASEBOARD_FAB2(SCH_1):PAGE58_I172@CHPSET_LIB.SKX_EXT_B(CHIPS)':
 'DDR1_DQS_DN'<2>: CDS_PINID='DDR1_DQS_DN(2)';
NODE_NAME     J1G2 174
 '@BASEBOARD_FAB2_LIB.BASEBOARD_FAB2(SCH_1):PAGE79_I64@MSTR_SCONN.SCONN288_H44441004(CHIPS)':
 'DQS2N': CDS_PINID='DQS2N';
NODE_NAME     J9U1 174
 '@BASEBOARD_FAB2_LIB.BASEBOARD_FAB2(SCH_1):PAGE80_I101@MSTR_SCONN.SCONN288_H44441003(CHIPS)':
 'DQS2N': CDS_PINID='DQS2N';
NET_NAME
'M_H_DQS_DN<3>'
 '@BASEBOARD_FAB2_LIB.BASEBOARD_FAB2(SCH_1):M_H_DQS_DN'<3>:
 C_SIGNAL='@baseboard_fab2_lib.baseboard_fab2(sch_1):m_h_dqs_dn(3)';
NODE_NAME     U2D1 H73
 '@BASEBOARD_FAB2_LIB.BASEBOARD_FAB2(SCH_1):PAGE58_I172@CHPSET_LIB.SKX_EXT_B(CHIPS)':
 'DDR1_DQS_DN'<3>: CDS_PINID='DDR1_DQS_DN(3)';
NODE_NAME     J1G2 185
 '@BASEBOARD_FAB2_LIB.BASEBOARD_FAB2(SCH_1):PAGE79_I64@MSTR_SCONN.SCONN288_H44441004(CHIPS)':
 'DQS3N': CDS_PINID='DQS3N';
NODE_NAME     J9U1 185
 '@BASEBOARD_FAB2_LIB.BASEBOARD_FAB2(SCH_1):PAGE80_I101@MSTR_SCONN.SCONN288_H44441003(CHIPS)':
 'DQS3N': CDS_PINID='DQS3N';
NET_NAME
'M_H_DQS_DN<4>'
 '@BASEBOARD_FAB2_LIB.BASEBOARD_FAB2(SCH_1):M_H_DQS_DN'<4>:
 C_SIGNAL='@baseboard_fab2_lib.baseboard_fab2(sch_1):m_h_dqs_dn(4)';
NODE_NAME     U2D1 N42
 '@BASEBOARD_FAB2_LIB.BASEBOARD_FAB2(SCH_1):PAGE58_I172@CHPSET_LIB.SKX_EXT_B(CHIPS)':
 'DDR1_DQS_DN'<4>: CDS_PINID='DDR1_DQS_DN(4)';
NODE_NAME     J1G2 244
 '@BASEBOARD_FAB2_LIB.BASEBOARD_FAB2(SCH_1):PAGE79_I64@MSTR_SCONN.SCONN288_H44441004(CHIPS)':
 'DQS4N': CDS_PINID='DQS4N';
NODE_NAME     J9U1 244
 '@BASEBOARD_FAB2_LIB.BASEBOARD_FAB2(SCH_1):PAGE80_I101@MSTR_SCONN.SCONN288_H44441003(CHIPS)':
 'DQS4N': CDS_PINID='DQS4N';
NET_NAME
'M_H_DQS_DN<5>'
 '@BASEBOARD_FAB2_LIB.BASEBOARD_FAB2(SCH_1):M_H_DQS_DN'<5>:
 C_SIGNAL='@baseboard_fab2_lib.baseboard_fab2(sch_1):m_h_dqs_dn(5)';
NODE_NAME     U2D1 G34
 '@BASEBOARD_FAB2_LIB.BASEBOARD_FAB2(SCH_1):PAGE58_I172@CHPSET_LIB.SKX_EXT_B(CHIPS)':
 'DDR1_DQS_DN'<5>: CDS_PINID='DDR1_DQS_DN(5)';
NODE_NAME     J1G2 255
 '@BASEBOARD_FAB2_LIB.BASEBOARD_FAB2(SCH_1):PAGE79_I64@MSTR_SCONN.SCONN288_H44441004(CHIPS)':
 'DQS5N': CDS_PINID='DQS5N';
NODE_NAME     J9U1 255
 '@BASEBOARD_FAB2_LIB.BASEBOARD_FAB2(SCH_1):PAGE80_I101@MSTR_SCONN.SCONN288_H44441003(CHIPS)':
 'DQS5N': CDS_PINID='DQS5N';
NET_NAME
'M_H_DQS_DN<6>'
 '@BASEBOARD_FAB2_LIB.BASEBOARD_FAB2(SCH_1):M_H_DQS_DN'<6>:
 C_SIGNAL='@baseboard_fab2_lib.baseboard_fab2(sch_1):m_h_dqs_dn(6)';
NODE_NAME     U2D1 G28
 '@BASEBOARD_FAB2_LIB.BASEBOARD_FAB2(SCH_1):PAGE58_I172@CHPSET_LIB.SKX_EXT_B(CHIPS)':
 'DDR1_DQS_DN'<6>: CDS_PINID='DDR1_DQS_DN(6)';
NODE_NAME     J1G2 266
 '@BASEBOARD_FAB2_LIB.BASEBOARD_FAB2(SCH_1):PAGE79_I64@MSTR_SCONN.SCONN288_H44441004(CHIPS)':
 'DQS6N': CDS_PINID='DQS6N';
NODE_NAME     J9U1 266
 '@BASEBOARD_FAB2_LIB.BASEBOARD_FAB2(SCH_1):PAGE80_I101@MSTR_SCONN.SCONN288_H44441003(CHIPS)':
 'DQS6N': CDS_PINID='DQS6N';
NET_NAME
'M_H_DQS_DN<7>'
 '@BASEBOARD_FAB2_LIB.BASEBOARD_FAB2(SCH_1):M_H_DQS_DN'<7>:
 C_SIGNAL='@baseboard_fab2_lib.baseboard_fab2(sch_1):m_h_dqs_dn(7)';
NODE_NAME     U2D1 AB27
 '@BASEBOARD_FAB2_LIB.BASEBOARD_FAB2(SCH_1):PAGE58_I172@CHPSET_LIB.SKX_EXT_B(CHIPS)':
 'DDR1_DQS_DN'<7>: CDS_PINID='DDR1_DQS_DN(7)';
NODE_NAME     J1G2 277
 '@BASEBOARD_FAB2_LIB.BASEBOARD_FAB2(SCH_1):PAGE79_I64@MSTR_SCONN.SCONN288_H44441004(CHIPS)':
 'DQS7N': CDS_PINID='DQS7N';
NODE_NAME     J9U1 277
 '@BASEBOARD_FAB2_LIB.BASEBOARD_FAB2(SCH_1):PAGE80_I101@MSTR_SCONN.SCONN288_H44441003(CHIPS)':
 'DQS7N': CDS_PINID='DQS7N';
NET_NAME
'M_H_DQS_DN<8>'
 '@BASEBOARD_FAB2_LIB.BASEBOARD_FAB2(SCH_1):M_H_DQS_DN'<8>:
 C_SIGNAL='@baseboard_fab2_lib.baseboard_fab2(sch_1):m_h_dqs_dn(8)';
NODE_NAME     U2D1 N68
 '@BASEBOARD_FAB2_LIB.BASEBOARD_FAB2(SCH_1):PAGE58_I172@CHPSET_LIB.SKX_EXT_B(CHIPS)':
 'DDR1_DQS_DN'<8>: CDS_PINID='DDR1_DQS_DN(8)';
NODE_NAME     J1G2 196
 '@BASEBOARD_FAB2_LIB.BASEBOARD_FAB2(SCH_1):PAGE79_I64@MSTR_SCONN.SCONN288_H44441004(CHIPS)':
 'DQS8N': CDS_PINID='DQS8N';
NODE_NAME     J9U1 196
 '@BASEBOARD_FAB2_LIB.BASEBOARD_FAB2(SCH_1):PAGE80_I101@MSTR_SCONN.SCONN288_H44441003(CHIPS)':
 'DQS8N': CDS_PINID='DQS8N';
NET_NAME
'M_H_DQS_DN<9>'
 '@BASEBOARD_FAB2_LIB.BASEBOARD_FAB2(SCH_1):M_H_DQS_DN'<9>:
 C_SIGNAL='@baseboard_fab2_lib.baseboard_fab2(sch_1):m_h_dqs_dn(9)';
NODE_NAME     U2D1 AU82
 '@BASEBOARD_FAB2_LIB.BASEBOARD_FAB2(SCH_1):PAGE58_I172@CHPSET_LIB.SKX_EXT_B(CHIPS)':
 'DDR1_DQS_DN'<9>: CDS_PINID='DDR1_DQS_DN(9)';
NODE_NAME     J1G2 8
 '@BASEBOARD_FAB2_LIB.BASEBOARD_FAB2(SCH_1):PAGE79_I64@MSTR_SCONN.SCONN288_H44441004(CHIPS)':
 'DQS9N': CDS_PINID='DQS9N';
NODE_NAME     J9U1 8
 '@BASEBOARD_FAB2_LIB.BASEBOARD_FAB2(SCH_1):PAGE80_I101@MSTR_SCONN.SCONN288_H44441003(CHIPS)':
 'DQS9N': CDS_PINID='DQS9N';
NET_NAME
'M_H_DQS_DP<0>'
 '@BASEBOARD_FAB2_LIB.BASEBOARD_FAB2(SCH_1):M_H_DQS_DP'<0>:
 C_SIGNAL='@baseboard_fab2_lib.baseboard_fab2(sch_1):m_h_dqs_dp(0)';
NODE_NAME     U2D1 AR80
 '@BASEBOARD_FAB2_LIB.BASEBOARD_FAB2(SCH_1):PAGE58_I172@CHPSET_LIB.SKX_EXT_B(CHIPS)':
 'DDR1_DQS_DP'<0>: CDS_PINID='DDR1_DQS_DP(0)';
NODE_NAME     J1G2 153
 '@BASEBOARD_FAB2_LIB.BASEBOARD_FAB2(SCH_1):PAGE79_I64@MSTR_SCONN.SCONN288_H44441004(CHIPS)':
 'DQS0P': CDS_PINID='DQS0P';
NODE_NAME     J9U1 153
 '@BASEBOARD_FAB2_LIB.BASEBOARD_FAB2(SCH_1):PAGE80_I101@MSTR_SCONN.SCONN288_H44441003(CHIPS)':
 'DQS0P': CDS_PINID='DQS0P';
NET_NAME
'M_H_DQS_DP<10>'
 '@BASEBOARD_FAB2_LIB.BASEBOARD_FAB2(SCH_1):M_H_DQS_DP'<10>:
 C_SIGNAL='@baseboard_fab2_lib.baseboard_fab2(sch_1):m_h_dqs_dp(10)';
NODE_NAME     U2D1 AF81
 '@BASEBOARD_FAB2_LIB.BASEBOARD_FAB2(SCH_1):PAGE58_I172@CHPSET_LIB.SKX_EXT_B(CHIPS)':
 'DDR1_DQS_DP'<10>: CDS_PINID='DDR1_DQS_DP(10)';
NODE_NAME     J1G2 18
 '@BASEBOARD_FAB2_LIB.BASEBOARD_FAB2(SCH_1):PAGE79_I64@MSTR_SCONN.SCONN288_H44441004(CHIPS)':
 'DQS10P': CDS_PINID='DQS10P';
NODE_NAME     J9U1 18
 '@BASEBOARD_FAB2_LIB.BASEBOARD_FAB2(SCH_1):PAGE80_I101@MSTR_SCONN.SCONN288_H44441003(CHIPS)':
 'DQS10P': CDS_PINID='DQS10P';
NET_NAME
'M_H_DQS_DP<11>'
 '@BASEBOARD_FAB2_LIB.BASEBOARD_FAB2(SCH_1):M_H_DQS_DP'<11>:
 C_SIGNAL='@baseboard_fab2_lib.baseboard_fab2(sch_1):m_h_dqs_dp(11)';
NODE_NAME     U2D1 F79
 '@BASEBOARD_FAB2_LIB.BASEBOARD_FAB2(SCH_1):PAGE58_I172@CHPSET_LIB.SKX_EXT_B(CHIPS)':
 'DDR1_DQS_DP'<11>: CDS_PINID='DDR1_DQS_DP(11)';
NODE_NAME     J1G2 29
 '@BASEBOARD_FAB2_LIB.BASEBOARD_FAB2(SCH_1):PAGE79_I64@MSTR_SCONN.SCONN288_H44441004(CHIPS)':
 'DQS11P': CDS_PINID='DQS11P';
NODE_NAME     J9U1 29
 '@BASEBOARD_FAB2_LIB.BASEBOARD_FAB2(SCH_1):PAGE80_I101@MSTR_SCONN.SCONN288_H44441003(CHIPS)':
 'DQS11P': CDS_PINID='DQS11P';
NET_NAME
'M_H_DQS_DP<12>'
 '@BASEBOARD_FAB2_LIB.BASEBOARD_FAB2(SCH_1):M_H_DQS_DP'<12>:
 C_SIGNAL='@baseboard_fab2_lib.baseboard_fab2(sch_1):m_h_dqs_dp(12)';
NODE_NAME     U2D1 D73
 '@BASEBOARD_FAB2_LIB.BASEBOARD_FAB2(SCH_1):PAGE58_I172@CHPSET_LIB.SKX_EXT_B(CHIPS)':
 'DDR1_DQS_DP'<12>: CDS_PINID='DDR1_DQS_DP(12)';
NODE_NAME     J1G2 40
 '@BASEBOARD_FAB2_LIB.BASEBOARD_FAB2(SCH_1):PAGE79_I64@MSTR_SCONN.SCONN288_H44441004(CHIPS)':
 'DQS12P': CDS_PINID='DQS12P';
NODE_NAME     J9U1 40
 '@BASEBOARD_FAB2_LIB.BASEBOARD_FAB2(SCH_1):PAGE80_I101@MSTR_SCONN.SCONN288_H44441003(CHIPS)':
 'DQS12P': CDS_PINID='DQS12P';
NET_NAME
'M_H_DQS_DP<13>'
 '@BASEBOARD_FAB2_LIB.BASEBOARD_FAB2(SCH_1):M_H_DQS_DP'<13>:
 C_SIGNAL='@baseboard_fab2_lib.baseboard_fab2(sch_1):m_h_dqs_dp(13)';
NODE_NAME     U2D1 L42
 '@BASEBOARD_FAB2_LIB.BASEBOARD_FAB2(SCH_1):PAGE58_I172@CHPSET_LIB.SKX_EXT_B(CHIPS)':
 'DDR1_DQS_DP'<13>: CDS_PINID='DDR1_DQS_DP(13)';
NODE_NAME     J1G2 99
 '@BASEBOARD_FAB2_LIB.BASEBOARD_FAB2(SCH_1):PAGE79_I64@MSTR_SCONN.SCONN288_H44441004(CHIPS)':
 'DQS13P': CDS_PINID='DQS13P';
NODE_NAME     J9U1 99
 '@BASEBOARD_FAB2_LIB.BASEBOARD_FAB2(SCH_1):PAGE80_I101@MSTR_SCONN.SCONN288_H44441003(CHIPS)':
 'DQS13P': CDS_PINID='DQS13P';
NET_NAME
'M_H_DQS_DP<14>'
 '@BASEBOARD_FAB2_LIB.BASEBOARD_FAB2(SCH_1):M_H_DQS_DP'<14>:
 C_SIGNAL='@baseboard_fab2_lib.baseboard_fab2(sch_1):m_h_dqs_dp(14)';
NODE_NAME     U2D1 C34
 '@BASEBOARD_FAB2_LIB.BASEBOARD_FAB2(SCH_1):PAGE58_I172@CHPSET_LIB.SKX_EXT_B(CHIPS)':
 'DDR1_DQS_DP'<14>: CDS_PINID='DDR1_DQS_DP(14)';
NODE_NAME     J1G2 110
 '@BASEBOARD_FAB2_LIB.BASEBOARD_FAB2(SCH_1):PAGE79_I64@MSTR_SCONN.SCONN288_H44441004(CHIPS)':
 'DQS14P': CDS_PINID='DQS14P';
NODE_NAME     J9U1 110
 '@BASEBOARD_FAB2_LIB.BASEBOARD_FAB2(SCH_1):PAGE80_I101@MSTR_SCONN.SCONN288_H44441003(CHIPS)':
 'DQS14P': CDS_PINID='DQS14P';
NET_NAME
'M_H_DQS_DP<15>'
 '@BASEBOARD_FAB2_LIB.BASEBOARD_FAB2(SCH_1):M_H_DQS_DP'<15>:
 C_SIGNAL='@baseboard_fab2_lib.baseboard_fab2(sch_1):m_h_dqs_dp(15)';
NODE_NAME     U2D1 C28
 '@BASEBOARD_FAB2_LIB.BASEBOARD_FAB2(SCH_1):PAGE58_I172@CHPSET_LIB.SKX_EXT_B(CHIPS)':
 'DDR1_DQS_DP'<15>: CDS_PINID='DDR1_DQS_DP(15)';
NODE_NAME     J1G2 121
 '@BASEBOARD_FAB2_LIB.BASEBOARD_FAB2(SCH_1):PAGE79_I64@MSTR_SCONN.SCONN288_H44441004(CHIPS)':
 'DQS15P': CDS_PINID='DQS15P';
NODE_NAME     J9U1 121
 '@BASEBOARD_FAB2_LIB.BASEBOARD_FAB2(SCH_1):PAGE80_I101@MSTR_SCONN.SCONN288_H44441003(CHIPS)':
 'DQS15P': CDS_PINID='DQS15P';
NET_NAME
'M_H_DQS_DP<16>'
 '@BASEBOARD_FAB2_LIB.BASEBOARD_FAB2(SCH_1):M_H_DQS_DP'<16>:
 C_SIGNAL='@baseboard_fab2_lib.baseboard_fab2(sch_1):m_h_dqs_dp(16)';
NODE_NAME     U2D1 V27
 '@BASEBOARD_FAB2_LIB.BASEBOARD_FAB2(SCH_1):PAGE58_I172@CHPSET_LIB.SKX_EXT_B(CHIPS)':
 'DDR1_DQS_DP'<16>: CDS_PINID='DDR1_DQS_DP(16)';
NODE_NAME     J1G2 132
 '@BASEBOARD_FAB2_LIB.BASEBOARD_FAB2(SCH_1):PAGE79_I64@MSTR_SCONN.SCONN288_H44441004(CHIPS)':
 'DQS16P': CDS_PINID='DQS16P';
NODE_NAME     J9U1 132
 '@BASEBOARD_FAB2_LIB.BASEBOARD_FAB2(SCH_1):PAGE80_I101@MSTR_SCONN.SCONN288_H44441003(CHIPS)':
 'DQS16P': CDS_PINID='DQS16P';
NET_NAME
'M_H_DQS_DP<17>'
 '@BASEBOARD_FAB2_LIB.BASEBOARD_FAB2(SCH_1):M_H_DQS_DP'<17>:
 C_SIGNAL='@baseboard_fab2_lib.baseboard_fab2(sch_1):m_h_dqs_dp(17)';
NODE_NAME     U2D1 J68
 '@BASEBOARD_FAB2_LIB.BASEBOARD_FAB2(SCH_1):PAGE58_I172@CHPSET_LIB.SKX_EXT_B(CHIPS)':
 'DDR1_DQS_DP'<17>: CDS_PINID='DDR1_DQS_DP(17)';
NODE_NAME     J1G2 51
 '@BASEBOARD_FAB2_LIB.BASEBOARD_FAB2(SCH_1):PAGE79_I64@MSTR_SCONN.SCONN288_H44441004(CHIPS)':
 'DQS17P': CDS_PINID='DQS17P';
NODE_NAME     J9U1 51
 '@BASEBOARD_FAB2_LIB.BASEBOARD_FAB2(SCH_1):PAGE80_I101@MSTR_SCONN.SCONN288_H44441003(CHIPS)':
 'DQS17P': CDS_PINID='DQS17P';
NET_NAME
'M_H_DQS_DP<1>'
 '@BASEBOARD_FAB2_LIB.BASEBOARD_FAB2(SCH_1):M_H_DQS_DP'<1>:
 C_SIGNAL='@baseboard_fab2_lib.baseboard_fab2(sch_1):m_h_dqs_dp(1)';
NODE_NAME     U2D1 AE80
 '@BASEBOARD_FAB2_LIB.BASEBOARD_FAB2(SCH_1):PAGE58_I172@CHPSET_LIB.SKX_EXT_B(CHIPS)':
 'DDR1_DQS_DP'<1>: CDS_PINID='DDR1_DQS_DP(1)';
NODE_NAME     J1G2 164
 '@BASEBOARD_FAB2_LIB.BASEBOARD_FAB2(SCH_1):PAGE79_I64@MSTR_SCONN.SCONN288_H44441004(CHIPS)':
 'DQS1P': CDS_PINID='DQS1P';
NODE_NAME     J9U1 164
 '@BASEBOARD_FAB2_LIB.BASEBOARD_FAB2(SCH_1):PAGE80_I101@MSTR_SCONN.SCONN288_H44441003(CHIPS)':
 'DQS1P': CDS_PINID='DQS1P';
NET_NAME
'M_H_DQS_DP<2>'
 '@BASEBOARD_FAB2_LIB.BASEBOARD_FAB2(SCH_1):M_H_DQS_DP'<2>:
 C_SIGNAL='@baseboard_fab2_lib.baseboard_fab2(sch_1):m_h_dqs_dp(2)';
NODE_NAME     U2D1 H79
 '@BASEBOARD_FAB2_LIB.BASEBOARD_FAB2(SCH_1):PAGE58_I172@CHPSET_LIB.SKX_EXT_B(CHIPS)':
 'DDR1_DQS_DP'<2>: CDS_PINID='DDR1_DQS_DP(2)';
NODE_NAME     J1G2 175
 '@BASEBOARD_FAB2_LIB.BASEBOARD_FAB2(SCH_1):PAGE79_I64@MSTR_SCONN.SCONN288_H44441004(CHIPS)':
 'DQS2P': CDS_PINID='DQS2P';
NODE_NAME     J9U1 175
 '@BASEBOARD_FAB2_LIB.BASEBOARD_FAB2(SCH_1):PAGE80_I101@MSTR_SCONN.SCONN288_H44441003(CHIPS)':
 'DQS2P': CDS_PINID='DQS2P';
NET_NAME
'M_H_DQS_DP<3>'
 '@BASEBOARD_FAB2_LIB.BASEBOARD_FAB2(SCH_1):M_H_DQS_DP'<3>:
 C_SIGNAL='@baseboard_fab2_lib.baseboard_fab2(sch_1):m_h_dqs_dp(3)';
NODE_NAME     U2D1 F73
 '@BASEBOARD_FAB2_LIB.BASEBOARD_FAB2(SCH_1):PAGE58_I172@CHPSET_LIB.SKX_EXT_B(CHIPS)':
 'DDR1_DQS_DP'<3>: CDS_PINID='DDR1_DQS_DP(3)';
NODE_NAME     J1G2 186
 '@BASEBOARD_FAB2_LIB.BASEBOARD_FAB2(SCH_1):PAGE79_I64@MSTR_SCONN.SCONN288_H44441004(CHIPS)':
 'DQS3P': CDS_PINID='DQS3P';
NODE_NAME     J9U1 186
 '@BASEBOARD_FAB2_LIB.BASEBOARD_FAB2(SCH_1):PAGE80_I101@MSTR_SCONN.SCONN288_H44441003(CHIPS)':
 'DQS3P': CDS_PINID='DQS3P';
NET_NAME
'M_H_DQS_DP<4>'
 '@BASEBOARD_FAB2_LIB.BASEBOARD_FAB2(SCH_1):M_H_DQS_DP'<4>:
 C_SIGNAL='@baseboard_fab2_lib.baseboard_fab2(sch_1):m_h_dqs_dp(4)';
NODE_NAME     U2D1 R42
 '@BASEBOARD_FAB2_LIB.BASEBOARD_FAB2(SCH_1):PAGE58_I172@CHPSET_LIB.SKX_EXT_B(CHIPS)':
 'DDR1_DQS_DP'<4>: CDS_PINID='DDR1_DQS_DP(4)';
NODE_NAME     J1G2 245
 '@BASEBOARD_FAB2_LIB.BASEBOARD_FAB2(SCH_1):PAGE79_I64@MSTR_SCONN.SCONN288_H44441004(CHIPS)':
 'DQS4P': CDS_PINID='DQS4P';
NODE_NAME     J9U1 245
 '@BASEBOARD_FAB2_LIB.BASEBOARD_FAB2(SCH_1):PAGE80_I101@MSTR_SCONN.SCONN288_H44441003(CHIPS)':
 'DQS4P': CDS_PINID='DQS4P';
NET_NAME
'M_H_DQS_DP<5>'
 '@BASEBOARD_FAB2_LIB.BASEBOARD_FAB2(SCH_1):M_H_DQS_DP'<5>:
 C_SIGNAL='@baseboard_fab2_lib.baseboard_fab2(sch_1):m_h_dqs_dp(5)';
NODE_NAME     U2D1 E34
 '@BASEBOARD_FAB2_LIB.BASEBOARD_FAB2(SCH_1):PAGE58_I172@CHPSET_LIB.SKX_EXT_B(CHIPS)':
 'DDR1_DQS_DP'<5>: CDS_PINID='DDR1_DQS_DP(5)';
NODE_NAME     J1G2 256
 '@BASEBOARD_FAB2_LIB.BASEBOARD_FAB2(SCH_1):PAGE79_I64@MSTR_SCONN.SCONN288_H44441004(CHIPS)':
 'DQS5P': CDS_PINID='DQS5P';
NODE_NAME     J9U1 256
 '@BASEBOARD_FAB2_LIB.BASEBOARD_FAB2(SCH_1):PAGE80_I101@MSTR_SCONN.SCONN288_H44441003(CHIPS)':
 'DQS5P': CDS_PINID='DQS5P';
NET_NAME
'M_H_DQS_DP<6>'
 '@BASEBOARD_FAB2_LIB.BASEBOARD_FAB2(SCH_1):M_H_DQS_DP'<6>:
 C_SIGNAL='@baseboard_fab2_lib.baseboard_fab2(sch_1):m_h_dqs_dp(6)';
NODE_NAME     U2D1 E28
 '@BASEBOARD_FAB2_LIB.BASEBOARD_FAB2(SCH_1):PAGE58_I172@CHPSET_LIB.SKX_EXT_B(CHIPS)':
 'DDR1_DQS_DP'<6>: CDS_PINID='DDR1_DQS_DP(6)';
NODE_NAME     J1G2 267
 '@BASEBOARD_FAB2_LIB.BASEBOARD_FAB2(SCH_1):PAGE79_I64@MSTR_SCONN.SCONN288_H44441004(CHIPS)':
 'DQS6P': CDS_PINID='DQS6P';
NODE_NAME     J9U1 267
 '@BASEBOARD_FAB2_LIB.BASEBOARD_FAB2(SCH_1):PAGE80_I101@MSTR_SCONN.SCONN288_H44441003(CHIPS)':
 'DQS6P': CDS_PINID='DQS6P';
NET_NAME
'M_H_DQS_DP<7>'
 '@BASEBOARD_FAB2_LIB.BASEBOARD_FAB2(SCH_1):M_H_DQS_DP'<7>:
 C_SIGNAL='@baseboard_fab2_lib.baseboard_fab2(sch_1):m_h_dqs_dp(7)';
NODE_NAME     U2D1 Y27
 '@BASEBOARD_FAB2_LIB.BASEBOARD_FAB2(SCH_1):PAGE58_I172@CHPSET_LIB.SKX_EXT_B(CHIPS)':
 'DDR1_DQS_DP'<7>: CDS_PINID='DDR1_DQS_DP(7)';
NODE_NAME     J1G2 278
 '@BASEBOARD_FAB2_LIB.BASEBOARD_FAB2(SCH_1):PAGE79_I64@MSTR_SCONN.SCONN288_H44441004(CHIPS)':
 'DQS7P': CDS_PINID='DQS7P';
NODE_NAME     J9U1 278
 '@BASEBOARD_FAB2_LIB.BASEBOARD_FAB2(SCH_1):PAGE80_I101@MSTR_SCONN.SCONN288_H44441003(CHIPS)':
 'DQS7P': CDS_PINID='DQS7P';
NET_NAME
'M_H_DQS_DP<8>'
 '@BASEBOARD_FAB2_LIB.BASEBOARD_FAB2(SCH_1):M_H_DQS_DP'<8>:
 C_SIGNAL='@baseboard_fab2_lib.baseboard_fab2(sch_1):m_h_dqs_dp(8)';
NODE_NAME     U2D1 L68
 '@BASEBOARD_FAB2_LIB.BASEBOARD_FAB2(SCH_1):PAGE58_I172@CHPSET_LIB.SKX_EXT_B(CHIPS)':
 'DDR1_DQS_DP'<8>: CDS_PINID='DDR1_DQS_DP(8)';
NODE_NAME     J1G2 197
 '@BASEBOARD_FAB2_LIB.BASEBOARD_FAB2(SCH_1):PAGE79_I64@MSTR_SCONN.SCONN288_H44441004(CHIPS)':
 'DQS8P': CDS_PINID='DQS8P';
NODE_NAME     J9U1 197
 '@BASEBOARD_FAB2_LIB.BASEBOARD_FAB2(SCH_1):PAGE80_I101@MSTR_SCONN.SCONN288_H44441003(CHIPS)':
 'DQS8P': CDS_PINID='DQS8P';
NET_NAME
'M_H_DQS_DP<9>'
 '@BASEBOARD_FAB2_LIB.BASEBOARD_FAB2(SCH_1):M_H_DQS_DP'<9>:
 C_SIGNAL='@baseboard_fab2_lib.baseboard_fab2(sch_1):m_h_dqs_dp(9)';
NODE_NAME     U2D1 AT81
 '@BASEBOARD_FAB2_LIB.BASEBOARD_FAB2(SCH_1):PAGE58_I172@CHPSET_LIB.SKX_EXT_B(CHIPS)':
 'DDR1_DQS_DP'<9>: CDS_PINID='DDR1_DQS_DP(9)';
NODE_NAME     J1G2 7
 '@BASEBOARD_FAB2_LIB.BASEBOARD_FAB2(SCH_1):PAGE79_I64@MSTR_SCONN.SCONN288_H44441004(CHIPS)':
 'DQS9P': CDS_PINID='DQS9P';
NODE_NAME     J9U1 7
 '@BASEBOARD_FAB2_LIB.BASEBOARD_FAB2(SCH_1):PAGE80_I101@MSTR_SCONN.SCONN288_H44441003(CHIPS)':
 'DQS9P': CDS_PINID='DQS9P';
NET_NAME
'M_H_ECC<0>'
 '@BASEBOARD_FAB2_LIB.BASEBOARD_FAB2(SCH_1):M_H_ECC'<0>:
 C_SIGNAL='@baseboard_fab2_lib.baseboard_fab2(sch_1):m_h_ecc(0)';
NODE_NAME     U2D1 J70
 '@BASEBOARD_FAB2_LIB.BASEBOARD_FAB2(SCH_1):PAGE58_I172@CHPSET_LIB.SKX_EXT_B(CHIPS)':
 'DDR1_ECC'<0>: CDS_PINID='DDR1_ECC(0)';
NODE_NAME     J1G2 194
 '@BASEBOARD_FAB2_LIB.BASEBOARD_FAB2(SCH_1):PAGE79_I111@MSTR_SCONN.SCONN288_H44441004(CHIPS)':
 'CB'<1>: CDS_PINID='CB(1)';
NODE_NAME     J9U1 49
 '@BASEBOARD_FAB2_LIB.BASEBOARD_FAB2(SCH_1):PAGE80_I24@MSTR_SCONN.SCONN288_H44441003(CHIPS)':
 'CB'<0>: CDS_PINID='CB(0)';
NET_NAME
'M_H_ECC<1>'
 '@BASEBOARD_FAB2_LIB.BASEBOARD_FAB2(SCH_1):M_H_ECC'<1>:
 C_SIGNAL='@baseboard_fab2_lib.baseboard_fab2(sch_1):m_h_ecc(1)';
NODE_NAME     U2D1 H69
 '@BASEBOARD_FAB2_LIB.BASEBOARD_FAB2(SCH_1):PAGE58_I172@CHPSET_LIB.SKX_EXT_B(CHIPS)':
 'DDR1_ECC'<1>: CDS_PINID='DDR1_ECC(1)';
NODE_NAME     J1G2 49
 '@BASEBOARD_FAB2_LIB.BASEBOARD_FAB2(SCH_1):PAGE79_I111@MSTR_SCONN.SCONN288_H44441004(CHIPS)':
 'CB'<0>: CDS_PINID='CB(0)';
NODE_NAME     J9U1 194
 '@BASEBOARD_FAB2_LIB.BASEBOARD_FAB2(SCH_1):PAGE80_I24@MSTR_SCONN.SCONN288_H44441003(CHIPS)':
 'CB'<1>: CDS_PINID='CB(1)';
NET_NAME
'M_H_ECC<2>'
 '@BASEBOARD_FAB2_LIB.BASEBOARD_FAB2(SCH_1):M_H_ECC'<2>:
 C_SIGNAL='@baseboard_fab2_lib.baseboard_fab2(sch_1):m_h_ecc(2)';
NODE_NAME     U2D1 J66
 '@BASEBOARD_FAB2_LIB.BASEBOARD_FAB2(SCH_1):PAGE58_I172@CHPSET_LIB.SKX_EXT_B(CHIPS)':
 'DDR1_ECC'<2>: CDS_PINID='DDR1_ECC(2)';
NODE_NAME     J1G2 201
 '@BASEBOARD_FAB2_LIB.BASEBOARD_FAB2(SCH_1):PAGE79_I111@MSTR_SCONN.SCONN288_H44441004(CHIPS)':
 'CB'<3>: CDS_PINID='CB(3)';
NODE_NAME     J9U1 56
 '@BASEBOARD_FAB2_LIB.BASEBOARD_FAB2(SCH_1):PAGE80_I24@MSTR_SCONN.SCONN288_H44441003(CHIPS)':
 'CB'<2>: CDS_PINID='CB(2)';
NET_NAME
'M_H_ECC<3>'
 '@BASEBOARD_FAB2_LIB.BASEBOARD_FAB2(SCH_1):M_H_ECC'<3>:
 C_SIGNAL='@baseboard_fab2_lib.baseboard_fab2(sch_1):m_h_ecc(3)';
NODE_NAME     U2D1 L66
 '@BASEBOARD_FAB2_LIB.BASEBOARD_FAB2(SCH_1):PAGE58_I172@CHPSET_LIB.SKX_EXT_B(CHIPS)':
 'DDR1_ECC'<3>: CDS_PINID='DDR1_ECC(3)';
NODE_NAME     J1G2 56
 '@BASEBOARD_FAB2_LIB.BASEBOARD_FAB2(SCH_1):PAGE79_I111@MSTR_SCONN.SCONN288_H44441004(CHIPS)':
 'CB'<2>: CDS_PINID='CB(2)';
NODE_NAME     J9U1 201
 '@BASEBOARD_FAB2_LIB.BASEBOARD_FAB2(SCH_1):PAGE80_I24@MSTR_SCONN.SCONN288_H44441003(CHIPS)':
 'CB'<3>: CDS_PINID='CB(3)';
NET_NAME
'M_H_ECC<4>'
 '@BASEBOARD_FAB2_LIB.BASEBOARD_FAB2(SCH_1):M_H_ECC'<4>:
 C_SIGNAL='@baseboard_fab2_lib.baseboard_fab2(sch_1):m_h_ecc(4)';
NODE_NAME     U2D1 L70
 '@BASEBOARD_FAB2_LIB.BASEBOARD_FAB2(SCH_1):PAGE58_I172@CHPSET_LIB.SKX_EXT_B(CHIPS)':
 'DDR1_ECC'<4>: CDS_PINID='DDR1_ECC(4)';
NODE_NAME     J1G2 192
 '@BASEBOARD_FAB2_LIB.BASEBOARD_FAB2(SCH_1):PAGE79_I111@MSTR_SCONN.SCONN288_H44441004(CHIPS)':
 'CB'<5>: CDS_PINID='CB(5)';
NODE_NAME     J9U1 47
 '@BASEBOARD_FAB2_LIB.BASEBOARD_FAB2(SCH_1):PAGE80_I24@MSTR_SCONN.SCONN288_H44441003(CHIPS)':
 'CB'<4>: CDS_PINID='CB(4)';
NET_NAME
'M_H_ECC<5>'
 '@BASEBOARD_FAB2_LIB.BASEBOARD_FAB2(SCH_1):M_H_ECC'<5>:
 C_SIGNAL='@baseboard_fab2_lib.baseboard_fab2(sch_1):m_h_ecc(5)';
NODE_NAME     U2D1 M69
 '@BASEBOARD_FAB2_LIB.BASEBOARD_FAB2(SCH_1):PAGE58_I172@CHPSET_LIB.SKX_EXT_B(CHIPS)':
 'DDR1_ECC'<5>: CDS_PINID='DDR1_ECC(5)';
NODE_NAME     J1G2 47
 '@BASEBOARD_FAB2_LIB.BASEBOARD_FAB2(SCH_1):PAGE79_I111@MSTR_SCONN.SCONN288_H44441004(CHIPS)':
 'CB'<4>: CDS_PINID='CB(4)';
NODE_NAME     J9U1 192
 '@BASEBOARD_FAB2_LIB.BASEBOARD_FAB2(SCH_1):PAGE80_I24@MSTR_SCONN.SCONN288_H44441003(CHIPS)':
 'CB'<5>: CDS_PINID='CB(5)';
NET_NAME
'M_H_ECC<6>'
 '@BASEBOARD_FAB2_LIB.BASEBOARD_FAB2(SCH_1):M_H_ECC'<6>:
 C_SIGNAL='@baseboard_fab2_lib.baseboard_fab2(sch_1):m_h_ecc(6)';
NODE_NAME     U2D1 H67
 '@BASEBOARD_FAB2_LIB.BASEBOARD_FAB2(SCH_1):PAGE58_I172@CHPSET_LIB.SKX_EXT_B(CHIPS)':
 'DDR1_ECC'<6>: CDS_PINID='DDR1_ECC(6)';
NODE_NAME     J1G2 199
 '@BASEBOARD_FAB2_LIB.BASEBOARD_FAB2(SCH_1):PAGE79_I111@MSTR_SCONN.SCONN288_H44441004(CHIPS)':
 'CB'<7>: CDS_PINID='CB(7)';
NODE_NAME     J9U1 54
 '@BASEBOARD_FAB2_LIB.BASEBOARD_FAB2(SCH_1):PAGE80_I24@MSTR_SCONN.SCONN288_H44441003(CHIPS)':
 'CB'<6>: CDS_PINID='CB(6)';
NET_NAME
'M_H_ECC<7>'
 '@BASEBOARD_FAB2_LIB.BASEBOARD_FAB2(SCH_1):M_H_ECC'<7>:
 C_SIGNAL='@baseboard_fab2_lib.baseboard_fab2(sch_1):m_h_ecc(7)';
NODE_NAME     U2D1 M67
 '@BASEBOARD_FAB2_LIB.BASEBOARD_FAB2(SCH_1):PAGE58_I172@CHPSET_LIB.SKX_EXT_B(CHIPS)':
 'DDR1_ECC'<7>: CDS_PINID='DDR1_ECC(7)';
NODE_NAME     J1G2 54
 '@BASEBOARD_FAB2_LIB.BASEBOARD_FAB2(SCH_1):PAGE79_I111@MSTR_SCONN.SCONN288_H44441004(CHIPS)':
 'CB'<6>: CDS_PINID='CB(6)';
NODE_NAME     J9U1 199
 '@BASEBOARD_FAB2_LIB.BASEBOARD_FAB2(SCH_1):PAGE80_I24@MSTR_SCONN.SCONN288_H44441003(CHIPS)':
 'CB'<7>: CDS_PINID='CB(7)';
NET_NAME
'M_H_MA<0>'
 '@BASEBOARD_FAB2_LIB.BASEBOARD_FAB2(SCH_1):M_H_MA'<0>:
 C_SIGNAL='@baseboard_fab2_lib.baseboard_fab2(sch_1):m_h_ma(0)';
NODE_NAME     U2D1 J52
 '@BASEBOARD_FAB2_LIB.BASEBOARD_FAB2(SCH_1):PAGE58_I172@CHPSET_LIB.SKX_EXT_B(CHIPS)':
 'DDR1_MA'<0>: CDS_PINID='DDR1_MA(0)';
NODE_NAME     J1G2 79
 '@BASEBOARD_FAB2_LIB.BASEBOARD_FAB2(SCH_1):PAGE79_I111@MSTR_SCONN.SCONN288_H44441004(CHIPS)':
 'A0': CDS_PINID='A0';
NODE_NAME     J9U1 79
 '@BASEBOARD_FAB2_LIB.BASEBOARD_FAB2(SCH_1):PAGE80_I24@MSTR_SCONN.SCONN288_H44441003(CHIPS)':
 'A0': CDS_PINID='A0';
NET_NAME
'M_H_MA<10>'
 '@BASEBOARD_FAB2_LIB.BASEBOARD_FAB2(SCH_1):M_H_MA'<10>:
 C_SIGNAL='@baseboard_fab2_lib.baseboard_fab2(sch_1):m_h_ma(10)';
NODE_NAME     U2D1 M55
 '@BASEBOARD_FAB2_LIB.BASEBOARD_FAB2(SCH_1):PAGE58_I172@CHPSET_LIB.SKX_EXT_B(CHIPS)':
 'DDR1_MA'<10>: CDS_PINID='DDR1_MA(10)';
NODE_NAME     J1G2 225
 '@BASEBOARD_FAB2_LIB.BASEBOARD_FAB2(SCH_1):PAGE79_I111@MSTR_SCONN.SCONN288_H44441004(CHIPS)':
 'A10': CDS_PINID='A10';
NODE_NAME     J9U1 225
 '@BASEBOARD_FAB2_LIB.BASEBOARD_FAB2(SCH_1):PAGE80_I24@MSTR_SCONN.SCONN288_H44441003(CHIPS)':
 'A10': CDS_PINID='A10';
NET_NAME
'M_H_MA<11>'
 '@BASEBOARD_FAB2_LIB.BASEBOARD_FAB2(SCH_1):M_H_MA'<11>:
 C_SIGNAL='@baseboard_fab2_lib.baseboard_fab2(sch_1):m_h_ma(11)';
NODE_NAME     U2D1 R60
 '@BASEBOARD_FAB2_LIB.BASEBOARD_FAB2(SCH_1):PAGE58_I172@CHPSET_LIB.SKX_EXT_B(CHIPS)':
 'DDR1_MA'<11>: CDS_PINID='DDR1_MA(11)';
NODE_NAME     J1G2 210
 '@BASEBOARD_FAB2_LIB.BASEBOARD_FAB2(SCH_1):PAGE79_I111@MSTR_SCONN.SCONN288_H44441004(CHIPS)':
 'A11': CDS_PINID='A11';
NODE_NAME     J9U1 210
 '@BASEBOARD_FAB2_LIB.BASEBOARD_FAB2(SCH_1):PAGE80_I24@MSTR_SCONN.SCONN288_H44441003(CHIPS)':
 'A11': CDS_PINID='A11';
NET_NAME
'M_H_MA<12>'
 '@BASEBOARD_FAB2_LIB.BASEBOARD_FAB2(SCH_1):M_H_MA'<12>:
 C_SIGNAL='@baseboard_fab2_lib.baseboard_fab2(sch_1):m_h_ma(12)';
NODE_NAME     U2D1 T61
 '@BASEBOARD_FAB2_LIB.BASEBOARD_FAB2(SCH_1):PAGE58_I172@CHPSET_LIB.SKX_EXT_B(CHIPS)':
 'DDR1_MA'<12>: CDS_PINID='DDR1_MA(12)';
NODE_NAME     J1G2 65
 '@BASEBOARD_FAB2_LIB.BASEBOARD_FAB2(SCH_1):PAGE79_I111@MSTR_SCONN.SCONN288_H44441004(CHIPS)':
 'A12': CDS_PINID='A12';
NODE_NAME     J9U1 65
 '@BASEBOARD_FAB2_LIB.BASEBOARD_FAB2(SCH_1):PAGE80_I24@MSTR_SCONN.SCONN288_H44441003(CHIPS)':
 'A12': CDS_PINID='A12';
NET_NAME
'M_H_MA<13>'
 '@BASEBOARD_FAB2_LIB.BASEBOARD_FAB2(SCH_1):M_H_MA'<13>:
 C_SIGNAL='@baseboard_fab2_lib.baseboard_fab2(sch_1):m_h_ma(13)';
NODE_NAME     U2D1 M51
 '@BASEBOARD_FAB2_LIB.BASEBOARD_FAB2(SCH_1):PAGE58_I172@CHPSET_LIB.SKX_EXT_B(CHIPS)':
 'DDR1_MA'<13>: CDS_PINID='DDR1_MA(13)';
NODE_NAME     J1G2 232
 '@BASEBOARD_FAB2_LIB.BASEBOARD_FAB2(SCH_1):PAGE79_I111@MSTR_SCONN.SCONN288_H44441004(CHIPS)':
 'A13': CDS_PINID='A13';
NODE_NAME     J9U1 232
 '@BASEBOARD_FAB2_LIB.BASEBOARD_FAB2(SCH_1):PAGE80_I24@MSTR_SCONN.SCONN288_H44441003(CHIPS)':
 'A13': CDS_PINID='A13';
NET_NAME
'M_H_MA<14>'
 '@BASEBOARD_FAB2_LIB.BASEBOARD_FAB2(SCH_1):M_H_MA'<14>:
 C_SIGNAL='@baseboard_fab2_lib.baseboard_fab2(sch_1):m_h_ma(14)';
NODE_NAME     U2D1 T51
 '@BASEBOARD_FAB2_LIB.BASEBOARD_FAB2(SCH_1):PAGE58_I172@CHPSET_LIB.SKX_EXT_B(CHIPS)':
 'DDR1_MA'<14>: CDS_PINID='DDR1_MA(14)';
NODE_NAME     J1G2 228
 '@BASEBOARD_FAB2_LIB.BASEBOARD_FAB2(SCH_1):PAGE79_I111@MSTR_SCONN.SCONN288_H44441004(CHIPS)':
 'A14_WE_N': CDS_PINID='A14_WE_N';
NODE_NAME     J9U1 228
 '@BASEBOARD_FAB2_LIB.BASEBOARD_FAB2(SCH_1):PAGE80_I24@MSTR_SCONN.SCONN288_H44441003(CHIPS)':
 'A14_WE_N': CDS_PINID='A14_WE_N';
NET_NAME
'M_H_MA<15>'
 '@BASEBOARD_FAB2_LIB.BASEBOARD_FAB2(SCH_1):M_H_MA'<15>:
 C_SIGNAL='@baseboard_fab2_lib.baseboard_fab2(sch_1):m_h_ma(15)';
NODE_NAME     U2D1 N52
 '@BASEBOARD_FAB2_LIB.BASEBOARD_FAB2(SCH_1):PAGE58_I172@CHPSET_LIB.SKX_EXT_B(CHIPS)':
 'DDR1_MA'<15>: CDS_PINID='DDR1_MA(15)';
NODE_NAME     J1G2 86
 '@BASEBOARD_FAB2_LIB.BASEBOARD_FAB2(SCH_1):PAGE79_I111@MSTR_SCONN.SCONN288_H44441004(CHIPS)':
 'A15_CAS_N': CDS_PINID='A15_CAS_N';
NODE_NAME     J9U1 86
 '@BASEBOARD_FAB2_LIB.BASEBOARD_FAB2(SCH_1):PAGE80_I24@MSTR_SCONN.SCONN288_H44441003(CHIPS)':
 'A15_CAS_N': CDS_PINID='A15_CAS_N';
NET_NAME
'M_H_MA<16>'
 '@BASEBOARD_FAB2_LIB.BASEBOARD_FAB2(SCH_1):M_H_MA'<16>:
 C_SIGNAL='@baseboard_fab2_lib.baseboard_fab2(sch_1):m_h_ma(16)';
NODE_NAME     U2D1 R52
 '@BASEBOARD_FAB2_LIB.BASEBOARD_FAB2(SCH_1):PAGE58_I172@CHPSET_LIB.SKX_EXT_B(CHIPS)':
 'DDR1_MA'<16>: CDS_PINID='DDR1_MA(16)';
NODE_NAME     J1G2 82
 '@BASEBOARD_FAB2_LIB.BASEBOARD_FAB2(SCH_1):PAGE79_I111@MSTR_SCONN.SCONN288_H44441004(CHIPS)':
 'A16_RAS_N': CDS_PINID='A16_RAS_N';
NODE_NAME     J9U1 82
 '@BASEBOARD_FAB2_LIB.BASEBOARD_FAB2(SCH_1):PAGE80_I24@MSTR_SCONN.SCONN288_H44441003(CHIPS)':
 'A16_RAS_N': CDS_PINID='A16_RAS_N';
NET_NAME
'M_H_MA<17>'
 '@BASEBOARD_FAB2_LIB.BASEBOARD_FAB2(SCH_1):M_H_MA'<17>:
 C_SIGNAL='@baseboard_fab2_lib.baseboard_fab2(sch_1):m_h_ma(17)';
NODE_NAME     U2D1 N48
 '@BASEBOARD_FAB2_LIB.BASEBOARD_FAB2(SCH_1):PAGE58_I172@CHPSET_LIB.SKX_EXT_B(CHIPS)':
 'DDR1_MA'<17>: CDS_PINID='DDR1_MA(17)';
NODE_NAME     J1G2 234
 '@BASEBOARD_FAB2_LIB.BASEBOARD_FAB2(SCH_1):PAGE79_I111@MSTR_SCONN.SCONN288_H44441004(CHIPS)':
 'A17': CDS_PINID='A17';
NODE_NAME     J9U1 234
 '@BASEBOARD_FAB2_LIB.BASEBOARD_FAB2(SCH_1):PAGE80_I24@MSTR_SCONN.SCONN288_H44441003(CHIPS)':
 'A17': CDS_PINID='A17';
NET_NAME
'M_H_MA<1>'
 '@BASEBOARD_FAB2_LIB.BASEBOARD_FAB2(SCH_1):M_H_MA'<1>:
 C_SIGNAL='@baseboard_fab2_lib.baseboard_fab2(sch_1):m_h_ma(1)';
NODE_NAME     U2D1 J58
 '@BASEBOARD_FAB2_LIB.BASEBOARD_FAB2(SCH_1):PAGE58_I172@CHPSET_LIB.SKX_EXT_B(CHIPS)':
 'DDR1_MA'<1>: CDS_PINID='DDR1_MA(1)';
NODE_NAME     J1G2 72
 '@BASEBOARD_FAB2_LIB.BASEBOARD_FAB2(SCH_1):PAGE79_I111@MSTR_SCONN.SCONN288_H44441004(CHIPS)':
 'A1': CDS_PINID='A1';
NODE_NAME     J9U1 72
 '@BASEBOARD_FAB2_LIB.BASEBOARD_FAB2(SCH_1):PAGE80_I24@MSTR_SCONN.SCONN288_H44441003(CHIPS)':
 'A1': CDS_PINID='A1';
NET_NAME
'M_H_MA<2>'
 '@BASEBOARD_FAB2_LIB.BASEBOARD_FAB2(SCH_1):M_H_MA'<2>:
 C_SIGNAL='@baseboard_fab2_lib.baseboard_fab2(sch_1):m_h_ma(2)';
NODE_NAME     U2D1 K57
 '@BASEBOARD_FAB2_LIB.BASEBOARD_FAB2(SCH_1):PAGE58_I172@CHPSET_LIB.SKX_EXT_B(CHIPS)':
 'DDR1_MA'<2>: CDS_PINID='DDR1_MA(2)';
NODE_NAME     J1G2 216
 '@BASEBOARD_FAB2_LIB.BASEBOARD_FAB2(SCH_1):PAGE79_I111@MSTR_SCONN.SCONN288_H44441004(CHIPS)':
 'A2': CDS_PINID='A2';
NODE_NAME     J9U1 216
 '@BASEBOARD_FAB2_LIB.BASEBOARD_FAB2(SCH_1):PAGE80_I24@MSTR_SCONN.SCONN288_H44441003(CHIPS)':
 'A2': CDS_PINID='A2';
NET_NAME
'M_H_MA<3>'
 '@BASEBOARD_FAB2_LIB.BASEBOARD_FAB2(SCH_1):M_H_MA'<3>:
 C_SIGNAL='@baseboard_fab2_lib.baseboard_fab2(sch_1):m_h_ma(3)';
NODE_NAME     U2D1 N58
 '@BASEBOARD_FAB2_LIB.BASEBOARD_FAB2(SCH_1):PAGE58_I172@CHPSET_LIB.SKX_EXT_B(CHIPS)':
 'DDR1_MA'<3>: CDS_PINID='DDR1_MA(3)';
NODE_NAME     J1G2 71
 '@BASEBOARD_FAB2_LIB.BASEBOARD_FAB2(SCH_1):PAGE79_I111@MSTR_SCONN.SCONN288_H44441004(CHIPS)':
 'A3': CDS_PINID='A3';
NODE_NAME     J9U1 71
 '@BASEBOARD_FAB2_LIB.BASEBOARD_FAB2(SCH_1):PAGE80_I24@MSTR_SCONN.SCONN288_H44441003(CHIPS)':
 'A3': CDS_PINID='A3';
NET_NAME
'M_H_MA<4>'
 '@BASEBOARD_FAB2_LIB.BASEBOARD_FAB2(SCH_1):M_H_MA'<4>:
 C_SIGNAL='@baseboard_fab2_lib.baseboard_fab2(sch_1):m_h_ma(4)';
NODE_NAME     U2D1 M59
 '@BASEBOARD_FAB2_LIB.BASEBOARD_FAB2(SCH_1):PAGE58_I172@CHPSET_LIB.SKX_EXT_B(CHIPS)':
 'DDR1_MA'<4>: CDS_PINID='DDR1_MA(4)';
NODE_NAME     J1G2 214
 '@BASEBOARD_FAB2_LIB.BASEBOARD_FAB2(SCH_1):PAGE79_I111@MSTR_SCONN.SCONN288_H44441004(CHIPS)':
 'A4': CDS_PINID='A4';
NODE_NAME     J9U1 214
 '@BASEBOARD_FAB2_LIB.BASEBOARD_FAB2(SCH_1):PAGE80_I24@MSTR_SCONN.SCONN288_H44441003(CHIPS)':
 'A4': CDS_PINID='A4';
NET_NAME
'M_H_MA<5>'
 '@BASEBOARD_FAB2_LIB.BASEBOARD_FAB2(SCH_1):M_H_MA'<5>:
 C_SIGNAL='@baseboard_fab2_lib.baseboard_fab2(sch_1):m_h_ma(5)';
NODE_NAME     U2D1 R58
 '@BASEBOARD_FAB2_LIB.BASEBOARD_FAB2(SCH_1):PAGE58_I172@CHPSET_LIB.SKX_EXT_B(CHIPS)':
 'DDR1_MA'<5>: CDS_PINID='DDR1_MA(5)';
NODE_NAME     J1G2 213
 '@BASEBOARD_FAB2_LIB.BASEBOARD_FAB2(SCH_1):PAGE79_I111@MSTR_SCONN.SCONN288_H44441004(CHIPS)':
 'A5': CDS_PINID='A5';
NODE_NAME     J9U1 213
 '@BASEBOARD_FAB2_LIB.BASEBOARD_FAB2(SCH_1):PAGE80_I24@MSTR_SCONN.SCONN288_H44441003(CHIPS)':
 'A5': CDS_PINID='A5';
NET_NAME
'M_H_MA<6>'
 '@BASEBOARD_FAB2_LIB.BASEBOARD_FAB2(SCH_1):M_H_MA'<6>:
 C_SIGNAL='@baseboard_fab2_lib.baseboard_fab2(sch_1):m_h_ma(6)';
NODE_NAME     U2D1 T59
 '@BASEBOARD_FAB2_LIB.BASEBOARD_FAB2(SCH_1):PAGE58_I172@CHPSET_LIB.SKX_EXT_B(CHIPS)':
 'DDR1_MA'<6>: CDS_PINID='DDR1_MA(6)';
NODE_NAME     J1G2 69
 '@BASEBOARD_FAB2_LIB.BASEBOARD_FAB2(SCH_1):PAGE79_I111@MSTR_SCONN.SCONN288_H44441004(CHIPS)':
 'A6': CDS_PINID='A6';
NODE_NAME     J9U1 69
 '@BASEBOARD_FAB2_LIB.BASEBOARD_FAB2(SCH_1):PAGE80_I24@MSTR_SCONN.SCONN288_H44441003(CHIPS)':
 'A6': CDS_PINID='A6';
NET_NAME
'M_H_MA<7>'
 '@BASEBOARD_FAB2_LIB.BASEBOARD_FAB2(SCH_1):M_H_MA'<7>:
 C_SIGNAL='@baseboard_fab2_lib.baseboard_fab2(sch_1):m_h_ma(7)';
NODE_NAME     U2D1 V61
 '@BASEBOARD_FAB2_LIB.BASEBOARD_FAB2(SCH_1):PAGE58_I172@CHPSET_LIB.SKX_EXT_B(CHIPS)':
 'DDR1_MA'<7>: CDS_PINID='DDR1_MA(7)';
NODE_NAME     J1G2 211
 '@BASEBOARD_FAB2_LIB.BASEBOARD_FAB2(SCH_1):PAGE79_I111@MSTR_SCONN.SCONN288_H44441004(CHIPS)':
 'A7': CDS_PINID='A7';
NODE_NAME     J9U1 211
 '@BASEBOARD_FAB2_LIB.BASEBOARD_FAB2(SCH_1):PAGE80_I24@MSTR_SCONN.SCONN288_H44441003(CHIPS)':
 'A7': CDS_PINID='A7';
NET_NAME
'M_H_MA<8>'
 '@BASEBOARD_FAB2_LIB.BASEBOARD_FAB2(SCH_1):M_H_MA'<8>:
 C_SIGNAL='@baseboard_fab2_lib.baseboard_fab2(sch_1):m_h_ma(8)';
NODE_NAME     U2D1 W60
 '@BASEBOARD_FAB2_LIB.BASEBOARD_FAB2(SCH_1):PAGE58_I172@CHPSET_LIB.SKX_EXT_B(CHIPS)':
 'DDR1_MA'<8>: CDS_PINID='DDR1_MA(8)';
NODE_NAME     J1G2 68
 '@BASEBOARD_FAB2_LIB.BASEBOARD_FAB2(SCH_1):PAGE79_I111@MSTR_SCONN.SCONN288_H44441004(CHIPS)':
 'A8': CDS_PINID='A8';
NODE_NAME     J9U1 68
 '@BASEBOARD_FAB2_LIB.BASEBOARD_FAB2(SCH_1):PAGE80_I24@MSTR_SCONN.SCONN288_H44441003(CHIPS)':
 'A8': CDS_PINID='A8';
NET_NAME
'M_H_MA<9>'
 '@BASEBOARD_FAB2_LIB.BASEBOARD_FAB2(SCH_1):M_H_MA'<9>:
 C_SIGNAL='@baseboard_fab2_lib.baseboard_fab2(sch_1):m_h_ma(9)';
NODE_NAME     U2D1 K59
 '@BASEBOARD_FAB2_LIB.BASEBOARD_FAB2(SCH_1):PAGE58_I172@CHPSET_LIB.SKX_EXT_B(CHIPS)':
 'DDR1_MA'<9>: CDS_PINID='DDR1_MA(9)';
NODE_NAME     J1G2 66
 '@BASEBOARD_FAB2_LIB.BASEBOARD_FAB2(SCH_1):PAGE79_I111@MSTR_SCONN.SCONN288_H44441004(CHIPS)':
 'A9': CDS_PINID='A9';
NODE_NAME     J9U1 66
 '@BASEBOARD_FAB2_LIB.BASEBOARD_FAB2(SCH_1):PAGE80_I24@MSTR_SCONN.SCONN288_H44441003(CHIPS)':
 'A9': CDS_PINID='A9';
NET_NAME
'M_H_ODT<0>'
 '@BASEBOARD_FAB2_LIB.BASEBOARD_FAB2(SCH_1):M_H_ODT'<0>:
 C_SIGNAL='@baseboard_fab2_lib.baseboard_fab2(sch_1):m_h_odt(0)';
NODE_NAME     U2D1 N50
 '@BASEBOARD_FAB2_LIB.BASEBOARD_FAB2(SCH_1):PAGE58_I172@CHPSET_LIB.SKX_EXT_B(CHIPS)':
 'DDR1_ODT'<0>: CDS_PINID='DDR1_ODT(0)';
NODE_NAME     J1G2 87
 '@BASEBOARD_FAB2_LIB.BASEBOARD_FAB2(SCH_1):PAGE79_I111@MSTR_SCONN.SCONN288_H44441004(CHIPS)':
 'ODT'<0>: CDS_PINID='ODT(0)';
NET_NAME
'M_H_ODT<1>'
 '@BASEBOARD_FAB2_LIB.BASEBOARD_FAB2(SCH_1):M_H_ODT'<1>:
 C_SIGNAL='@baseboard_fab2_lib.baseboard_fab2(sch_1):m_h_odt(1)';
NODE_NAME     U2D1 R48
 '@BASEBOARD_FAB2_LIB.BASEBOARD_FAB2(SCH_1):PAGE58_I172@CHPSET_LIB.SKX_EXT_B(CHIPS)':
 'DDR1_ODT'<1>: CDS_PINID='DDR1_ODT(1)';
NODE_NAME     J1G2 91
 '@BASEBOARD_FAB2_LIB.BASEBOARD_FAB2(SCH_1):PAGE79_I111@MSTR_SCONN.SCONN288_H44441004(CHIPS)':
 'ODT'<1>: CDS_PINID='ODT(1)';
NET_NAME
'M_H_ODT<2>'
 '@BASEBOARD_FAB2_LIB.BASEBOARD_FAB2(SCH_1):M_H_ODT'<2>:
 C_SIGNAL='@baseboard_fab2_lib.baseboard_fab2(sch_1):m_h_odt(2)';
NODE_NAME     U2D1 M49
 '@BASEBOARD_FAB2_LIB.BASEBOARD_FAB2(SCH_1):PAGE58_I172@CHPSET_LIB.SKX_EXT_B(CHIPS)':
 'DDR1_ODT'<2>: CDS_PINID='DDR1_ODT(2)';
NODE_NAME     J9U1 87
 '@BASEBOARD_FAB2_LIB.BASEBOARD_FAB2(SCH_1):PAGE80_I24@MSTR_SCONN.SCONN288_H44441003(CHIPS)':
 'ODT'<0>: CDS_PINID='ODT(0)';
NET_NAME
'M_H_ODT<3>'
 '@BASEBOARD_FAB2_LIB.BASEBOARD_FAB2(SCH_1):M_H_ODT'<3>:
 C_SIGNAL='@baseboard_fab2_lib.baseboard_fab2(sch_1):m_h_odt(3)';
NODE_NAME     U2D1 T47
 '@BASEBOARD_FAB2_LIB.BASEBOARD_FAB2(SCH_1):PAGE58_I172@CHPSET_LIB.SKX_EXT_B(CHIPS)':
 'DDR1_ODT'<3>: CDS_PINID='DDR1_ODT(3)';
NODE_NAME     J9U1 91
 '@BASEBOARD_FAB2_LIB.BASEBOARD_FAB2(SCH_1):PAGE80_I24@MSTR_SCONN.SCONN288_H44441003(CHIPS)':
 'ODT'<1>: CDS_PINID='ODT(1)';
NET_NAME
'M_H_PAR'
 '@BASEBOARD_FAB2_LIB.BASEBOARD_FAB2(SCH_1):M_H_PAR':
 C_SIGNAL='@baseboard_fab2_lib.baseboard_fab2(sch_1):m_h_par';
NODE_NAME     U2D1 K53
 '@BASEBOARD_FAB2_LIB.BASEBOARD_FAB2(SCH_1):PAGE58_I172@CHPSET_LIB.SKX_EXT_B(CHIPS)':
 'DDR1_PAR': CDS_PINID='DDR1_PAR';
NODE_NAME     J1G2 222
 '@BASEBOARD_FAB2_LIB.BASEBOARD_FAB2(SCH_1):PAGE79_I111@MSTR_SCONN.SCONN288_H44441004(CHIPS)':
 'PAR': CDS_PINID='PAR';
NODE_NAME     J9U1 222
 '@BASEBOARD_FAB2_LIB.BASEBOARD_FAB2(SCH_1):PAGE80_I24@MSTR_SCONN.SCONN288_H44441003(CHIPS)':
 'PAR': CDS_PINID='PAR';
NET_NAME
'M_H_VREF'
 '@BASEBOARD_FAB2_LIB.BASEBOARD_FAB2(SCH_1):M_H_VREF':
 C_SIGNAL='@baseboard_fab2_lib.baseboard_fab2(sch_1):m_h_vref';
NODE_NAME     J1G2 146
 '@BASEBOARD_FAB2_LIB.BASEBOARD_FAB2(SCH_1):PAGE79_I111@MSTR_SCONN.SCONN288_H44441004(CHIPS)':
 'VREFCA': CDS_PINID='VREFCA';
NODE_NAME     C9U7 1
 '@BASEBOARD_FAB2_LIB.BASEBOARD_FAB2(SCH_1):PAGE79_I178@DEV_DISCRETE.CAP_A(CHIPS)':
 'A': CDS_PINID='A';
NODE_NAME     C1G10 1
 '@BASEBOARD_FAB2_LIB.BASEBOARD_FAB2(SCH_1):PAGE80_I3@DEV_DISCRETE.CAP_A(CHIPS)':
 'A': CDS_PINID='A';
NODE_NAME     J9U1 146
 '@BASEBOARD_FAB2_LIB.BASEBOARD_FAB2(SCH_1):PAGE80_I24@MSTR_SCONN.SCONN288_H44441003(CHIPS)':
 'VREFCA': CDS_PINID='VREFCA';
NODE_NAME     R1G2 2
 '@BASEBOARD_FAB2_LIB.BASEBOARD_FAB2(SCH_1):PAGE100_I19@MSTR_DISCRETE.RES(CHIPS)':
 'B': CDS_PINID='B';
NODE_NAME     R1G3 1
 '@BASEBOARD_FAB2_LIB.BASEBOARD_FAB2(SCH_1):PAGE100_I20@MSTR_DISCRETE.RES(CHIPS)':
 'A': CDS_PINID='A';
NODE_NAME     R1G1 2
 '@BASEBOARD_FAB2_LIB.BASEBOARD_FAB2(SCH_1):PAGE100_I25@MSTR_DISCRETE.RES(CHIPS)':
 'B': CDS_PINID='B';
NET_NAME
'M_J_ACT_N'
 '@BASEBOARD_FAB2_LIB.BASEBOARD_FAB2(SCH_1):M_J_ACT_N':
 C_SIGNAL='@baseboard_fab2_lib.baseboard_fab2(sch_1):m_j_act_n';
NODE_NAME     U2D1 AB61
 '@BASEBOARD_FAB2_LIB.BASEBOARD_FAB2(SCH_1):PAGE59_I172@CHPSET_LIB.SKX_EXT_B(CHIPS)':
 'DDR2_ACT_N': CDS_PINID='DDR2_ACT_N';
NODE_NAME     J1G3 62
 '@BASEBOARD_FAB2_LIB.BASEBOARD_FAB2(SCH_1):PAGE81_I186@MSTR_SCONN.SCONN288_H44441004(CHIPS)':
 'ACT_N': CDS_PINID='ACT_N';
NODE_NAME     J9U2 62
 '@BASEBOARD_FAB2_LIB.BASEBOARD_FAB2(SCH_1):PAGE82_I187@MSTR_SCONN.SCONN288_H44441003(CHIPS)':
 'ACT_N': CDS_PINID='ACT_N';
NET_NAME
'M_J_ALERT_N'
 '@BASEBOARD_FAB2_LIB.BASEBOARD_FAB2(SCH_1):M_J_ALERT_N':
 C_SIGNAL='@baseboard_fab2_lib.baseboard_fab2(sch_1):m_j_alert_n';
NODE_NAME     U2D1 AD61
 '@BASEBOARD_FAB2_LIB.BASEBOARD_FAB2(SCH_1):PAGE59_I172@CHPSET_LIB.SKX_EXT_B(CHIPS)':
 'DDR2_ALERT_N': CDS_PINID='DDR2_ALERT_N';
NODE_NAME     J1G3 208
 '@BASEBOARD_FAB2_LIB.BASEBOARD_FAB2(SCH_1):PAGE81_I186@MSTR_SCONN.SCONN288_H44441004(CHIPS)':
 'ALERT_N': CDS_PINID='ALERT_N';
NODE_NAME     J9U2 208
 '@BASEBOARD_FAB2_LIB.BASEBOARD_FAB2(SCH_1):PAGE82_I187@MSTR_SCONN.SCONN288_H44441003(CHIPS)':
 'ALERT_N': CDS_PINID='ALERT_N';
NET_NAME
'M_J_BA<0>'
 '@BASEBOARD_FAB2_LIB.BASEBOARD_FAB2(SCH_1):M_J_BA'<0>:
 C_SIGNAL='@baseboard_fab2_lib.baseboard_fab2(sch_1):m_j_ba(0)';
NODE_NAME     U2D1 W52
 '@BASEBOARD_FAB2_LIB.BASEBOARD_FAB2(SCH_1):PAGE59_I172@CHPSET_LIB.SKX_EXT_B(CHIPS)':
 'DDR2_BA'<0>: CDS_PINID='DDR2_BA(0)';
NODE_NAME     J1G3 81
 '@BASEBOARD_FAB2_LIB.BASEBOARD_FAB2(SCH_1):PAGE81_I186@MSTR_SCONN.SCONN288_H44441004(CHIPS)':
 'BA'<0>: CDS_PINID='BA(0)';
NODE_NAME     J9U2 81
 '@BASEBOARD_FAB2_LIB.BASEBOARD_FAB2(SCH_1):PAGE82_I187@MSTR_SCONN.SCONN288_H44441003(CHIPS)':
 'BA'<0>: CDS_PINID='BA(0)';
NET_NAME
'M_J_BA<1>'
 '@BASEBOARD_FAB2_LIB.BASEBOARD_FAB2(SCH_1):M_J_BA'<1>:
 C_SIGNAL='@baseboard_fab2_lib.baseboard_fab2(sch_1):m_j_ba(1)';
NODE_NAME     U2D1 AE56
 '@BASEBOARD_FAB2_LIB.BASEBOARD_FAB2(SCH_1):PAGE59_I172@CHPSET_LIB.SKX_EXT_B(CHIPS)':
 'DDR2_BA'<1>: CDS_PINID='DDR2_BA(1)';
NODE_NAME     J1G3 224
 '@BASEBOARD_FAB2_LIB.BASEBOARD_FAB2(SCH_1):PAGE81_I186@MSTR_SCONN.SCONN288_H44441004(CHIPS)':
 'BA'<1>: CDS_PINID='BA(1)';
NODE_NAME     J9U2 224
 '@BASEBOARD_FAB2_LIB.BASEBOARD_FAB2(SCH_1):PAGE82_I187@MSTR_SCONN.SCONN288_H44441003(CHIPS)':
 'BA'<1>: CDS_PINID='BA(1)';
NET_NAME
'M_J_BG<0>'
 '@BASEBOARD_FAB2_LIB.BASEBOARD_FAB2(SCH_1):M_J_BG'<0>:
 C_SIGNAL='@baseboard_fab2_lib.baseboard_fab2(sch_1):m_j_bg(0)';
NODE_NAME     U2D1 AA60
 '@BASEBOARD_FAB2_LIB.BASEBOARD_FAB2(SCH_1):PAGE59_I172@CHPSET_LIB.SKX_EXT_B(CHIPS)':
 'DDR2_BG'<0>: CDS_PINID='DDR2_BG(0)';
NODE_NAME     J1G3 63
 '@BASEBOARD_FAB2_LIB.BASEBOARD_FAB2(SCH_1):PAGE81_I186@MSTR_SCONN.SCONN288_H44441004(CHIPS)':
 'BG'<0>: CDS_PINID='BG(0)';
NODE_NAME     J9U2 63
 '@BASEBOARD_FAB2_LIB.BASEBOARD_FAB2(SCH_1):PAGE82_I187@MSTR_SCONN.SCONN288_H44441003(CHIPS)':
 'BG'<0>: CDS_PINID='BG(0)';
NET_NAME
'M_J_BG<1>'
 '@BASEBOARD_FAB2_LIB.BASEBOARD_FAB2(SCH_1):M_J_BG'<1>:
 C_SIGNAL='@baseboard_fab2_lib.baseboard_fab2(sch_1):m_j_bg(1)';
NODE_NAME     U2D1 AE62
 '@BASEBOARD_FAB2_LIB.BASEBOARD_FAB2(SCH_1):PAGE59_I172@CHPSET_LIB.SKX_EXT_B(CHIPS)':
 'DDR2_BG'<1>: CDS_PINID='DDR2_BG(1)';
NODE_NAME     J1G3 207
 '@BASEBOARD_FAB2_LIB.BASEBOARD_FAB2(SCH_1):PAGE81_I186@MSTR_SCONN.SCONN288_H44441004(CHIPS)':
 'BG'<1>: CDS_PINID='BG(1)';
NODE_NAME     J9U2 207
 '@BASEBOARD_FAB2_LIB.BASEBOARD_FAB2(SCH_1):PAGE82_I187@MSTR_SCONN.SCONN288_H44441003(CHIPS)':
 'BG'<1>: CDS_PINID='BG(1)';
NET_NAME
'M_J_C<2>'
 '@BASEBOARD_FAB2_LIB.BASEBOARD_FAB2(SCH_1):M_J_C'<2>:
 C_SIGNAL='@baseboard_fab2_lib.baseboard_fab2(sch_1):m_j_c(2)';
NODE_NAME     U2D1 AB45
 '@BASEBOARD_FAB2_LIB.BASEBOARD_FAB2(SCH_1):PAGE59_I172@CHPSET_LIB.SKX_EXT_B(CHIPS)':
 'DDR2_CID'<2>: CDS_PINID='DDR2_CID(2)';
NODE_NAME     J1G3 235
 '@BASEBOARD_FAB2_LIB.BASEBOARD_FAB2(SCH_1):PAGE81_I186@MSTR_SCONN.SCONN288_H44441004(CHIPS)':
 'C'<2>: CDS_PINID='C(2)';
NODE_NAME     J9U2 235
 '@BASEBOARD_FAB2_LIB.BASEBOARD_FAB2(SCH_1):PAGE82_I187@MSTR_SCONN.SCONN288_H44441003(CHIPS)':
 'C'<2>: CDS_PINID='C(2)';
NET_NAME
'M_J_CKE<0>'
 '@BASEBOARD_FAB2_LIB.BASEBOARD_FAB2(SCH_1):M_J_CKE'<0>:
 C_SIGNAL='@baseboard_fab2_lib.baseboard_fab2(sch_1):m_j_cke(0)';
NODE_NAME     U2D1 AA62
 '@BASEBOARD_FAB2_LIB.BASEBOARD_FAB2(SCH_1):PAGE59_I172@CHPSET_LIB.SKX_EXT_B(CHIPS)':
 'DDR2_CKE'<0>: CDS_PINID='DDR2_CKE(0)';
NODE_NAME     J1G3 60
 '@BASEBOARD_FAB2_LIB.BASEBOARD_FAB2(SCH_1):PAGE81_I186@MSTR_SCONN.SCONN288_H44441004(CHIPS)':
 'CKE'<0>: CDS_PINID='CKE(0)';
NET_NAME
'M_J_CKE<1>'
 '@BASEBOARD_FAB2_LIB.BASEBOARD_FAB2(SCH_1):M_J_CKE'<1>:
 C_SIGNAL='@baseboard_fab2_lib.baseboard_fab2(sch_1):m_j_cke(1)';
NODE_NAME     U2D1 AD63
 '@BASEBOARD_FAB2_LIB.BASEBOARD_FAB2(SCH_1):PAGE59_I172@CHPSET_LIB.SKX_EXT_B(CHIPS)':
 'DDR2_CKE'<1>: CDS_PINID='DDR2_CKE(1)';
NODE_NAME     J1G3 203
 '@BASEBOARD_FAB2_LIB.BASEBOARD_FAB2(SCH_1):PAGE81_I186@MSTR_SCONN.SCONN288_H44441004(CHIPS)':
 'CKE'<1>: CDS_PINID='CKE(1)';
NET_NAME
'M_J_CKE<2>'
 '@BASEBOARD_FAB2_LIB.BASEBOARD_FAB2(SCH_1):M_J_CKE'<2>:
 C_SIGNAL='@baseboard_fab2_lib.baseboard_fab2(sch_1):m_j_cke(2)';
NODE_NAME     U2D1 V63
 '@BASEBOARD_FAB2_LIB.BASEBOARD_FAB2(SCH_1):PAGE59_I172@CHPSET_LIB.SKX_EXT_B(CHIPS)':
 'DDR2_CKE'<2>: CDS_PINID='DDR2_CKE(2)';
NODE_NAME     J9U2 60
 '@BASEBOARD_FAB2_LIB.BASEBOARD_FAB2(SCH_1):PAGE82_I187@MSTR_SCONN.SCONN288_H44441003(CHIPS)':
 'CKE'<0>: CDS_PINID='CKE(0)';
NET_NAME
'M_J_CKE<3>'
 '@BASEBOARD_FAB2_LIB.BASEBOARD_FAB2(SCH_1):M_J_CKE'<3>:
 C_SIGNAL='@baseboard_fab2_lib.baseboard_fab2(sch_1):m_j_cke(3)';
NODE_NAME     U2D1 AB63
 '@BASEBOARD_FAB2_LIB.BASEBOARD_FAB2(SCH_1):PAGE59_I172@CHPSET_LIB.SKX_EXT_B(CHIPS)':
 'DDR2_CKE'<3>: CDS_PINID='DDR2_CKE(3)';
NODE_NAME     J9U2 203
 '@BASEBOARD_FAB2_LIB.BASEBOARD_FAB2(SCH_1):PAGE82_I187@MSTR_SCONN.SCONN288_H44441003(CHIPS)':
 'CKE'<1>: CDS_PINID='CKE(1)';
NET_NAME
'M_J_CLK_DN<0>'
 '@BASEBOARD_FAB2_LIB.BASEBOARD_FAB2(SCH_1):M_J_CLK_DN'<0>:
 C_SIGNAL='@baseboard_fab2_lib.baseboard_fab2(sch_1):m_j_clk_dn(0)';
NODE_NAME     U2D1 AA54
 '@BASEBOARD_FAB2_LIB.BASEBOARD_FAB2(SCH_1):PAGE59_I172@CHPSET_LIB.SKX_EXT_B(CHIPS)':
 'DDR2_CLK_DN'<0>: CDS_PINID='DDR2_CLK_DN(0)';
NODE_NAME     J1G3 75
 '@BASEBOARD_FAB2_LIB.BASEBOARD_FAB2(SCH_1):PAGE81_I186@MSTR_SCONN.SCONN288_H44441004(CHIPS)':
 'CK0N': CDS_PINID='CK0N';
NET_NAME
'M_J_CLK_DN<1>'
 '@BASEBOARD_FAB2_LIB.BASEBOARD_FAB2(SCH_1):M_J_CLK_DN'<1>:
 C_SIGNAL='@baseboard_fab2_lib.baseboard_fab2(sch_1):m_j_clk_dn(1)';
NODE_NAME     U2D1 W54
 '@BASEBOARD_FAB2_LIB.BASEBOARD_FAB2(SCH_1):PAGE59_I172@CHPSET_LIB.SKX_EXT_B(CHIPS)':
 'DDR2_CLK_DN'<1>: CDS_PINID='DDR2_CLK_DN(1)';
NODE_NAME     J1G3 219
 '@BASEBOARD_FAB2_LIB.BASEBOARD_FAB2(SCH_1):PAGE81_I186@MSTR_SCONN.SCONN288_H44441004(CHIPS)':
 'CK1N': CDS_PINID='CK1N';
NET_NAME
'M_J_CLK_DN<2>'
 '@BASEBOARD_FAB2_LIB.BASEBOARD_FAB2(SCH_1):M_J_CLK_DN'<2>:
 C_SIGNAL='@baseboard_fab2_lib.baseboard_fab2(sch_1):m_j_clk_dn(2)';
NODE_NAME     U2D1 AA56
 '@BASEBOARD_FAB2_LIB.BASEBOARD_FAB2(SCH_1):PAGE59_I172@CHPSET_LIB.SKX_EXT_B(CHIPS)':
 'DDR2_CLK_DN'<2>: CDS_PINID='DDR2_CLK_DN(2)';
NODE_NAME     J9U2 75
 '@BASEBOARD_FAB2_LIB.BASEBOARD_FAB2(SCH_1):PAGE82_I187@MSTR_SCONN.SCONN288_H44441003(CHIPS)':
 'CK0N': CDS_PINID='CK0N';
NET_NAME
'M_J_CLK_DN<3>'
 '@BASEBOARD_FAB2_LIB.BASEBOARD_FAB2(SCH_1):M_J_CLK_DN'<3>:
 C_SIGNAL='@baseboard_fab2_lib.baseboard_fab2(sch_1):m_j_clk_dn(3)';
NODE_NAME     U2D1 W56
 '@BASEBOARD_FAB2_LIB.BASEBOARD_FAB2(SCH_1):PAGE59_I172@CHPSET_LIB.SKX_EXT_B(CHIPS)':
 'DDR2_CLK_DN'<3>: CDS_PINID='DDR2_CLK_DN(3)';
NODE_NAME     J9U2 219
 '@BASEBOARD_FAB2_LIB.BASEBOARD_FAB2(SCH_1):PAGE82_I187@MSTR_SCONN.SCONN288_H44441003(CHIPS)':
 'CK1N': CDS_PINID='CK1N';
NET_NAME
'M_J_CLK_DP<0>'
 '@BASEBOARD_FAB2_LIB.BASEBOARD_FAB2(SCH_1):M_J_CLK_DP'<0>:
 C_SIGNAL='@baseboard_fab2_lib.baseboard_fab2(sch_1):m_j_clk_dp(0)';
NODE_NAME     U2D1 AB55
 '@BASEBOARD_FAB2_LIB.BASEBOARD_FAB2(SCH_1):PAGE59_I172@CHPSET_LIB.SKX_EXT_B(CHIPS)':
 'DDR2_CLK_DP'<0>: CDS_PINID='DDR2_CLK_DP(0)';
NODE_NAME     J1G3 74
 '@BASEBOARD_FAB2_LIB.BASEBOARD_FAB2(SCH_1):PAGE81_I186@MSTR_SCONN.SCONN288_H44441004(CHIPS)':
 'CK0P': CDS_PINID='CK0P';
NET_NAME
'M_J_CLK_DP<1>'
 '@BASEBOARD_FAB2_LIB.BASEBOARD_FAB2(SCH_1):M_J_CLK_DP'<1>:
 C_SIGNAL='@baseboard_fab2_lib.baseboard_fab2(sch_1):m_j_clk_dp(1)';
NODE_NAME     U2D1 V55
 '@BASEBOARD_FAB2_LIB.BASEBOARD_FAB2(SCH_1):PAGE59_I172@CHPSET_LIB.SKX_EXT_B(CHIPS)':
 'DDR2_CLK_DP'<1>: CDS_PINID='DDR2_CLK_DP(1)';
NODE_NAME     J1G3 218
 '@BASEBOARD_FAB2_LIB.BASEBOARD_FAB2(SCH_1):PAGE81_I186@MSTR_SCONN.SCONN288_H44441004(CHIPS)':
 'CK1P': CDS_PINID='CK1P';
NET_NAME
'M_J_CLK_DP<2>'
 '@BASEBOARD_FAB2_LIB.BASEBOARD_FAB2(SCH_1):M_J_CLK_DP'<2>:
 C_SIGNAL='@baseboard_fab2_lib.baseboard_fab2(sch_1):m_j_clk_dp(2)';
NODE_NAME     U2D1 AB57
 '@BASEBOARD_FAB2_LIB.BASEBOARD_FAB2(SCH_1):PAGE59_I172@CHPSET_LIB.SKX_EXT_B(CHIPS)':
 'DDR2_CLK_DP'<2>: CDS_PINID='DDR2_CLK_DP(2)';
NODE_NAME     J9U2 74
 '@BASEBOARD_FAB2_LIB.BASEBOARD_FAB2(SCH_1):PAGE82_I187@MSTR_SCONN.SCONN288_H44441003(CHIPS)':
 'CK0P': CDS_PINID='CK0P';
NET_NAME
'M_J_CLK_DP<3>'
 '@BASEBOARD_FAB2_LIB.BASEBOARD_FAB2(SCH_1):M_J_CLK_DP'<3>:
 C_SIGNAL='@baseboard_fab2_lib.baseboard_fab2(sch_1):m_j_clk_dp(3)';
NODE_NAME     U2D1 V57
 '@BASEBOARD_FAB2_LIB.BASEBOARD_FAB2(SCH_1):PAGE59_I172@CHPSET_LIB.SKX_EXT_B(CHIPS)':
 'DDR2_CLK_DP'<3>: CDS_PINID='DDR2_CLK_DP(3)';
NODE_NAME     J9U2 218
 '@BASEBOARD_FAB2_LIB.BASEBOARD_FAB2(SCH_1):PAGE82_I187@MSTR_SCONN.SCONN288_H44441003(CHIPS)':
 'CK1P': CDS_PINID='CK1P';
NET_NAME
'M_J_CPU_VREF'
 '@BASEBOARD_FAB2_LIB.BASEBOARD_FAB2(SCH_1):M_J_CPU_VREF':
 C_SIGNAL='@baseboard_fab2_lib.baseboard_fab2(sch_1):m_j_cpu_vref';
NODE_NAME     U2D1 AH63
 '@BASEBOARD_FAB2_LIB.BASEBOARD_FAB2(SCH_1):PAGE55_I172@CHPSET_LIB.SKX_EXT_B(CHIPS)':
 'DDR2_CAVREF': CDS_PINID='DDR2_CAVREF';
NODE_NAME     R1G14 1
 '@BASEBOARD_FAB2_LIB.BASEBOARD_FAB2(SCH_1):PAGE100_I41@MSTR_DISCRETE.RES(CHIPS)':
 'A': CDS_PINID='A';
NODE_NAME     C1G18 1
 '@BASEBOARD_FAB2_LIB.BASEBOARD_FAB2(SCH_1):PAGE100_I42@DEV_DISCRETE.CAP_A(CHIPS)':
 'A': CDS_PINID='A';
NET_NAME
'M_J_CS_N<0>'
 '@BASEBOARD_FAB2_LIB.BASEBOARD_FAB2(SCH_1):M_J_CS_N'<0>:
 C_SIGNAL='@baseboard_fab2_lib.baseboard_fab2(sch_1):m_j_cs_n(0)';
NODE_NAME     U2D1 V51
 '@BASEBOARD_FAB2_LIB.BASEBOARD_FAB2(SCH_1):PAGE59_I172@CHPSET_LIB.SKX_EXT_B(CHIPS)':
 'DDR2_CS_N'<0>: CDS_PINID='DDR2_CS_N(0)';
NODE_NAME     J1G3 84
 '@BASEBOARD_FAB2_LIB.BASEBOARD_FAB2(SCH_1):PAGE81_I186@MSTR_SCONN.SCONN288_H44441004(CHIPS)':
 'S0_N': CDS_PINID='S0_N';
NET_NAME
'M_J_CS_N<1>'
 '@BASEBOARD_FAB2_LIB.BASEBOARD_FAB2(SCH_1):M_J_CS_N'<1>:
 C_SIGNAL='@baseboard_fab2_lib.baseboard_fab2(sch_1):m_j_cs_n(1)';
NODE_NAME     U2D1 AB49
 '@BASEBOARD_FAB2_LIB.BASEBOARD_FAB2(SCH_1):PAGE59_I172@CHPSET_LIB.SKX_EXT_B(CHIPS)':
 'DDR2_CS_N'<1>: CDS_PINID='DDR2_CS_N(1)';
NODE_NAME     J1G3 89
 '@BASEBOARD_FAB2_LIB.BASEBOARD_FAB2(SCH_1):PAGE81_I186@MSTR_SCONN.SCONN288_H44441004(CHIPS)':
 'S1_N': CDS_PINID='S1_N';
NET_NAME
'M_J_CS_N<2>'
 '@BASEBOARD_FAB2_LIB.BASEBOARD_FAB2(SCH_1):M_J_CS_N'<2>:
 C_SIGNAL='@baseboard_fab2_lib.baseboard_fab2(sch_1):m_j_cs_n(2)';
NODE_NAME     U2D1 W46
 '@BASEBOARD_FAB2_LIB.BASEBOARD_FAB2(SCH_1):PAGE59_I172@CHPSET_LIB.SKX_EXT_B(CHIPS)':
 'DDR2_CS_N'<2>: CDS_PINID='DDR2_CS_N(2)';
NODE_NAME     J1G3 93
 '@BASEBOARD_FAB2_LIB.BASEBOARD_FAB2(SCH_1):PAGE81_I186@MSTR_SCONN.SCONN288_H44441004(CHIPS)':
 'S2_N_C'<0>: CDS_PINID='S2_N_C(0)';
NET_NAME
'M_J_CS_N<3>'
 '@BASEBOARD_FAB2_LIB.BASEBOARD_FAB2(SCH_1):M_J_CS_N'<3>:
 C_SIGNAL='@baseboard_fab2_lib.baseboard_fab2(sch_1):m_j_cs_n(3)';
NODE_NAME     U2D1 AA46
 '@BASEBOARD_FAB2_LIB.BASEBOARD_FAB2(SCH_1):PAGE59_I172@CHPSET_LIB.SKX_EXT_B(CHIPS)':
 'DDR2_CS_N'<3>: CDS_PINID='DDR2_CS_N(3)';
NODE_NAME     J1G3 237
 '@BASEBOARD_FAB2_LIB.BASEBOARD_FAB2(SCH_1):PAGE81_I186@MSTR_SCONN.SCONN288_H44441004(CHIPS)':
 'S3_N_C'<1>: CDS_PINID='S3_N_C(1)';
NET_NAME
'M_J_CS_N<4>'
 '@BASEBOARD_FAB2_LIB.BASEBOARD_FAB2(SCH_1):M_J_CS_N'<4>:
 C_SIGNAL='@baseboard_fab2_lib.baseboard_fab2(sch_1):m_j_cs_n(4)';
NODE_NAME     U2D1 AB51
 '@BASEBOARD_FAB2_LIB.BASEBOARD_FAB2(SCH_1):PAGE59_I172@CHPSET_LIB.SKX_EXT_B(CHIPS)':
 'DDR2_CS_N'<4>: CDS_PINID='DDR2_CS_N(4)';
NODE_NAME     J9U2 84
 '@BASEBOARD_FAB2_LIB.BASEBOARD_FAB2(SCH_1):PAGE82_I187@MSTR_SCONN.SCONN288_H44441003(CHIPS)':
 'S0_N': CDS_PINID='S0_N';
NET_NAME
'M_J_CS_N<5>'
 '@BASEBOARD_FAB2_LIB.BASEBOARD_FAB2(SCH_1):M_J_CS_N'<5>:
 C_SIGNAL='@baseboard_fab2_lib.baseboard_fab2(sch_1):m_j_cs_n(5)';
NODE_NAME     U2D1 W48
 '@BASEBOARD_FAB2_LIB.BASEBOARD_FAB2(SCH_1):PAGE59_I172@CHPSET_LIB.SKX_EXT_B(CHIPS)':
 'DDR2_CS_N'<5>: CDS_PINID='DDR2_CS_N(5)';
NODE_NAME     J9U2 89
 '@BASEBOARD_FAB2_LIB.BASEBOARD_FAB2(SCH_1):PAGE82_I187@MSTR_SCONN.SCONN288_H44441003(CHIPS)':
 'S1_N': CDS_PINID='S1_N';
NET_NAME
'M_J_CS_N<6>'
 '@BASEBOARD_FAB2_LIB.BASEBOARD_FAB2(SCH_1):M_J_CS_N'<6>:
 C_SIGNAL='@baseboard_fab2_lib.baseboard_fab2(sch_1):m_j_cs_n(6)';
NODE_NAME     U2D1 T45
 '@BASEBOARD_FAB2_LIB.BASEBOARD_FAB2(SCH_1):PAGE59_I172@CHPSET_LIB.SKX_EXT_B(CHIPS)':
 'DDR2_CS_N'<6>: CDS_PINID='DDR2_CS_N(6)';
NODE_NAME     J9U2 93
 '@BASEBOARD_FAB2_LIB.BASEBOARD_FAB2(SCH_1):PAGE82_I187@MSTR_SCONN.SCONN288_H44441003(CHIPS)':
 'S2_N_C'<0>: CDS_PINID='S2_N_C(0)';
NET_NAME
'M_J_CS_N<7>'
 '@BASEBOARD_FAB2_LIB.BASEBOARD_FAB2(SCH_1):M_J_CS_N'<7>:
 C_SIGNAL='@baseboard_fab2_lib.baseboard_fab2(sch_1):m_j_cs_n(7)';
NODE_NAME     U2D1 V45
 '@BASEBOARD_FAB2_LIB.BASEBOARD_FAB2(SCH_1):PAGE59_I172@CHPSET_LIB.SKX_EXT_B(CHIPS)':
 'DDR2_CS_N'<7>: CDS_PINID='DDR2_CS_N(7)';
NODE_NAME     J9U2 237
 '@BASEBOARD_FAB2_LIB.BASEBOARD_FAB2(SCH_1):PAGE82_I187@MSTR_SCONN.SCONN288_H44441003(CHIPS)':
 'S3_N_C'<1>: CDS_PINID='S3_N_C(1)';
NET_NAME
'M_J_DQ<0>'
 '@BASEBOARD_FAB2_LIB.BASEBOARD_FAB2(SCH_1):M_J_DQ'<0>:
 C_SIGNAL='@baseboard_fab2_lib.baseboard_fab2(sch_1):m_j_dq(0)';
NODE_NAME     U2D1 AR76
 '@BASEBOARD_FAB2_LIB.BASEBOARD_FAB2(SCH_1):PAGE59_I172@CHPSET_LIB.SKX_EXT_B(CHIPS)':
 'DDR2_DQ'<0>: CDS_PINID='DDR2_DQ(0)';
NODE_NAME     J1G3 150
 '@BASEBOARD_FAB2_LIB.BASEBOARD_FAB2(SCH_1):PAGE81_I186@MSTR_SCONN.SCONN288_H44441004(CHIPS)':
 'DQ'<1>: CDS_PINID='DQ(1)';
NODE_NAME     J9U2 5
 '@BASEBOARD_FAB2_LIB.BASEBOARD_FAB2(SCH_1):PAGE82_I187@MSTR_SCONN.SCONN288_H44441003(CHIPS)':
 'DQ'<0>: CDS_PINID='DQ(0)';
NET_NAME
'M_J_DQ<10>'
 '@BASEBOARD_FAB2_LIB.BASEBOARD_FAB2(SCH_1):M_J_DQ'<10>:
 C_SIGNAL='@baseboard_fab2_lib.baseboard_fab2(sch_1):m_j_dq(10)';
NODE_NAME     U2D1 Y77
 '@BASEBOARD_FAB2_LIB.BASEBOARD_FAB2(SCH_1):PAGE59_I172@CHPSET_LIB.SKX_EXT_B(CHIPS)':
 'DDR2_DQ'<10>: CDS_PINID='DDR2_DQ(10)';
NODE_NAME     J1G3 168
 '@BASEBOARD_FAB2_LIB.BASEBOARD_FAB2(SCH_1):PAGE81_I186@MSTR_SCONN.SCONN288_H44441004(CHIPS)':
 'DQ'<11>: CDS_PINID='DQ(11)';
NODE_NAME     J9U2 23
 '@BASEBOARD_FAB2_LIB.BASEBOARD_FAB2(SCH_1):PAGE82_I187@MSTR_SCONN.SCONN288_H44441003(CHIPS)':
 'DQ'<10>: CDS_PINID='DQ(10)';
NET_NAME
'M_J_DQ<11>'
 '@BASEBOARD_FAB2_LIB.BASEBOARD_FAB2(SCH_1):M_J_DQ'<11>:
 C_SIGNAL='@baseboard_fab2_lib.baseboard_fab2(sch_1):m_j_dq(11)';
NODE_NAME     U2D1 W76
 '@BASEBOARD_FAB2_LIB.BASEBOARD_FAB2(SCH_1):PAGE59_I172@CHPSET_LIB.SKX_EXT_B(CHIPS)':
 'DDR2_DQ'<11>: CDS_PINID='DDR2_DQ(11)';
NODE_NAME     J1G3 23
 '@BASEBOARD_FAB2_LIB.BASEBOARD_FAB2(SCH_1):PAGE81_I186@MSTR_SCONN.SCONN288_H44441004(CHIPS)':
 'DQ'<10>: CDS_PINID='DQ(10)';
NODE_NAME     J9U2 168
 '@BASEBOARD_FAB2_LIB.BASEBOARD_FAB2(SCH_1):PAGE82_I187@MSTR_SCONN.SCONN288_H44441003(CHIPS)':
 'DQ'<11>: CDS_PINID='DQ(11)';
NET_NAME
'M_J_DQ<12>'
 '@BASEBOARD_FAB2_LIB.BASEBOARD_FAB2(SCH_1):M_J_DQ'<12>:
 C_SIGNAL='@baseboard_fab2_lib.baseboard_fab2(sch_1):m_j_dq(12)';
NODE_NAME     U2D1 AF75
 '@BASEBOARD_FAB2_LIB.BASEBOARD_FAB2(SCH_1):PAGE59_I172@CHPSET_LIB.SKX_EXT_B(CHIPS)':
 'DDR2_DQ'<12>: CDS_PINID='DDR2_DQ(12)';
NODE_NAME     J1G3 159
 '@BASEBOARD_FAB2_LIB.BASEBOARD_FAB2(SCH_1):PAGE81_I186@MSTR_SCONN.SCONN288_H44441004(CHIPS)':
 'DQ'<13>: CDS_PINID='DQ(13)';
NODE_NAME     J9U2 14
 '@BASEBOARD_FAB2_LIB.BASEBOARD_FAB2(SCH_1):PAGE82_I187@MSTR_SCONN.SCONN288_H44441003(CHIPS)':
 'DQ'<12>: CDS_PINID='DQ(12)';
NET_NAME
'M_J_DQ<13>'
 '@BASEBOARD_FAB2_LIB.BASEBOARD_FAB2(SCH_1):M_J_DQ'<13>:
 C_SIGNAL='@baseboard_fab2_lib.baseboard_fab2(sch_1):m_j_dq(13)';
NODE_NAME     U2D1 AE74
 '@BASEBOARD_FAB2_LIB.BASEBOARD_FAB2(SCH_1):PAGE59_I172@CHPSET_LIB.SKX_EXT_B(CHIPS)':
 'DDR2_DQ'<13>: CDS_PINID='DDR2_DQ(13)';
NODE_NAME     J1G3 14
 '@BASEBOARD_FAB2_LIB.BASEBOARD_FAB2(SCH_1):PAGE81_I186@MSTR_SCONN.SCONN288_H44441004(CHIPS)':
 'DQ'<12>: CDS_PINID='DQ(12)';
NODE_NAME     J9U2 159
 '@BASEBOARD_FAB2_LIB.BASEBOARD_FAB2(SCH_1):PAGE82_I187@MSTR_SCONN.SCONN288_H44441003(CHIPS)':
 'DQ'<13>: CDS_PINID='DQ(13)';
NET_NAME
'M_J_DQ<14>'
 '@BASEBOARD_FAB2_LIB.BASEBOARD_FAB2(SCH_1):M_J_DQ'<14>:
 C_SIGNAL='@baseboard_fab2_lib.baseboard_fab2(sch_1):m_j_dq(14)';
NODE_NAME     U2D1 AB77
 '@BASEBOARD_FAB2_LIB.BASEBOARD_FAB2(SCH_1):PAGE59_I172@CHPSET_LIB.SKX_EXT_B(CHIPS)':
 'DDR2_DQ'<14>: CDS_PINID='DDR2_DQ(14)';
NODE_NAME     J1G3 166
 '@BASEBOARD_FAB2_LIB.BASEBOARD_FAB2(SCH_1):PAGE81_I186@MSTR_SCONN.SCONN288_H44441004(CHIPS)':
 'DQ'<15>: CDS_PINID='DQ(15)';
NODE_NAME     J9U2 21
 '@BASEBOARD_FAB2_LIB.BASEBOARD_FAB2(SCH_1):PAGE82_I187@MSTR_SCONN.SCONN288_H44441003(CHIPS)':
 'DQ'<14>: CDS_PINID='DQ(14)';
NET_NAME
'M_J_DQ<15>'
 '@BASEBOARD_FAB2_LIB.BASEBOARD_FAB2(SCH_1):M_J_DQ'<15>:
 C_SIGNAL='@baseboard_fab2_lib.baseboard_fab2(sch_1):m_j_dq(15)';
NODE_NAME     U2D1 Y75
 '@BASEBOARD_FAB2_LIB.BASEBOARD_FAB2(SCH_1):PAGE59_I172@CHPSET_LIB.SKX_EXT_B(CHIPS)':
 'DDR2_DQ'<15>: CDS_PINID='DDR2_DQ(15)';
NODE_NAME     J1G3 21
 '@BASEBOARD_FAB2_LIB.BASEBOARD_FAB2(SCH_1):PAGE81_I186@MSTR_SCONN.SCONN288_H44441004(CHIPS)':
 'DQ'<14>: CDS_PINID='DQ(14)';
NODE_NAME     J9U2 166
 '@BASEBOARD_FAB2_LIB.BASEBOARD_FAB2(SCH_1):PAGE82_I187@MSTR_SCONN.SCONN288_H44441003(CHIPS)':
 'DQ'<15>: CDS_PINID='DQ(15)';
NET_NAME
'M_J_DQ<16>'
 '@BASEBOARD_FAB2_LIB.BASEBOARD_FAB2(SCH_1):M_J_DQ'<16>:
 C_SIGNAL='@baseboard_fab2_lib.baseboard_fab2(sch_1):m_j_dq(16)';
NODE_NAME     U2D1 W72
 '@BASEBOARD_FAB2_LIB.BASEBOARD_FAB2(SCH_1):PAGE59_I172@CHPSET_LIB.SKX_EXT_B(CHIPS)':
 'DDR2_DQ'<16>: CDS_PINID='DDR2_DQ(16)';
NODE_NAME     J1G3 172
 '@BASEBOARD_FAB2_LIB.BASEBOARD_FAB2(SCH_1):PAGE81_I186@MSTR_SCONN.SCONN288_H44441004(CHIPS)':
 'DQ'<17>: CDS_PINID='DQ(17)';
NODE_NAME     J9U2 27
 '@BASEBOARD_FAB2_LIB.BASEBOARD_FAB2(SCH_1):PAGE82_I187@MSTR_SCONN.SCONN288_H44441003(CHIPS)':
 'DQ'<16>: CDS_PINID='DQ(16)';
NET_NAME
'M_J_DQ<17>'
 '@BASEBOARD_FAB2_LIB.BASEBOARD_FAB2(SCH_1):M_J_DQ'<17>:
 C_SIGNAL='@baseboard_fab2_lib.baseboard_fab2(sch_1):m_j_dq(17)';
NODE_NAME     U2D1 AA70
 '@BASEBOARD_FAB2_LIB.BASEBOARD_FAB2(SCH_1):PAGE59_I172@CHPSET_LIB.SKX_EXT_B(CHIPS)':
 'DDR2_DQ'<17>: CDS_PINID='DDR2_DQ(17)';
NODE_NAME     J1G3 27
 '@BASEBOARD_FAB2_LIB.BASEBOARD_FAB2(SCH_1):PAGE81_I186@MSTR_SCONN.SCONN288_H44441004(CHIPS)':
 'DQ'<16>: CDS_PINID='DQ(16)';
NODE_NAME     J9U2 172
 '@BASEBOARD_FAB2_LIB.BASEBOARD_FAB2(SCH_1):PAGE82_I187@MSTR_SCONN.SCONN288_H44441003(CHIPS)':
 'DQ'<17>: CDS_PINID='DQ(17)';
NET_NAME
'M_J_DQ<18>'
 '@BASEBOARD_FAB2_LIB.BASEBOARD_FAB2(SCH_1):M_J_DQ'<18>:
 C_SIGNAL='@baseboard_fab2_lib.baseboard_fab2(sch_1):m_j_dq(18)';
NODE_NAME     U2D1 R70
 '@BASEBOARD_FAB2_LIB.BASEBOARD_FAB2(SCH_1):PAGE59_I172@CHPSET_LIB.SKX_EXT_B(CHIPS)':
 'DDR2_DQ'<18>: CDS_PINID='DDR2_DQ(18)';
NODE_NAME     J1G3 179
 '@BASEBOARD_FAB2_LIB.BASEBOARD_FAB2(SCH_1):PAGE81_I186@MSTR_SCONN.SCONN288_H44441004(CHIPS)':
 'DQ'<19>: CDS_PINID='DQ(19)';
NODE_NAME     J9U2 34
 '@BASEBOARD_FAB2_LIB.BASEBOARD_FAB2(SCH_1):PAGE82_I187@MSTR_SCONN.SCONN288_H44441003(CHIPS)':
 'DQ'<18>: CDS_PINID='DQ(18)';
NET_NAME
'M_J_DQ<19>'
 '@BASEBOARD_FAB2_LIB.BASEBOARD_FAB2(SCH_1):M_J_DQ'<19>:
 C_SIGNAL='@baseboard_fab2_lib.baseboard_fab2(sch_1):m_j_dq(19)';
NODE_NAME     U2D1 T69
 '@BASEBOARD_FAB2_LIB.BASEBOARD_FAB2(SCH_1):PAGE59_I172@CHPSET_LIB.SKX_EXT_B(CHIPS)':
 'DDR2_DQ'<19>: CDS_PINID='DDR2_DQ(19)';
NODE_NAME     J1G3 34
 '@BASEBOARD_FAB2_LIB.BASEBOARD_FAB2(SCH_1):PAGE81_I186@MSTR_SCONN.SCONN288_H44441004(CHIPS)':
 'DQ'<18>: CDS_PINID='DQ(18)';
NODE_NAME     J9U2 179
 '@BASEBOARD_FAB2_LIB.BASEBOARD_FAB2(SCH_1):PAGE82_I187@MSTR_SCONN.SCONN288_H44441003(CHIPS)':
 'DQ'<19>: CDS_PINID='DQ(19)';
NET_NAME
'M_J_DQ<1>'
 '@BASEBOARD_FAB2_LIB.BASEBOARD_FAB2(SCH_1):M_J_DQ'<1>:
 C_SIGNAL='@baseboard_fab2_lib.baseboard_fab2(sch_1):m_j_dq(1)';
NODE_NAME     U2D1 AN74
 '@BASEBOARD_FAB2_LIB.BASEBOARD_FAB2(SCH_1):PAGE59_I172@CHPSET_LIB.SKX_EXT_B(CHIPS)':
 'DDR2_DQ'<1>: CDS_PINID='DDR2_DQ(1)';
NODE_NAME     J1G3 5
 '@BASEBOARD_FAB2_LIB.BASEBOARD_FAB2(SCH_1):PAGE81_I186@MSTR_SCONN.SCONN288_H44441004(CHIPS)':
 'DQ'<0>: CDS_PINID='DQ(0)';
NODE_NAME     J9U2 150
 '@BASEBOARD_FAB2_LIB.BASEBOARD_FAB2(SCH_1):PAGE82_I187@MSTR_SCONN.SCONN288_H44441003(CHIPS)':
 'DQ'<1>: CDS_PINID='DQ(1)';
NET_NAME
'M_J_DQ<20>'
 '@BASEBOARD_FAB2_LIB.BASEBOARD_FAB2(SCH_1):M_J_DQ'<20>:
 C_SIGNAL='@baseboard_fab2_lib.baseboard_fab2(sch_1):m_j_dq(20)';
NODE_NAME     U2D1 AA72
 '@BASEBOARD_FAB2_LIB.BASEBOARD_FAB2(SCH_1):PAGE59_I172@CHPSET_LIB.SKX_EXT_B(CHIPS)':
 'DDR2_DQ'<20>: CDS_PINID='DDR2_DQ(20)';
NODE_NAME     J1G3 170
 '@BASEBOARD_FAB2_LIB.BASEBOARD_FAB2(SCH_1):PAGE81_I186@MSTR_SCONN.SCONN288_H44441004(CHIPS)':
 'DQ'<21>: CDS_PINID='DQ(21)';
NODE_NAME     J9U2 25
 '@BASEBOARD_FAB2_LIB.BASEBOARD_FAB2(SCH_1):PAGE82_I187@MSTR_SCONN.SCONN288_H44441003(CHIPS)':
 'DQ'<20>: CDS_PINID='DQ(20)';
NET_NAME
'M_J_DQ<21>'
 '@BASEBOARD_FAB2_LIB.BASEBOARD_FAB2(SCH_1):M_J_DQ'<21>:
 C_SIGNAL='@baseboard_fab2_lib.baseboard_fab2(sch_1):m_j_dq(21)';
NODE_NAME     U2D1 AB71
 '@BASEBOARD_FAB2_LIB.BASEBOARD_FAB2(SCH_1):PAGE59_I172@CHPSET_LIB.SKX_EXT_B(CHIPS)':
 'DDR2_DQ'<21>: CDS_PINID='DDR2_DQ(21)';
NODE_NAME     J1G3 25
 '@BASEBOARD_FAB2_LIB.BASEBOARD_FAB2(SCH_1):PAGE81_I186@MSTR_SCONN.SCONN288_H44441004(CHIPS)':
 'DQ'<20>: CDS_PINID='DQ(20)';
NODE_NAME     J9U2 170
 '@BASEBOARD_FAB2_LIB.BASEBOARD_FAB2(SCH_1):PAGE82_I187@MSTR_SCONN.SCONN288_H44441003(CHIPS)':
 'DQ'<21>: CDS_PINID='DQ(21)';
NET_NAME
'M_J_DQ<22>'
 '@BASEBOARD_FAB2_LIB.BASEBOARD_FAB2(SCH_1):M_J_DQ'<22>:
 C_SIGNAL='@baseboard_fab2_lib.baseboard_fab2(sch_1):m_j_dq(22)';
NODE_NAME     U2D1 T71
 '@BASEBOARD_FAB2_LIB.BASEBOARD_FAB2(SCH_1):PAGE59_I172@CHPSET_LIB.SKX_EXT_B(CHIPS)':
 'DDR2_DQ'<22>: CDS_PINID='DDR2_DQ(22)';
NODE_NAME     J1G3 177
 '@BASEBOARD_FAB2_LIB.BASEBOARD_FAB2(SCH_1):PAGE81_I186@MSTR_SCONN.SCONN288_H44441004(CHIPS)':
 'DQ'<23>: CDS_PINID='DQ(23)';
NODE_NAME     J9U2 32
 '@BASEBOARD_FAB2_LIB.BASEBOARD_FAB2(SCH_1):PAGE82_I187@MSTR_SCONN.SCONN288_H44441003(CHIPS)':
 'DQ'<22>: CDS_PINID='DQ(22)';
NET_NAME
'M_J_DQ<23>'
 '@BASEBOARD_FAB2_LIB.BASEBOARD_FAB2(SCH_1):M_J_DQ'<23>:
 C_SIGNAL='@baseboard_fab2_lib.baseboard_fab2(sch_1):m_j_dq(23)';
NODE_NAME     U2D1 V69
 '@BASEBOARD_FAB2_LIB.BASEBOARD_FAB2(SCH_1):PAGE59_I172@CHPSET_LIB.SKX_EXT_B(CHIPS)':
 'DDR2_DQ'<23>: CDS_PINID='DDR2_DQ(23)';
NODE_NAME     J1G3 32
 '@BASEBOARD_FAB2_LIB.BASEBOARD_FAB2(SCH_1):PAGE81_I186@MSTR_SCONN.SCONN288_H44441004(CHIPS)':
 'DQ'<22>: CDS_PINID='DQ(22)';
NODE_NAME     J9U2 177
 '@BASEBOARD_FAB2_LIB.BASEBOARD_FAB2(SCH_1):PAGE82_I187@MSTR_SCONN.SCONN288_H44441003(CHIPS)':
 'DQ'<23>: CDS_PINID='DQ(23)';
NET_NAME
'M_J_DQ<24>'
 '@BASEBOARD_FAB2_LIB.BASEBOARD_FAB2(SCH_1):M_J_DQ'<24>:
 C_SIGNAL='@baseboard_fab2_lib.baseboard_fab2(sch_1):m_j_dq(24)';
NODE_NAME     U2D1 AM67
 '@BASEBOARD_FAB2_LIB.BASEBOARD_FAB2(SCH_1):PAGE59_I172@CHPSET_LIB.SKX_EXT_B(CHIPS)':
 'DDR2_DQ'<24>: CDS_PINID='DDR2_DQ(24)';
NODE_NAME     J1G3 183
 '@BASEBOARD_FAB2_LIB.BASEBOARD_FAB2(SCH_1):PAGE81_I186@MSTR_SCONN.SCONN288_H44441004(CHIPS)':
 'DQ'<25>: CDS_PINID='DQ(25)';
NODE_NAME     J9U2 38
 '@BASEBOARD_FAB2_LIB.BASEBOARD_FAB2(SCH_1):PAGE82_I187@MSTR_SCONN.SCONN288_H44441003(CHIPS)':
 'DQ'<24>: CDS_PINID='DQ(24)';
NET_NAME
'M_J_DQ<25>'
 '@BASEBOARD_FAB2_LIB.BASEBOARD_FAB2(SCH_1):M_J_DQ'<25>:
 C_SIGNAL='@baseboard_fab2_lib.baseboard_fab2(sch_1):m_j_dq(25)';
NODE_NAME     U2D1 AT67
 '@BASEBOARD_FAB2_LIB.BASEBOARD_FAB2(SCH_1):PAGE59_I172@CHPSET_LIB.SKX_EXT_B(CHIPS)':
 'DDR2_DQ'<25>: CDS_PINID='DDR2_DQ(25)';
NODE_NAME     J1G3 38
 '@BASEBOARD_FAB2_LIB.BASEBOARD_FAB2(SCH_1):PAGE81_I186@MSTR_SCONN.SCONN288_H44441004(CHIPS)':
 'DQ'<24>: CDS_PINID='DQ(24)';
NODE_NAME     J9U2 183
 '@BASEBOARD_FAB2_LIB.BASEBOARD_FAB2(SCH_1):PAGE82_I187@MSTR_SCONN.SCONN288_H44441003(CHIPS)':
 'DQ'<25>: CDS_PINID='DQ(25)';
NET_NAME
'M_J_DQ<26>'
 '@BASEBOARD_FAB2_LIB.BASEBOARD_FAB2(SCH_1):M_J_DQ'<26>:
 C_SIGNAL='@baseboard_fab2_lib.baseboard_fab2(sch_1):m_j_dq(26)';
NODE_NAME     U2D1 AN64
 '@BASEBOARD_FAB2_LIB.BASEBOARD_FAB2(SCH_1):PAGE59_I172@CHPSET_LIB.SKX_EXT_B(CHIPS)':
 'DDR2_DQ'<26>: CDS_PINID='DDR2_DQ(26)';
NODE_NAME     J1G3 190
 '@BASEBOARD_FAB2_LIB.BASEBOARD_FAB2(SCH_1):PAGE81_I186@MSTR_SCONN.SCONN288_H44441004(CHIPS)':
 'DQ'<27>: CDS_PINID='DQ(27)';
NODE_NAME     J9U2 45
 '@BASEBOARD_FAB2_LIB.BASEBOARD_FAB2(SCH_1):PAGE82_I187@MSTR_SCONN.SCONN288_H44441003(CHIPS)':
 'DQ'<26>: CDS_PINID='DQ(26)';
NET_NAME
'M_J_DQ<27>'
 '@BASEBOARD_FAB2_LIB.BASEBOARD_FAB2(SCH_1):M_J_DQ'<27>:
 C_SIGNAL='@baseboard_fab2_lib.baseboard_fab2(sch_1):m_j_dq(27)';
NODE_NAME     U2D1 AR64
 '@BASEBOARD_FAB2_LIB.BASEBOARD_FAB2(SCH_1):PAGE59_I172@CHPSET_LIB.SKX_EXT_B(CHIPS)':
 'DDR2_DQ'<27>: CDS_PINID='DDR2_DQ(27)';
NODE_NAME     J1G3 45
 '@BASEBOARD_FAB2_LIB.BASEBOARD_FAB2(SCH_1):PAGE81_I186@MSTR_SCONN.SCONN288_H44441004(CHIPS)':
 'DQ'<26>: CDS_PINID='DQ(26)';
NODE_NAME     J9U2 190
 '@BASEBOARD_FAB2_LIB.BASEBOARD_FAB2(SCH_1):PAGE82_I187@MSTR_SCONN.SCONN288_H44441003(CHIPS)':
 'DQ'<27>: CDS_PINID='DQ(27)';
NET_NAME
'M_J_DQ<28>'
 '@BASEBOARD_FAB2_LIB.BASEBOARD_FAB2(SCH_1):M_J_DQ'<28>:
 C_SIGNAL='@baseboard_fab2_lib.baseboard_fab2(sch_1):m_j_dq(28)';
NODE_NAME     U2D1 AN68
 '@BASEBOARD_FAB2_LIB.BASEBOARD_FAB2(SCH_1):PAGE59_I172@CHPSET_LIB.SKX_EXT_B(CHIPS)':
 'DDR2_DQ'<28>: CDS_PINID='DDR2_DQ(28)';
NODE_NAME     J1G3 181
 '@BASEBOARD_FAB2_LIB.BASEBOARD_FAB2(SCH_1):PAGE81_I186@MSTR_SCONN.SCONN288_H44441004(CHIPS)':
 'DQ'<29>: CDS_PINID='DQ(29)';
NODE_NAME     J9U2 36
 '@BASEBOARD_FAB2_LIB.BASEBOARD_FAB2(SCH_1):PAGE82_I187@MSTR_SCONN.SCONN288_H44441003(CHIPS)':
 'DQ'<28>: CDS_PINID='DQ(28)';
NET_NAME
'M_J_DQ<29>'
 '@BASEBOARD_FAB2_LIB.BASEBOARD_FAB2(SCH_1):M_J_DQ'<29>:
 C_SIGNAL='@baseboard_fab2_lib.baseboard_fab2(sch_1):m_j_dq(29)';
NODE_NAME     U2D1 AR68
 '@BASEBOARD_FAB2_LIB.BASEBOARD_FAB2(SCH_1):PAGE59_I172@CHPSET_LIB.SKX_EXT_B(CHIPS)':
 'DDR2_DQ'<29>: CDS_PINID='DDR2_DQ(29)';
NODE_NAME     J1G3 36
 '@BASEBOARD_FAB2_LIB.BASEBOARD_FAB2(SCH_1):PAGE81_I186@MSTR_SCONN.SCONN288_H44441004(CHIPS)':
 'DQ'<28>: CDS_PINID='DQ(28)';
NODE_NAME     J9U2 181
 '@BASEBOARD_FAB2_LIB.BASEBOARD_FAB2(SCH_1):PAGE82_I187@MSTR_SCONN.SCONN288_H44441003(CHIPS)':
 'DQ'<29>: CDS_PINID='DQ(29)';
NET_NAME
'M_J_DQ<2>'
 '@BASEBOARD_FAB2_LIB.BASEBOARD_FAB2(SCH_1):M_J_DQ'<2>:
 C_SIGNAL='@baseboard_fab2_lib.baseboard_fab2(sch_1):m_j_dq(2)';
NODE_NAME     U2D1 AK77
 '@BASEBOARD_FAB2_LIB.BASEBOARD_FAB2(SCH_1):PAGE59_I172@CHPSET_LIB.SKX_EXT_B(CHIPS)':
 'DDR2_DQ'<2>: CDS_PINID='DDR2_DQ(2)';
NODE_NAME     J1G3 157
 '@BASEBOARD_FAB2_LIB.BASEBOARD_FAB2(SCH_1):PAGE81_I186@MSTR_SCONN.SCONN288_H44441004(CHIPS)':
 'DQ'<3>: CDS_PINID='DQ(3)';
NODE_NAME     J9U2 12
 '@BASEBOARD_FAB2_LIB.BASEBOARD_FAB2(SCH_1):PAGE82_I187@MSTR_SCONN.SCONN288_H44441003(CHIPS)':
 'DQ'<2>: CDS_PINID='DQ(2)';
NET_NAME
'M_J_DQ<30>'
 '@BASEBOARD_FAB2_LIB.BASEBOARD_FAB2(SCH_1):M_J_DQ'<30>:
 C_SIGNAL='@baseboard_fab2_lib.baseboard_fab2(sch_1):m_j_dq(30)';
NODE_NAME     U2D1 AM65
 '@BASEBOARD_FAB2_LIB.BASEBOARD_FAB2(SCH_1):PAGE59_I172@CHPSET_LIB.SKX_EXT_B(CHIPS)':
 'DDR2_DQ'<30>: CDS_PINID='DDR2_DQ(30)';
NODE_NAME     J1G3 188
 '@BASEBOARD_FAB2_LIB.BASEBOARD_FAB2(SCH_1):PAGE81_I186@MSTR_SCONN.SCONN288_H44441004(CHIPS)':
 'DQ'<31>: CDS_PINID='DQ(31)';
NODE_NAME     J9U2 43
 '@BASEBOARD_FAB2_LIB.BASEBOARD_FAB2(SCH_1):PAGE82_I187@MSTR_SCONN.SCONN288_H44441003(CHIPS)':
 'DQ'<30>: CDS_PINID='DQ(30)';
NET_NAME
'M_J_DQ<31>'
 '@BASEBOARD_FAB2_LIB.BASEBOARD_FAB2(SCH_1):M_J_DQ'<31>:
 C_SIGNAL='@baseboard_fab2_lib.baseboard_fab2(sch_1):m_j_dq(31)';
NODE_NAME     U2D1 AT65
 '@BASEBOARD_FAB2_LIB.BASEBOARD_FAB2(SCH_1):PAGE59_I172@CHPSET_LIB.SKX_EXT_B(CHIPS)':
 'DDR2_DQ'<31>: CDS_PINID='DDR2_DQ(31)';
NODE_NAME     J1G3 43
 '@BASEBOARD_FAB2_LIB.BASEBOARD_FAB2(SCH_1):PAGE81_I186@MSTR_SCONN.SCONN288_H44441004(CHIPS)':
 'DQ'<30>: CDS_PINID='DQ(30)';
NODE_NAME     J9U2 188
 '@BASEBOARD_FAB2_LIB.BASEBOARD_FAB2(SCH_1):PAGE82_I187@MSTR_SCONN.SCONN288_H44441003(CHIPS)':
 'DQ'<31>: CDS_PINID='DQ(31)';
NET_NAME
'M_J_DQ<32>'
 '@BASEBOARD_FAB2_LIB.BASEBOARD_FAB2(SCH_1):M_J_DQ'<32>:
 C_SIGNAL='@baseboard_fab2_lib.baseboard_fab2(sch_1):m_j_dq(32)';
NODE_NAME     U2D1 U40
 '@BASEBOARD_FAB2_LIB.BASEBOARD_FAB2(SCH_1):PAGE59_I172@CHPSET_LIB.SKX_EXT_B(CHIPS)':
 'DDR2_DQ'<32>: CDS_PINID='DDR2_DQ(32)';
NODE_NAME     J1G3 242
 '@BASEBOARD_FAB2_LIB.BASEBOARD_FAB2(SCH_1):PAGE81_I186@MSTR_SCONN.SCONN288_H44441004(CHIPS)':
 'DQ'<33>: CDS_PINID='DQ(33)';
NODE_NAME     J9U2 97
 '@BASEBOARD_FAB2_LIB.BASEBOARD_FAB2(SCH_1):PAGE82_I187@MSTR_SCONN.SCONN288_H44441003(CHIPS)':
 'DQ'<32>: CDS_PINID='DQ(32)';
NET_NAME
'M_J_DQ<33>'
 '@BASEBOARD_FAB2_LIB.BASEBOARD_FAB2(SCH_1):M_J_DQ'<33>:
 C_SIGNAL='@baseboard_fab2_lib.baseboard_fab2(sch_1):m_j_dq(33)';
NODE_NAME     U2D1 AA40
 '@BASEBOARD_FAB2_LIB.BASEBOARD_FAB2(SCH_1):PAGE59_I172@CHPSET_LIB.SKX_EXT_B(CHIPS)':
 'DDR2_DQ'<33>: CDS_PINID='DDR2_DQ(33)';
NODE_NAME     J1G3 97
 '@BASEBOARD_FAB2_LIB.BASEBOARD_FAB2(SCH_1):PAGE81_I186@MSTR_SCONN.SCONN288_H44441004(CHIPS)':
 'DQ'<32>: CDS_PINID='DQ(32)';
NODE_NAME     J9U2 242
 '@BASEBOARD_FAB2_LIB.BASEBOARD_FAB2(SCH_1):PAGE82_I187@MSTR_SCONN.SCONN288_H44441003(CHIPS)':
 'DQ'<33>: CDS_PINID='DQ(33)';
NET_NAME
'M_J_DQ<34>'
 '@BASEBOARD_FAB2_LIB.BASEBOARD_FAB2(SCH_1):M_J_DQ'<34>:
 C_SIGNAL='@baseboard_fab2_lib.baseboard_fab2(sch_1):m_j_dq(34)';
NODE_NAME     U2D1 V37
 '@BASEBOARD_FAB2_LIB.BASEBOARD_FAB2(SCH_1):PAGE59_I172@CHPSET_LIB.SKX_EXT_B(CHIPS)':
 'DDR2_DQ'<34>: CDS_PINID='DDR2_DQ(34)';
NODE_NAME     J1G3 249
 '@BASEBOARD_FAB2_LIB.BASEBOARD_FAB2(SCH_1):PAGE81_I186@MSTR_SCONN.SCONN288_H44441004(CHIPS)':
 'DQ'<35>: CDS_PINID='DQ(35)';
NODE_NAME     J9U2 104
 '@BASEBOARD_FAB2_LIB.BASEBOARD_FAB2(SCH_1):PAGE82_I187@MSTR_SCONN.SCONN288_H44441003(CHIPS)':
 'DQ'<34>: CDS_PINID='DQ(34)';
NET_NAME
'M_J_DQ<35>'
 '@BASEBOARD_FAB2_LIB.BASEBOARD_FAB2(SCH_1):M_J_DQ'<35>:
 C_SIGNAL='@baseboard_fab2_lib.baseboard_fab2(sch_1):m_j_dq(35)';
NODE_NAME     U2D1 Y37
 '@BASEBOARD_FAB2_LIB.BASEBOARD_FAB2(SCH_1):PAGE59_I172@CHPSET_LIB.SKX_EXT_B(CHIPS)':
 'DDR2_DQ'<35>: CDS_PINID='DDR2_DQ(35)';
NODE_NAME     J1G3 104
 '@BASEBOARD_FAB2_LIB.BASEBOARD_FAB2(SCH_1):PAGE81_I186@MSTR_SCONN.SCONN288_H44441004(CHIPS)':
 'DQ'<34>: CDS_PINID='DQ(34)';
NODE_NAME     J9U2 249
 '@BASEBOARD_FAB2_LIB.BASEBOARD_FAB2(SCH_1):PAGE82_I187@MSTR_SCONN.SCONN288_H44441003(CHIPS)':
 'DQ'<35>: CDS_PINID='DQ(35)';
NET_NAME
'M_J_DQ<36>'
 '@BASEBOARD_FAB2_LIB.BASEBOARD_FAB2(SCH_1):M_J_DQ'<36>:
 C_SIGNAL='@baseboard_fab2_lib.baseboard_fab2(sch_1):m_j_dq(36)';
NODE_NAME     U2D1 V41
 '@BASEBOARD_FAB2_LIB.BASEBOARD_FAB2(SCH_1):PAGE59_I172@CHPSET_LIB.SKX_EXT_B(CHIPS)':
 'DDR2_DQ'<36>: CDS_PINID='DDR2_DQ(36)';
NODE_NAME     J1G3 240
 '@BASEBOARD_FAB2_LIB.BASEBOARD_FAB2(SCH_1):PAGE81_I186@MSTR_SCONN.SCONN288_H44441004(CHIPS)':
 'DQ'<37>: CDS_PINID='DQ(37)';
NODE_NAME     J9U2 95
 '@BASEBOARD_FAB2_LIB.BASEBOARD_FAB2(SCH_1):PAGE82_I187@MSTR_SCONN.SCONN288_H44441003(CHIPS)':
 'DQ'<36>: CDS_PINID='DQ(36)';
NET_NAME
'M_J_DQ<37>'
 '@BASEBOARD_FAB2_LIB.BASEBOARD_FAB2(SCH_1):M_J_DQ'<37>:
 C_SIGNAL='@baseboard_fab2_lib.baseboard_fab2(sch_1):m_j_dq(37)';
NODE_NAME     U2D1 Y41
 '@BASEBOARD_FAB2_LIB.BASEBOARD_FAB2(SCH_1):PAGE59_I172@CHPSET_LIB.SKX_EXT_B(CHIPS)':
 'DDR2_DQ'<37>: CDS_PINID='DDR2_DQ(37)';
NODE_NAME     J1G3 95
 '@BASEBOARD_FAB2_LIB.BASEBOARD_FAB2(SCH_1):PAGE81_I186@MSTR_SCONN.SCONN288_H44441004(CHIPS)':
 'DQ'<36>: CDS_PINID='DQ(36)';
NODE_NAME     J9U2 240
 '@BASEBOARD_FAB2_LIB.BASEBOARD_FAB2(SCH_1):PAGE82_I187@MSTR_SCONN.SCONN288_H44441003(CHIPS)':
 'DQ'<37>: CDS_PINID='DQ(37)';
NET_NAME
'M_J_DQ<38>'
 '@BASEBOARD_FAB2_LIB.BASEBOARD_FAB2(SCH_1):M_J_DQ'<38>:
 C_SIGNAL='@baseboard_fab2_lib.baseboard_fab2(sch_1):m_j_dq(38)';
NODE_NAME     U2D1 U38
 '@BASEBOARD_FAB2_LIB.BASEBOARD_FAB2(SCH_1):PAGE59_I172@CHPSET_LIB.SKX_EXT_B(CHIPS)':
 'DDR2_DQ'<38>: CDS_PINID='DDR2_DQ(38)';
NODE_NAME     J1G3 247
 '@BASEBOARD_FAB2_LIB.BASEBOARD_FAB2(SCH_1):PAGE81_I186@MSTR_SCONN.SCONN288_H44441004(CHIPS)':
 'DQ'<39>: CDS_PINID='DQ(39)';
NODE_NAME     J9U2 102
 '@BASEBOARD_FAB2_LIB.BASEBOARD_FAB2(SCH_1):PAGE82_I187@MSTR_SCONN.SCONN288_H44441003(CHIPS)':
 'DQ'<38>: CDS_PINID='DQ(38)';
NET_NAME
'M_J_DQ<39>'
 '@BASEBOARD_FAB2_LIB.BASEBOARD_FAB2(SCH_1):M_J_DQ'<39>:
 C_SIGNAL='@baseboard_fab2_lib.baseboard_fab2(sch_1):m_j_dq(39)';
NODE_NAME     U2D1 AA38
 '@BASEBOARD_FAB2_LIB.BASEBOARD_FAB2(SCH_1):PAGE59_I172@CHPSET_LIB.SKX_EXT_B(CHIPS)':
 'DDR2_DQ'<39>: CDS_PINID='DDR2_DQ(39)';
NODE_NAME     J1G3 102
 '@BASEBOARD_FAB2_LIB.BASEBOARD_FAB2(SCH_1):PAGE81_I186@MSTR_SCONN.SCONN288_H44441004(CHIPS)':
 'DQ'<38>: CDS_PINID='DQ(38)';
NODE_NAME     J9U2 247
 '@BASEBOARD_FAB2_LIB.BASEBOARD_FAB2(SCH_1):PAGE82_I187@MSTR_SCONN.SCONN288_H44441003(CHIPS)':
 'DQ'<39>: CDS_PINID='DQ(39)';
NET_NAME
'M_J_DQ<3>'
 '@BASEBOARD_FAB2_LIB.BASEBOARD_FAB2(SCH_1):M_J_DQ'<3>:
 C_SIGNAL='@baseboard_fab2_lib.baseboard_fab2(sch_1):m_j_dq(3)';
NODE_NAME     U2D1 AJ76
 '@BASEBOARD_FAB2_LIB.BASEBOARD_FAB2(SCH_1):PAGE59_I172@CHPSET_LIB.SKX_EXT_B(CHIPS)':
 'DDR2_DQ'<3>: CDS_PINID='DDR2_DQ(3)';
NODE_NAME     J1G3 12
 '@BASEBOARD_FAB2_LIB.BASEBOARD_FAB2(SCH_1):PAGE81_I186@MSTR_SCONN.SCONN288_H44441004(CHIPS)':
 'DQ'<2>: CDS_PINID='DQ(2)';
NODE_NAME     J9U2 157
 '@BASEBOARD_FAB2_LIB.BASEBOARD_FAB2(SCH_1):PAGE82_I187@MSTR_SCONN.SCONN288_H44441003(CHIPS)':
 'DQ'<3>: CDS_PINID='DQ(3)';
NET_NAME
'M_J_DQ<40>'
 '@BASEBOARD_FAB2_LIB.BASEBOARD_FAB2(SCH_1):M_J_DQ'<40>:
 C_SIGNAL='@baseboard_fab2_lib.baseboard_fab2(sch_1):m_j_dq(40)';
NODE_NAME     U2D1 U34
 '@BASEBOARD_FAB2_LIB.BASEBOARD_FAB2(SCH_1):PAGE59_I172@CHPSET_LIB.SKX_EXT_B(CHIPS)':
 'DDR2_DQ'<40>: CDS_PINID='DDR2_DQ(40)';
NODE_NAME     J1G3 253
 '@BASEBOARD_FAB2_LIB.BASEBOARD_FAB2(SCH_1):PAGE81_I186@MSTR_SCONN.SCONN288_H44441004(CHIPS)':
 'DQ'<41>: CDS_PINID='DQ(41)';
NODE_NAME     J9U2 108
 '@BASEBOARD_FAB2_LIB.BASEBOARD_FAB2(SCH_1):PAGE82_I187@MSTR_SCONN.SCONN288_H44441003(CHIPS)':
 'DQ'<40>: CDS_PINID='DQ(40)';
NET_NAME
'M_J_DQ<41>'
 '@BASEBOARD_FAB2_LIB.BASEBOARD_FAB2(SCH_1):M_J_DQ'<41>:
 C_SIGNAL='@baseboard_fab2_lib.baseboard_fab2(sch_1):m_j_dq(41)';
NODE_NAME     U2D1 AA34
 '@BASEBOARD_FAB2_LIB.BASEBOARD_FAB2(SCH_1):PAGE59_I172@CHPSET_LIB.SKX_EXT_B(CHIPS)':
 'DDR2_DQ'<41>: CDS_PINID='DDR2_DQ(41)';
NODE_NAME     J1G3 108
 '@BASEBOARD_FAB2_LIB.BASEBOARD_FAB2(SCH_1):PAGE81_I186@MSTR_SCONN.SCONN288_H44441004(CHIPS)':
 'DQ'<40>: CDS_PINID='DQ(40)';
NODE_NAME     J9U2 253
 '@BASEBOARD_FAB2_LIB.BASEBOARD_FAB2(SCH_1):PAGE82_I187@MSTR_SCONN.SCONN288_H44441003(CHIPS)':
 'DQ'<41>: CDS_PINID='DQ(41)';
NET_NAME
'M_J_DQ<42>'
 '@BASEBOARD_FAB2_LIB.BASEBOARD_FAB2(SCH_1):M_J_DQ'<42>:
 C_SIGNAL='@baseboard_fab2_lib.baseboard_fab2(sch_1):m_j_dq(42)';
NODE_NAME     U2D1 V31
 '@BASEBOARD_FAB2_LIB.BASEBOARD_FAB2(SCH_1):PAGE59_I172@CHPSET_LIB.SKX_EXT_B(CHIPS)':
 'DDR2_DQ'<42>: CDS_PINID='DDR2_DQ(42)';
NODE_NAME     J1G3 260
 '@BASEBOARD_FAB2_LIB.BASEBOARD_FAB2(SCH_1):PAGE81_I186@MSTR_SCONN.SCONN288_H44441004(CHIPS)':
 'DQ'<43>: CDS_PINID='DQ(43)';
NODE_NAME     J9U2 115
 '@BASEBOARD_FAB2_LIB.BASEBOARD_FAB2(SCH_1):PAGE82_I187@MSTR_SCONN.SCONN288_H44441003(CHIPS)':
 'DQ'<42>: CDS_PINID='DQ(42)';
NET_NAME
'M_J_DQ<43>'
 '@BASEBOARD_FAB2_LIB.BASEBOARD_FAB2(SCH_1):M_J_DQ'<43>:
 C_SIGNAL='@baseboard_fab2_lib.baseboard_fab2(sch_1):m_j_dq(43)';
NODE_NAME     U2D1 Y31
 '@BASEBOARD_FAB2_LIB.BASEBOARD_FAB2(SCH_1):PAGE59_I172@CHPSET_LIB.SKX_EXT_B(CHIPS)':
 'DDR2_DQ'<43>: CDS_PINID='DDR2_DQ(43)';
NODE_NAME     J1G3 115
 '@BASEBOARD_FAB2_LIB.BASEBOARD_FAB2(SCH_1):PAGE81_I186@MSTR_SCONN.SCONN288_H44441004(CHIPS)':
 'DQ'<42>: CDS_PINID='DQ(42)';
NODE_NAME     J9U2 260
 '@BASEBOARD_FAB2_LIB.BASEBOARD_FAB2(SCH_1):PAGE82_I187@MSTR_SCONN.SCONN288_H44441003(CHIPS)':
 'DQ'<43>: CDS_PINID='DQ(43)';
NET_NAME
'M_J_DQ<44>'
 '@BASEBOARD_FAB2_LIB.BASEBOARD_FAB2(SCH_1):M_J_DQ'<44>:
 C_SIGNAL='@baseboard_fab2_lib.baseboard_fab2(sch_1):m_j_dq(44)';
NODE_NAME     U2D1 V35
 '@BASEBOARD_FAB2_LIB.BASEBOARD_FAB2(SCH_1):PAGE59_I172@CHPSET_LIB.SKX_EXT_B(CHIPS)':
 'DDR2_DQ'<44>: CDS_PINID='DDR2_DQ(44)';
NODE_NAME     J1G3 251
 '@BASEBOARD_FAB2_LIB.BASEBOARD_FAB2(SCH_1):PAGE81_I186@MSTR_SCONN.SCONN288_H44441004(CHIPS)':
 'DQ'<45>: CDS_PINID='DQ(45)';
NODE_NAME     J9U2 106
 '@BASEBOARD_FAB2_LIB.BASEBOARD_FAB2(SCH_1):PAGE82_I187@MSTR_SCONN.SCONN288_H44441003(CHIPS)':
 'DQ'<44>: CDS_PINID='DQ(44)';
NET_NAME
'M_J_DQ<45>'
 '@BASEBOARD_FAB2_LIB.BASEBOARD_FAB2(SCH_1):M_J_DQ'<45>:
 C_SIGNAL='@baseboard_fab2_lib.baseboard_fab2(sch_1):m_j_dq(45)';
NODE_NAME     U2D1 Y35
 '@BASEBOARD_FAB2_LIB.BASEBOARD_FAB2(SCH_1):PAGE59_I172@CHPSET_LIB.SKX_EXT_B(CHIPS)':
 'DDR2_DQ'<45>: CDS_PINID='DDR2_DQ(45)';
NODE_NAME     J1G3 106
 '@BASEBOARD_FAB2_LIB.BASEBOARD_FAB2(SCH_1):PAGE81_I186@MSTR_SCONN.SCONN288_H44441004(CHIPS)':
 'DQ'<44>: CDS_PINID='DQ(44)';
NODE_NAME     J9U2 251
 '@BASEBOARD_FAB2_LIB.BASEBOARD_FAB2(SCH_1):PAGE82_I187@MSTR_SCONN.SCONN288_H44441003(CHIPS)':
 'DQ'<45>: CDS_PINID='DQ(45)';
NET_NAME
'M_J_DQ<46>'
 '@BASEBOARD_FAB2_LIB.BASEBOARD_FAB2(SCH_1):M_J_DQ'<46>:
 C_SIGNAL='@baseboard_fab2_lib.baseboard_fab2(sch_1):m_j_dq(46)';
NODE_NAME     U2D1 U32
 '@BASEBOARD_FAB2_LIB.BASEBOARD_FAB2(SCH_1):PAGE59_I172@CHPSET_LIB.SKX_EXT_B(CHIPS)':
 'DDR2_DQ'<46>: CDS_PINID='DDR2_DQ(46)';
NODE_NAME     J1G3 258
 '@BASEBOARD_FAB2_LIB.BASEBOARD_FAB2(SCH_1):PAGE81_I186@MSTR_SCONN.SCONN288_H44441004(CHIPS)':
 'DQ'<47>: CDS_PINID='DQ(47)';
NODE_NAME     J9U2 113
 '@BASEBOARD_FAB2_LIB.BASEBOARD_FAB2(SCH_1):PAGE82_I187@MSTR_SCONN.SCONN288_H44441003(CHIPS)':
 'DQ'<46>: CDS_PINID='DQ(46)';
NET_NAME
'M_J_DQ<47>'
 '@BASEBOARD_FAB2_LIB.BASEBOARD_FAB2(SCH_1):M_J_DQ'<47>:
 C_SIGNAL='@baseboard_fab2_lib.baseboard_fab2(sch_1):m_j_dq(47)';
NODE_NAME     U2D1 AA32
 '@BASEBOARD_FAB2_LIB.BASEBOARD_FAB2(SCH_1):PAGE59_I172@CHPSET_LIB.SKX_EXT_B(CHIPS)':
 'DDR2_DQ'<47>: CDS_PINID='DDR2_DQ(47)';
NODE_NAME     J1G3 113
 '@BASEBOARD_FAB2_LIB.BASEBOARD_FAB2(SCH_1):PAGE81_I186@MSTR_SCONN.SCONN288_H44441004(CHIPS)':
 'DQ'<46>: CDS_PINID='DQ(46)';
NODE_NAME     J9U2 258
 '@BASEBOARD_FAB2_LIB.BASEBOARD_FAB2(SCH_1):PAGE82_I187@MSTR_SCONN.SCONN288_H44441003(CHIPS)':
 'DQ'<47>: CDS_PINID='DQ(47)';
NET_NAME
'M_J_DQ<48>'
 '@BASEBOARD_FAB2_LIB.BASEBOARD_FAB2(SCH_1):M_J_DQ'<48>:
 C_SIGNAL='@baseboard_fab2_lib.baseboard_fab2(sch_1):m_j_dq(48)';
NODE_NAME     U2D1 AD31
 '@BASEBOARD_FAB2_LIB.BASEBOARD_FAB2(SCH_1):PAGE59_I172@CHPSET_LIB.SKX_EXT_B(CHIPS)':
 'DDR2_DQ'<48>: CDS_PINID='DDR2_DQ(48)';
NODE_NAME     J1G3 264
 '@BASEBOARD_FAB2_LIB.BASEBOARD_FAB2(SCH_1):PAGE81_I186@MSTR_SCONN.SCONN288_H44441004(CHIPS)':
 'DQ'<49>: CDS_PINID='DQ(49)';
NODE_NAME     J9U2 119
 '@BASEBOARD_FAB2_LIB.BASEBOARD_FAB2(SCH_1):PAGE82_I187@MSTR_SCONN.SCONN288_H44441003(CHIPS)':
 'DQ'<48>: CDS_PINID='DQ(48)';
NET_NAME
'M_J_DQ<49>'
 '@BASEBOARD_FAB2_LIB.BASEBOARD_FAB2(SCH_1):M_J_DQ'<49>:
 C_SIGNAL='@baseboard_fab2_lib.baseboard_fab2(sch_1):m_j_dq(49)';
NODE_NAME     U2D1 AH31
 '@BASEBOARD_FAB2_LIB.BASEBOARD_FAB2(SCH_1):PAGE59_I172@CHPSET_LIB.SKX_EXT_B(CHIPS)':
 'DDR2_DQ'<49>: CDS_PINID='DDR2_DQ(49)';
NODE_NAME     J1G3 119
 '@BASEBOARD_FAB2_LIB.BASEBOARD_FAB2(SCH_1):PAGE81_I186@MSTR_SCONN.SCONN288_H44441004(CHIPS)':
 'DQ'<48>: CDS_PINID='DQ(48)';
NODE_NAME     J9U2 264
 '@BASEBOARD_FAB2_LIB.BASEBOARD_FAB2(SCH_1):PAGE82_I187@MSTR_SCONN.SCONN288_H44441003(CHIPS)':
 'DQ'<49>: CDS_PINID='DQ(49)';
NET_NAME
'M_J_DQ<4>'
 '@BASEBOARD_FAB2_LIB.BASEBOARD_FAB2(SCH_1):M_J_DQ'<4>:
 C_SIGNAL='@baseboard_fab2_lib.baseboard_fab2(sch_1):m_j_dq(4)';
NODE_NAME     U2D1 AT75
 '@BASEBOARD_FAB2_LIB.BASEBOARD_FAB2(SCH_1):PAGE59_I172@CHPSET_LIB.SKX_EXT_B(CHIPS)':
 'DDR2_DQ'<4>: CDS_PINID='DDR2_DQ(4)';
NODE_NAME     J1G3 148
 '@BASEBOARD_FAB2_LIB.BASEBOARD_FAB2(SCH_1):PAGE81_I186@MSTR_SCONN.SCONN288_H44441004(CHIPS)':
 'DQ'<5>: CDS_PINID='DQ(5)';
NODE_NAME     J9U2 3
 '@BASEBOARD_FAB2_LIB.BASEBOARD_FAB2(SCH_1):PAGE82_I187@MSTR_SCONN.SCONN288_H44441003(CHIPS)':
 'DQ'<4>: CDS_PINID='DQ(4)';
NET_NAME
'M_J_DQ<50>'
 '@BASEBOARD_FAB2_LIB.BASEBOARD_FAB2(SCH_1):M_J_DQ'<50>:
 C_SIGNAL='@baseboard_fab2_lib.baseboard_fab2(sch_1):m_j_dq(50)';
NODE_NAME     U2D1 AE28
 '@BASEBOARD_FAB2_LIB.BASEBOARD_FAB2(SCH_1):PAGE59_I172@CHPSET_LIB.SKX_EXT_B(CHIPS)':
 'DDR2_DQ'<50>: CDS_PINID='DDR2_DQ(50)';
NODE_NAME     J1G3 271
 '@BASEBOARD_FAB2_LIB.BASEBOARD_FAB2(SCH_1):PAGE81_I186@MSTR_SCONN.SCONN288_H44441004(CHIPS)':
 'DQ'<51>: CDS_PINID='DQ(51)';
NODE_NAME     J9U2 126
 '@BASEBOARD_FAB2_LIB.BASEBOARD_FAB2(SCH_1):PAGE82_I187@MSTR_SCONN.SCONN288_H44441003(CHIPS)':
 'DQ'<50>: CDS_PINID='DQ(50)';
NET_NAME
'M_J_DQ<51>'
 '@BASEBOARD_FAB2_LIB.BASEBOARD_FAB2(SCH_1):M_J_DQ'<51>:
 C_SIGNAL='@baseboard_fab2_lib.baseboard_fab2(sch_1):m_j_dq(51)';
NODE_NAME     U2D1 AG28
 '@BASEBOARD_FAB2_LIB.BASEBOARD_FAB2(SCH_1):PAGE59_I172@CHPSET_LIB.SKX_EXT_B(CHIPS)':
 'DDR2_DQ'<51>: CDS_PINID='DDR2_DQ(51)';
NODE_NAME     J1G3 126
 '@BASEBOARD_FAB2_LIB.BASEBOARD_FAB2(SCH_1):PAGE81_I186@MSTR_SCONN.SCONN288_H44441004(CHIPS)':
 'DQ'<50>: CDS_PINID='DQ(50)';
NODE_NAME     J9U2 271
 '@BASEBOARD_FAB2_LIB.BASEBOARD_FAB2(SCH_1):PAGE82_I187@MSTR_SCONN.SCONN288_H44441003(CHIPS)':
 'DQ'<51>: CDS_PINID='DQ(51)';
NET_NAME
'M_J_DQ<52>'
 '@BASEBOARD_FAB2_LIB.BASEBOARD_FAB2(SCH_1):M_J_DQ'<52>:
 C_SIGNAL='@baseboard_fab2_lib.baseboard_fab2(sch_1):m_j_dq(52)';
NODE_NAME     U2D1 AE32
 '@BASEBOARD_FAB2_LIB.BASEBOARD_FAB2(SCH_1):PAGE59_I172@CHPSET_LIB.SKX_EXT_B(CHIPS)':
 'DDR2_DQ'<52>: CDS_PINID='DDR2_DQ(52)';
NODE_NAME     J1G3 262
 '@BASEBOARD_FAB2_LIB.BASEBOARD_FAB2(SCH_1):PAGE81_I186@MSTR_SCONN.SCONN288_H44441004(CHIPS)':
 'DQ'<53>: CDS_PINID='DQ(53)';
NODE_NAME     J9U2 117
 '@BASEBOARD_FAB2_LIB.BASEBOARD_FAB2(SCH_1):PAGE82_I187@MSTR_SCONN.SCONN288_H44441003(CHIPS)':
 'DQ'<52>: CDS_PINID='DQ(52)';
NET_NAME
'M_J_DQ<53>'
 '@BASEBOARD_FAB2_LIB.BASEBOARD_FAB2(SCH_1):M_J_DQ'<53>:
 C_SIGNAL='@baseboard_fab2_lib.baseboard_fab2(sch_1):m_j_dq(53)';
NODE_NAME     U2D1 AG32
 '@BASEBOARD_FAB2_LIB.BASEBOARD_FAB2(SCH_1):PAGE59_I172@CHPSET_LIB.SKX_EXT_B(CHIPS)':
 'DDR2_DQ'<53>: CDS_PINID='DDR2_DQ(53)';
NODE_NAME     J1G3 117
 '@BASEBOARD_FAB2_LIB.BASEBOARD_FAB2(SCH_1):PAGE81_I186@MSTR_SCONN.SCONN288_H44441004(CHIPS)':
 'DQ'<52>: CDS_PINID='DQ(52)';
NODE_NAME     J9U2 262
 '@BASEBOARD_FAB2_LIB.BASEBOARD_FAB2(SCH_1):PAGE82_I187@MSTR_SCONN.SCONN288_H44441003(CHIPS)':
 'DQ'<53>: CDS_PINID='DQ(53)';
NET_NAME
'M_J_DQ<54>'
 '@BASEBOARD_FAB2_LIB.BASEBOARD_FAB2(SCH_1):M_J_DQ'<54>:
 C_SIGNAL='@baseboard_fab2_lib.baseboard_fab2(sch_1):m_j_dq(54)';
NODE_NAME     U2D1 AD29
 '@BASEBOARD_FAB2_LIB.BASEBOARD_FAB2(SCH_1):PAGE59_I172@CHPSET_LIB.SKX_EXT_B(CHIPS)':
 'DDR2_DQ'<54>: CDS_PINID='DDR2_DQ(54)';
NODE_NAME     J1G3 269
 '@BASEBOARD_FAB2_LIB.BASEBOARD_FAB2(SCH_1):PAGE81_I186@MSTR_SCONN.SCONN288_H44441004(CHIPS)':
 'DQ'<55>: CDS_PINID='DQ(55)';
NODE_NAME     J9U2 124
 '@BASEBOARD_FAB2_LIB.BASEBOARD_FAB2(SCH_1):PAGE82_I187@MSTR_SCONN.SCONN288_H44441003(CHIPS)':
 'DQ'<54>: CDS_PINID='DQ(54)';
NET_NAME
'M_J_DQ<55>'
 '@BASEBOARD_FAB2_LIB.BASEBOARD_FAB2(SCH_1):M_J_DQ'<55>:
 C_SIGNAL='@baseboard_fab2_lib.baseboard_fab2(sch_1):m_j_dq(55)';
NODE_NAME     U2D1 AH29
 '@BASEBOARD_FAB2_LIB.BASEBOARD_FAB2(SCH_1):PAGE59_I172@CHPSET_LIB.SKX_EXT_B(CHIPS)':
 'DDR2_DQ'<55>: CDS_PINID='DDR2_DQ(55)';
NODE_NAME     J1G3 124
 '@BASEBOARD_FAB2_LIB.BASEBOARD_FAB2(SCH_1):PAGE81_I186@MSTR_SCONN.SCONN288_H44441004(CHIPS)':
 'DQ'<54>: CDS_PINID='DQ(54)';
NODE_NAME     J9U2 269
 '@BASEBOARD_FAB2_LIB.BASEBOARD_FAB2(SCH_1):PAGE82_I187@MSTR_SCONN.SCONN288_H44441003(CHIPS)':
 'DQ'<55>: CDS_PINID='DQ(55)';
NET_NAME
'M_J_DQ<56>'
 '@BASEBOARD_FAB2_LIB.BASEBOARD_FAB2(SCH_1):M_J_DQ'<56>:
 C_SIGNAL='@baseboard_fab2_lib.baseboard_fab2(sch_1):m_j_dq(56)';
NODE_NAME     U2D1 AD25
 '@BASEBOARD_FAB2_LIB.BASEBOARD_FAB2(SCH_1):PAGE59_I172@CHPSET_LIB.SKX_EXT_B(CHIPS)':
 'DDR2_DQ'<56>: CDS_PINID='DDR2_DQ(56)';
NODE_NAME     J1G3 275
 '@BASEBOARD_FAB2_LIB.BASEBOARD_FAB2(SCH_1):PAGE81_I186@MSTR_SCONN.SCONN288_H44441004(CHIPS)':
 'DQ'<57>: CDS_PINID='DQ(57)';
NODE_NAME     J9U2 130
 '@BASEBOARD_FAB2_LIB.BASEBOARD_FAB2(SCH_1):PAGE82_I187@MSTR_SCONN.SCONN288_H44441003(CHIPS)':
 'DQ'<56>: CDS_PINID='DQ(56)';
NET_NAME
'M_J_DQ<57>'
 '@BASEBOARD_FAB2_LIB.BASEBOARD_FAB2(SCH_1):M_J_DQ'<57>:
 C_SIGNAL='@baseboard_fab2_lib.baseboard_fab2(sch_1):m_j_dq(57)';
NODE_NAME     U2D1 AH25
 '@BASEBOARD_FAB2_LIB.BASEBOARD_FAB2(SCH_1):PAGE59_I172@CHPSET_LIB.SKX_EXT_B(CHIPS)':
 'DDR2_DQ'<57>: CDS_PINID='DDR2_DQ(57)';
NODE_NAME     J1G3 130
 '@BASEBOARD_FAB2_LIB.BASEBOARD_FAB2(SCH_1):PAGE81_I186@MSTR_SCONN.SCONN288_H44441004(CHIPS)':
 'DQ'<56>: CDS_PINID='DQ(56)';
NODE_NAME     J9U2 275
 '@BASEBOARD_FAB2_LIB.BASEBOARD_FAB2(SCH_1):PAGE82_I187@MSTR_SCONN.SCONN288_H44441003(CHIPS)':
 'DQ'<57>: CDS_PINID='DQ(57)';
NET_NAME
'M_J_DQ<58>'
 '@BASEBOARD_FAB2_LIB.BASEBOARD_FAB2(SCH_1):M_J_DQ'<58>:
 C_SIGNAL='@baseboard_fab2_lib.baseboard_fab2(sch_1):m_j_dq(58)';
NODE_NAME     U2D1 AE22
 '@BASEBOARD_FAB2_LIB.BASEBOARD_FAB2(SCH_1):PAGE59_I172@CHPSET_LIB.SKX_EXT_B(CHIPS)':
 'DDR2_DQ'<58>: CDS_PINID='DDR2_DQ(58)';
NODE_NAME     J1G3 282
 '@BASEBOARD_FAB2_LIB.BASEBOARD_FAB2(SCH_1):PAGE81_I186@MSTR_SCONN.SCONN288_H44441004(CHIPS)':
 'DQ'<59>: CDS_PINID='DQ(59)';
NODE_NAME     J9U2 137
 '@BASEBOARD_FAB2_LIB.BASEBOARD_FAB2(SCH_1):PAGE82_I187@MSTR_SCONN.SCONN288_H44441003(CHIPS)':
 'DQ'<58>: CDS_PINID='DQ(58)';
NET_NAME
'M_J_DQ<59>'
 '@BASEBOARD_FAB2_LIB.BASEBOARD_FAB2(SCH_1):M_J_DQ'<59>:
 C_SIGNAL='@baseboard_fab2_lib.baseboard_fab2(sch_1):m_j_dq(59)';
NODE_NAME     U2D1 AG22
 '@BASEBOARD_FAB2_LIB.BASEBOARD_FAB2(SCH_1):PAGE59_I172@CHPSET_LIB.SKX_EXT_B(CHIPS)':
 'DDR2_DQ'<59>: CDS_PINID='DDR2_DQ(59)';
NODE_NAME     J1G3 137
 '@BASEBOARD_FAB2_LIB.BASEBOARD_FAB2(SCH_1):PAGE81_I186@MSTR_SCONN.SCONN288_H44441004(CHIPS)':
 'DQ'<58>: CDS_PINID='DQ(58)';
NODE_NAME     J9U2 282
 '@BASEBOARD_FAB2_LIB.BASEBOARD_FAB2(SCH_1):PAGE82_I187@MSTR_SCONN.SCONN288_H44441003(CHIPS)':
 'DQ'<59>: CDS_PINID='DQ(59)';
NET_NAME
'M_J_DQ<5>'
 '@BASEBOARD_FAB2_LIB.BASEBOARD_FAB2(SCH_1):M_J_DQ'<5>:
 C_SIGNAL='@baseboard_fab2_lib.baseboard_fab2(sch_1):m_j_dq(5)';
NODE_NAME     U2D1 AR74
 '@BASEBOARD_FAB2_LIB.BASEBOARD_FAB2(SCH_1):PAGE59_I172@CHPSET_LIB.SKX_EXT_B(CHIPS)':
 'DDR2_DQ'<5>: CDS_PINID='DDR2_DQ(5)';
NODE_NAME     J1G3 3
 '@BASEBOARD_FAB2_LIB.BASEBOARD_FAB2(SCH_1):PAGE81_I186@MSTR_SCONN.SCONN288_H44441004(CHIPS)':
 'DQ'<4>: CDS_PINID='DQ(4)';
NODE_NAME     J9U2 148
 '@BASEBOARD_FAB2_LIB.BASEBOARD_FAB2(SCH_1):PAGE82_I187@MSTR_SCONN.SCONN288_H44441003(CHIPS)':
 'DQ'<5>: CDS_PINID='DQ(5)';
NET_NAME
'M_J_DQ<60>'
 '@BASEBOARD_FAB2_LIB.BASEBOARD_FAB2(SCH_1):M_J_DQ'<60>:
 C_SIGNAL='@baseboard_fab2_lib.baseboard_fab2(sch_1):m_j_dq(60)';
NODE_NAME     U2D1 AE26
 '@BASEBOARD_FAB2_LIB.BASEBOARD_FAB2(SCH_1):PAGE59_I172@CHPSET_LIB.SKX_EXT_B(CHIPS)':
 'DDR2_DQ'<60>: CDS_PINID='DDR2_DQ(60)';
NODE_NAME     J1G3 273
 '@BASEBOARD_FAB2_LIB.BASEBOARD_FAB2(SCH_1):PAGE81_I186@MSTR_SCONN.SCONN288_H44441004(CHIPS)':
 'DQ'<61>: CDS_PINID='DQ(61)';
NODE_NAME     J9U2 128
 '@BASEBOARD_FAB2_LIB.BASEBOARD_FAB2(SCH_1):PAGE82_I187@MSTR_SCONN.SCONN288_H44441003(CHIPS)':
 'DQ'<60>: CDS_PINID='DQ(60)';
NET_NAME
'M_J_DQ<61>'
 '@BASEBOARD_FAB2_LIB.BASEBOARD_FAB2(SCH_1):M_J_DQ'<61>:
 C_SIGNAL='@baseboard_fab2_lib.baseboard_fab2(sch_1):m_j_dq(61)';
NODE_NAME     U2D1 AG26
 '@BASEBOARD_FAB2_LIB.BASEBOARD_FAB2(SCH_1):PAGE59_I172@CHPSET_LIB.SKX_EXT_B(CHIPS)':
 'DDR2_DQ'<61>: CDS_PINID='DDR2_DQ(61)';
NODE_NAME     J1G3 128
 '@BASEBOARD_FAB2_LIB.BASEBOARD_FAB2(SCH_1):PAGE81_I186@MSTR_SCONN.SCONN288_H44441004(CHIPS)':
 'DQ'<60>: CDS_PINID='DQ(60)';
NODE_NAME     J9U2 273
 '@BASEBOARD_FAB2_LIB.BASEBOARD_FAB2(SCH_1):PAGE82_I187@MSTR_SCONN.SCONN288_H44441003(CHIPS)':
 'DQ'<61>: CDS_PINID='DQ(61)';
NET_NAME
'M_J_DQ<62>'
 '@BASEBOARD_FAB2_LIB.BASEBOARD_FAB2(SCH_1):M_J_DQ'<62>:
 C_SIGNAL='@baseboard_fab2_lib.baseboard_fab2(sch_1):m_j_dq(62)';
NODE_NAME     U2D1 AD23
 '@BASEBOARD_FAB2_LIB.BASEBOARD_FAB2(SCH_1):PAGE59_I172@CHPSET_LIB.SKX_EXT_B(CHIPS)':
 'DDR2_DQ'<62>: CDS_PINID='DDR2_DQ(62)';
NODE_NAME     J1G3 280
 '@BASEBOARD_FAB2_LIB.BASEBOARD_FAB2(SCH_1):PAGE81_I186@MSTR_SCONN.SCONN288_H44441004(CHIPS)':
 'DQ'<63>: CDS_PINID='DQ(63)';
NODE_NAME     J9U2 135
 '@BASEBOARD_FAB2_LIB.BASEBOARD_FAB2(SCH_1):PAGE82_I187@MSTR_SCONN.SCONN288_H44441003(CHIPS)':
 'DQ'<62>: CDS_PINID='DQ(62)';
NET_NAME
'M_J_DQ<63>'
 '@BASEBOARD_FAB2_LIB.BASEBOARD_FAB2(SCH_1):M_J_DQ'<63>:
 C_SIGNAL='@baseboard_fab2_lib.baseboard_fab2(sch_1):m_j_dq(63)';
NODE_NAME     U2D1 AH23
 '@BASEBOARD_FAB2_LIB.BASEBOARD_FAB2(SCH_1):PAGE59_I172@CHPSET_LIB.SKX_EXT_B(CHIPS)':
 'DDR2_DQ'<63>: CDS_PINID='DDR2_DQ(63)';
NODE_NAME     J1G3 135
 '@BASEBOARD_FAB2_LIB.BASEBOARD_FAB2(SCH_1):PAGE81_I186@MSTR_SCONN.SCONN288_H44441004(CHIPS)':
 'DQ'<62>: CDS_PINID='DQ(62)';
NODE_NAME     J9U2 280
 '@BASEBOARD_FAB2_LIB.BASEBOARD_FAB2(SCH_1):PAGE82_I187@MSTR_SCONN.SCONN288_H44441003(CHIPS)':
 'DQ'<63>: CDS_PINID='DQ(63)';
NET_NAME
'M_J_DQ<6>'
 '@BASEBOARD_FAB2_LIB.BASEBOARD_FAB2(SCH_1):M_J_DQ'<6>:
 C_SIGNAL='@baseboard_fab2_lib.baseboard_fab2(sch_1):m_j_dq(6)';
NODE_NAME     U2D1 AM77
 '@BASEBOARD_FAB2_LIB.BASEBOARD_FAB2(SCH_1):PAGE59_I172@CHPSET_LIB.SKX_EXT_B(CHIPS)':
 'DDR2_DQ'<6>: CDS_PINID='DDR2_DQ(6)';
NODE_NAME     J1G3 155
 '@BASEBOARD_FAB2_LIB.BASEBOARD_FAB2(SCH_1):PAGE81_I186@MSTR_SCONN.SCONN288_H44441004(CHIPS)':
 'DQ'<7>: CDS_PINID='DQ(7)';
NODE_NAME     J9U2 10
 '@BASEBOARD_FAB2_LIB.BASEBOARD_FAB2(SCH_1):PAGE82_I187@MSTR_SCONN.SCONN288_H44441003(CHIPS)':
 'DQ'<6>: CDS_PINID='DQ(6)';
NET_NAME
'M_J_DQ<7>'
 '@BASEBOARD_FAB2_LIB.BASEBOARD_FAB2(SCH_1):M_J_DQ'<7>:
 C_SIGNAL='@baseboard_fab2_lib.baseboard_fab2(sch_1):m_j_dq(7)';
NODE_NAME     U2D1 AK75
 '@BASEBOARD_FAB2_LIB.BASEBOARD_FAB2(SCH_1):PAGE59_I172@CHPSET_LIB.SKX_EXT_B(CHIPS)':
 'DDR2_DQ'<7>: CDS_PINID='DDR2_DQ(7)';
NODE_NAME     J1G3 10
 '@BASEBOARD_FAB2_LIB.BASEBOARD_FAB2(SCH_1):PAGE81_I186@MSTR_SCONN.SCONN288_H44441004(CHIPS)':
 'DQ'<6>: CDS_PINID='DQ(6)';
NODE_NAME     J9U2 155
 '@BASEBOARD_FAB2_LIB.BASEBOARD_FAB2(SCH_1):PAGE82_I187@MSTR_SCONN.SCONN288_H44441003(CHIPS)':
 'DQ'<7>: CDS_PINID='DQ(7)';
NET_NAME
'M_J_DQ<8>'
 '@BASEBOARD_FAB2_LIB.BASEBOARD_FAB2(SCH_1):M_J_DQ'<8>:
 C_SIGNAL='@baseboard_fab2_lib.baseboard_fab2(sch_1):m_j_dq(8)';
NODE_NAME     U2D1 AE76
 '@BASEBOARD_FAB2_LIB.BASEBOARD_FAB2(SCH_1):PAGE59_I172@CHPSET_LIB.SKX_EXT_B(CHIPS)':
 'DDR2_DQ'<8>: CDS_PINID='DDR2_DQ(8)';
NODE_NAME     J1G3 161
 '@BASEBOARD_FAB2_LIB.BASEBOARD_FAB2(SCH_1):PAGE81_I186@MSTR_SCONN.SCONN288_H44441004(CHIPS)':
 'DQ'<9>: CDS_PINID='DQ(9)';
NODE_NAME     J9U2 16
 '@BASEBOARD_FAB2_LIB.BASEBOARD_FAB2(SCH_1):PAGE82_I187@MSTR_SCONN.SCONN288_H44441003(CHIPS)':
 'DQ'<8>: CDS_PINID='DQ(8)';
NET_NAME
'M_J_DQ<9>'
 '@BASEBOARD_FAB2_LIB.BASEBOARD_FAB2(SCH_1):M_J_DQ'<9>:
 C_SIGNAL='@baseboard_fab2_lib.baseboard_fab2(sch_1):m_j_dq(9)';
NODE_NAME     U2D1 AC74
 '@BASEBOARD_FAB2_LIB.BASEBOARD_FAB2(SCH_1):PAGE59_I172@CHPSET_LIB.SKX_EXT_B(CHIPS)':
 'DDR2_DQ'<9>: CDS_PINID='DDR2_DQ(9)';
NODE_NAME     J1G3 16
 '@BASEBOARD_FAB2_LIB.BASEBOARD_FAB2(SCH_1):PAGE81_I186@MSTR_SCONN.SCONN288_H44441004(CHIPS)':
 'DQ'<8>: CDS_PINID='DQ(8)';
NODE_NAME     J9U2 161
 '@BASEBOARD_FAB2_LIB.BASEBOARD_FAB2(SCH_1):PAGE82_I187@MSTR_SCONN.SCONN288_H44441003(CHIPS)':
 'DQ'<9>: CDS_PINID='DQ(9)';
NET_NAME
'M_J_DQS_DN<0>'
 '@BASEBOARD_FAB2_LIB.BASEBOARD_FAB2(SCH_1):M_J_DQS_DN'<0>:
 C_SIGNAL='@baseboard_fab2_lib.baseboard_fab2(sch_1):m_j_dqs_dn(0)';
NODE_NAME     U2D1 AL74
 '@BASEBOARD_FAB2_LIB.BASEBOARD_FAB2(SCH_1):PAGE59_I172@CHPSET_LIB.SKX_EXT_B(CHIPS)':
 'DDR2_DQS_DN'<0>: CDS_PINID='DDR2_DQS_DN(0)';
NODE_NAME     J1G3 152
 '@BASEBOARD_FAB2_LIB.BASEBOARD_FAB2(SCH_1):PAGE81_I67@MSTR_SCONN.SCONN288_H44441004(CHIPS)':
 'DQS0N': CDS_PINID='DQS0N';
NODE_NAME     J9U2 152
 '@BASEBOARD_FAB2_LIB.BASEBOARD_FAB2(SCH_1):PAGE82_I64@MSTR_SCONN.SCONN288_H44441003(CHIPS)':
 'DQS0N': CDS_PINID='DQS0N';
NET_NAME
'M_J_DQS_DN<10>'
 '@BASEBOARD_FAB2_LIB.BASEBOARD_FAB2(SCH_1):M_J_DQS_DN'<10>:
 C_SIGNAL='@baseboard_fab2_lib.baseboard_fab2(sch_1):m_j_dqs_dn(10)';
NODE_NAME     U2D1 AD77
 '@BASEBOARD_FAB2_LIB.BASEBOARD_FAB2(SCH_1):PAGE59_I172@CHPSET_LIB.SKX_EXT_B(CHIPS)':
 'DDR2_DQS_DN'<10>: CDS_PINID='DDR2_DQS_DN(10)';
NODE_NAME     J1G3 19
 '@BASEBOARD_FAB2_LIB.BASEBOARD_FAB2(SCH_1):PAGE81_I67@MSTR_SCONN.SCONN288_H44441004(CHIPS)':
 'DQS10N': CDS_PINID='DQS10N';
NODE_NAME     J9U2 19
 '@BASEBOARD_FAB2_LIB.BASEBOARD_FAB2(SCH_1):PAGE82_I64@MSTR_SCONN.SCONN288_H44441003(CHIPS)':
 'DQS10N': CDS_PINID='DQS10N';
NET_NAME
'M_J_DQS_DN<11>'
 '@BASEBOARD_FAB2_LIB.BASEBOARD_FAB2(SCH_1):M_J_DQS_DN'<11>:
 C_SIGNAL='@baseboard_fab2_lib.baseboard_fab2(sch_1):m_j_dqs_dn(11)';
NODE_NAME     U2D1 U72
 '@BASEBOARD_FAB2_LIB.BASEBOARD_FAB2(SCH_1):PAGE59_I172@CHPSET_LIB.SKX_EXT_B(CHIPS)':
 'DDR2_DQS_DN'<11>: CDS_PINID='DDR2_DQS_DN(11)';
NODE_NAME     J1G3 30
 '@BASEBOARD_FAB2_LIB.BASEBOARD_FAB2(SCH_1):PAGE81_I67@MSTR_SCONN.SCONN288_H44441004(CHIPS)':
 'DQS11N': CDS_PINID='DQS11N';
NODE_NAME     J9U2 30
 '@BASEBOARD_FAB2_LIB.BASEBOARD_FAB2(SCH_1):PAGE82_I64@MSTR_SCONN.SCONN288_H44441003(CHIPS)':
 'DQS11N': CDS_PINID='DQS11N';
NET_NAME
'M_J_DQS_DN<12>'
 '@BASEBOARD_FAB2_LIB.BASEBOARD_FAB2(SCH_1):M_J_DQS_DN'<12>:
 C_SIGNAL='@baseboard_fab2_lib.baseboard_fab2(sch_1):m_j_dqs_dn(12)';
NODE_NAME     U2D1 AL66
 '@BASEBOARD_FAB2_LIB.BASEBOARD_FAB2(SCH_1):PAGE59_I172@CHPSET_LIB.SKX_EXT_B(CHIPS)':
 'DDR2_DQS_DN'<12>: CDS_PINID='DDR2_DQS_DN(12)';
NODE_NAME     J1G3 41
 '@BASEBOARD_FAB2_LIB.BASEBOARD_FAB2(SCH_1):PAGE81_I67@MSTR_SCONN.SCONN288_H44441004(CHIPS)':
 'DQS12N': CDS_PINID='DQS12N';
NODE_NAME     J9U2 41
 '@BASEBOARD_FAB2_LIB.BASEBOARD_FAB2(SCH_1):PAGE82_I64@MSTR_SCONN.SCONN288_H44441003(CHIPS)':
 'DQS12N': CDS_PINID='DQS12N';
NET_NAME
'M_J_DQS_DN<13>'
 '@BASEBOARD_FAB2_LIB.BASEBOARD_FAB2(SCH_1):M_J_DQS_DN'<13>:
 C_SIGNAL='@baseboard_fab2_lib.baseboard_fab2(sch_1):m_j_dqs_dn(13)';
NODE_NAME     U2D1 T39
 '@BASEBOARD_FAB2_LIB.BASEBOARD_FAB2(SCH_1):PAGE59_I172@CHPSET_LIB.SKX_EXT_B(CHIPS)':
 'DDR2_DQS_DN'<13>: CDS_PINID='DDR2_DQS_DN(13)';
NODE_NAME     J1G3 100
 '@BASEBOARD_FAB2_LIB.BASEBOARD_FAB2(SCH_1):PAGE81_I67@MSTR_SCONN.SCONN288_H44441004(CHIPS)':
 'DQS13N': CDS_PINID='DQS13N';
NODE_NAME     J9U2 100
 '@BASEBOARD_FAB2_LIB.BASEBOARD_FAB2(SCH_1):PAGE82_I64@MSTR_SCONN.SCONN288_H44441003(CHIPS)':
 'DQS13N': CDS_PINID='DQS13N';
NET_NAME
'M_J_DQS_DN<14>'
 '@BASEBOARD_FAB2_LIB.BASEBOARD_FAB2(SCH_1):M_J_DQS_DN'<14>:
 C_SIGNAL='@baseboard_fab2_lib.baseboard_fab2(sch_1):m_j_dqs_dn(14)';
NODE_NAME     U2D1 T33
 '@BASEBOARD_FAB2_LIB.BASEBOARD_FAB2(SCH_1):PAGE59_I172@CHPSET_LIB.SKX_EXT_B(CHIPS)':
 'DDR2_DQS_DN'<14>: CDS_PINID='DDR2_DQS_DN(14)';
NODE_NAME     J1G3 111
 '@BASEBOARD_FAB2_LIB.BASEBOARD_FAB2(SCH_1):PAGE81_I67@MSTR_SCONN.SCONN288_H44441004(CHIPS)':
 'DQS14N': CDS_PINID='DQS14N';
NODE_NAME     J9U2 111
 '@BASEBOARD_FAB2_LIB.BASEBOARD_FAB2(SCH_1):PAGE82_I64@MSTR_SCONN.SCONN288_H44441003(CHIPS)':
 'DQS14N': CDS_PINID='DQS14N';
NET_NAME
'M_J_DQS_DN<15>'
 '@BASEBOARD_FAB2_LIB.BASEBOARD_FAB2(SCH_1):M_J_DQS_DN'<15>:
 C_SIGNAL='@baseboard_fab2_lib.baseboard_fab2(sch_1):m_j_dqs_dn(15)';
NODE_NAME     U2D1 AC30
 '@BASEBOARD_FAB2_LIB.BASEBOARD_FAB2(SCH_1):PAGE59_I172@CHPSET_LIB.SKX_EXT_B(CHIPS)':
 'DDR2_DQS_DN'<15>: CDS_PINID='DDR2_DQS_DN(15)';
NODE_NAME     J1G3 122
 '@BASEBOARD_FAB2_LIB.BASEBOARD_FAB2(SCH_1):PAGE81_I67@MSTR_SCONN.SCONN288_H44441004(CHIPS)':
 'DQS15N': CDS_PINID='DQS15N';
NODE_NAME     J9U2 122
 '@BASEBOARD_FAB2_LIB.BASEBOARD_FAB2(SCH_1):PAGE82_I64@MSTR_SCONN.SCONN288_H44441003(CHIPS)':
 'DQS15N': CDS_PINID='DQS15N';
NET_NAME
'M_J_DQS_DN<16>'
 '@BASEBOARD_FAB2_LIB.BASEBOARD_FAB2(SCH_1):M_J_DQS_DN'<16>:
 C_SIGNAL='@baseboard_fab2_lib.baseboard_fab2(sch_1):m_j_dqs_dn(16)';
NODE_NAME     U2D1 AC24
 '@BASEBOARD_FAB2_LIB.BASEBOARD_FAB2(SCH_1):PAGE59_I172@CHPSET_LIB.SKX_EXT_B(CHIPS)':
 'DDR2_DQS_DN'<16>: CDS_PINID='DDR2_DQS_DN(16)';
NODE_NAME     J1G3 133
 '@BASEBOARD_FAB2_LIB.BASEBOARD_FAB2(SCH_1):PAGE81_I67@MSTR_SCONN.SCONN288_H44441004(CHIPS)':
 'DQS16N': CDS_PINID='DQS16N';
NODE_NAME     J9U2 133
 '@BASEBOARD_FAB2_LIB.BASEBOARD_FAB2(SCH_1):PAGE82_I64@MSTR_SCONN.SCONN288_H44441003(CHIPS)':
 'DQS16N': CDS_PINID='DQS16N';
NET_NAME
'M_J_DQS_DN<17>'
 '@BASEBOARD_FAB2_LIB.BASEBOARD_FAB2(SCH_1):M_J_DQS_DN'<17>:
 C_SIGNAL='@baseboard_fab2_lib.baseboard_fab2(sch_1):m_j_dqs_dn(17)';
NODE_NAME     U2D1 AT71
 '@BASEBOARD_FAB2_LIB.BASEBOARD_FAB2(SCH_1):PAGE59_I172@CHPSET_LIB.SKX_EXT_B(CHIPS)':
 'DDR2_DQS_DN'<17>: CDS_PINID='DDR2_DQS_DN(17)';
NODE_NAME     J1G3 52
 '@BASEBOARD_FAB2_LIB.BASEBOARD_FAB2(SCH_1):PAGE81_I67@MSTR_SCONN.SCONN288_H44441004(CHIPS)':
 'DQS17N': CDS_PINID='DQS17N';
NODE_NAME     J9U2 52
 '@BASEBOARD_FAB2_LIB.BASEBOARD_FAB2(SCH_1):PAGE82_I64@MSTR_SCONN.SCONN288_H44441003(CHIPS)':
 'DQS17N': CDS_PINID='DQS17N';
NET_NAME
'M_J_DQS_DN<1>'
 '@BASEBOARD_FAB2_LIB.BASEBOARD_FAB2(SCH_1):M_J_DQS_DN'<1>:
 C_SIGNAL='@baseboard_fab2_lib.baseboard_fab2(sch_1):m_j_dqs_dn(1)';
NODE_NAME     U2D1 AA74
 '@BASEBOARD_FAB2_LIB.BASEBOARD_FAB2(SCH_1):PAGE59_I172@CHPSET_LIB.SKX_EXT_B(CHIPS)':
 'DDR2_DQS_DN'<1>: CDS_PINID='DDR2_DQS_DN(1)';
NODE_NAME     J1G3 163
 '@BASEBOARD_FAB2_LIB.BASEBOARD_FAB2(SCH_1):PAGE81_I67@MSTR_SCONN.SCONN288_H44441004(CHIPS)':
 'DQS1N': CDS_PINID='DQS1N';
NODE_NAME     J9U2 163
 '@BASEBOARD_FAB2_LIB.BASEBOARD_FAB2(SCH_1):PAGE82_I64@MSTR_SCONN.SCONN288_H44441003(CHIPS)':
 'DQS1N': CDS_PINID='DQS1N';
NET_NAME
'M_J_DQS_DN<2>'
 '@BASEBOARD_FAB2_LIB.BASEBOARD_FAB2(SCH_1):M_J_DQS_DN'<2>:
 C_SIGNAL='@baseboard_fab2_lib.baseboard_fab2(sch_1):m_j_dqs_dn(2)';
NODE_NAME     U2D1 Y69
 '@BASEBOARD_FAB2_LIB.BASEBOARD_FAB2(SCH_1):PAGE59_I172@CHPSET_LIB.SKX_EXT_B(CHIPS)':
 'DDR2_DQS_DN'<2>: CDS_PINID='DDR2_DQS_DN(2)';
NODE_NAME     J1G3 174
 '@BASEBOARD_FAB2_LIB.BASEBOARD_FAB2(SCH_1):PAGE81_I67@MSTR_SCONN.SCONN288_H44441004(CHIPS)':
 'DQS2N': CDS_PINID='DQS2N';
NODE_NAME     J9U2 174
 '@BASEBOARD_FAB2_LIB.BASEBOARD_FAB2(SCH_1):PAGE82_I64@MSTR_SCONN.SCONN288_H44441003(CHIPS)':
 'DQS2N': CDS_PINID='DQS2N';
NET_NAME
'M_J_DQS_DN<3>'
 '@BASEBOARD_FAB2_LIB.BASEBOARD_FAB2(SCH_1):M_J_DQS_DN'<3>:
 C_SIGNAL='@baseboard_fab2_lib.baseboard_fab2(sch_1):m_j_dqs_dn(3)';
NODE_NAME     U2D1 AU66
 '@BASEBOARD_FAB2_LIB.BASEBOARD_FAB2(SCH_1):PAGE59_I172@CHPSET_LIB.SKX_EXT_B(CHIPS)':
 'DDR2_DQS_DN'<3>: CDS_PINID='DDR2_DQS_DN(3)';
NODE_NAME     J1G3 185
 '@BASEBOARD_FAB2_LIB.BASEBOARD_FAB2(SCH_1):PAGE81_I67@MSTR_SCONN.SCONN288_H44441004(CHIPS)':
 'DQS3N': CDS_PINID='DQS3N';
NODE_NAME     J9U2 185
 '@BASEBOARD_FAB2_LIB.BASEBOARD_FAB2(SCH_1):PAGE82_I64@MSTR_SCONN.SCONN288_H44441003(CHIPS)':
 'DQS3N': CDS_PINID='DQS3N';
NET_NAME
'M_J_DQS_DN<4>'
 '@BASEBOARD_FAB2_LIB.BASEBOARD_FAB2(SCH_1):M_J_DQS_DN'<4>:
 C_SIGNAL='@baseboard_fab2_lib.baseboard_fab2(sch_1):m_j_dqs_dn(4)';
NODE_NAME     U2D1 AB39
 '@BASEBOARD_FAB2_LIB.BASEBOARD_FAB2(SCH_1):PAGE59_I172@CHPSET_LIB.SKX_EXT_B(CHIPS)':
 'DDR2_DQS_DN'<4>: CDS_PINID='DDR2_DQS_DN(4)';
NODE_NAME     J1G3 244
 '@BASEBOARD_FAB2_LIB.BASEBOARD_FAB2(SCH_1):PAGE81_I67@MSTR_SCONN.SCONN288_H44441004(CHIPS)':
 'DQS4N': CDS_PINID='DQS4N';
NODE_NAME     J9U2 244
 '@BASEBOARD_FAB2_LIB.BASEBOARD_FAB2(SCH_1):PAGE82_I64@MSTR_SCONN.SCONN288_H44441003(CHIPS)':
 'DQS4N': CDS_PINID='DQS4N';
NET_NAME
'M_J_DQS_DN<5>'
 '@BASEBOARD_FAB2_LIB.BASEBOARD_FAB2(SCH_1):M_J_DQS_DN'<5>:
 C_SIGNAL='@baseboard_fab2_lib.baseboard_fab2(sch_1):m_j_dqs_dn(5)';
NODE_NAME     U2D1 AB33
 '@BASEBOARD_FAB2_LIB.BASEBOARD_FAB2(SCH_1):PAGE59_I172@CHPSET_LIB.SKX_EXT_B(CHIPS)':
 'DDR2_DQS_DN'<5>: CDS_PINID='DDR2_DQS_DN(5)';
NODE_NAME     J1G3 255
 '@BASEBOARD_FAB2_LIB.BASEBOARD_FAB2(SCH_1):PAGE81_I67@MSTR_SCONN.SCONN288_H44441004(CHIPS)':
 'DQS5N': CDS_PINID='DQS5N';
NODE_NAME     J9U2 255
 '@BASEBOARD_FAB2_LIB.BASEBOARD_FAB2(SCH_1):PAGE82_I64@MSTR_SCONN.SCONN288_H44441003(CHIPS)':
 'DQS5N': CDS_PINID='DQS5N';
NET_NAME
'M_J_DQS_DN<6>'
 '@BASEBOARD_FAB2_LIB.BASEBOARD_FAB2(SCH_1):M_J_DQS_DN'<6>:
 C_SIGNAL='@baseboard_fab2_lib.baseboard_fab2(sch_1):m_j_dqs_dn(6)';
NODE_NAME     U2D1 AJ30
 '@BASEBOARD_FAB2_LIB.BASEBOARD_FAB2(SCH_1):PAGE59_I172@CHPSET_LIB.SKX_EXT_B(CHIPS)':
 'DDR2_DQS_DN'<6>: CDS_PINID='DDR2_DQS_DN(6)';
NODE_NAME     J1G3 266
 '@BASEBOARD_FAB2_LIB.BASEBOARD_FAB2(SCH_1):PAGE81_I67@MSTR_SCONN.SCONN288_H44441004(CHIPS)':
 'DQS6N': CDS_PINID='DQS6N';
NODE_NAME     J9U2 266
 '@BASEBOARD_FAB2_LIB.BASEBOARD_FAB2(SCH_1):PAGE82_I64@MSTR_SCONN.SCONN288_H44441003(CHIPS)':
 'DQS6N': CDS_PINID='DQS6N';
NET_NAME
'M_J_DQS_DN<7>'
 '@BASEBOARD_FAB2_LIB.BASEBOARD_FAB2(SCH_1):M_J_DQS_DN'<7>:
 C_SIGNAL='@baseboard_fab2_lib.baseboard_fab2(sch_1):m_j_dqs_dn(7)';
NODE_NAME     U2D1 AJ24
 '@BASEBOARD_FAB2_LIB.BASEBOARD_FAB2(SCH_1):PAGE59_I172@CHPSET_LIB.SKX_EXT_B(CHIPS)':
 'DDR2_DQS_DN'<7>: CDS_PINID='DDR2_DQS_DN(7)';
NODE_NAME     J1G3 277
 '@BASEBOARD_FAB2_LIB.BASEBOARD_FAB2(SCH_1):PAGE81_I67@MSTR_SCONN.SCONN288_H44441004(CHIPS)':
 'DQS7N': CDS_PINID='DQS7N';
NODE_NAME     J9U2 277
 '@BASEBOARD_FAB2_LIB.BASEBOARD_FAB2(SCH_1):PAGE82_I64@MSTR_SCONN.SCONN288_H44441003(CHIPS)':
 'DQS7N': CDS_PINID='DQS7N';
NET_NAME
'M_J_DQS_DN<8>'
 '@BASEBOARD_FAB2_LIB.BASEBOARD_FAB2(SCH_1):M_J_DQS_DN'<8>:
 C_SIGNAL='@baseboard_fab2_lib.baseboard_fab2(sch_1):m_j_dqs_dn(8)';
NODE_NAME     U2D1 BB71
 '@BASEBOARD_FAB2_LIB.BASEBOARD_FAB2(SCH_1):PAGE59_I172@CHPSET_LIB.SKX_EXT_B(CHIPS)':
 'DDR2_DQS_DN'<8>: CDS_PINID='DDR2_DQS_DN(8)';
NODE_NAME     J1G3 196
 '@BASEBOARD_FAB2_LIB.BASEBOARD_FAB2(SCH_1):PAGE81_I67@MSTR_SCONN.SCONN288_H44441004(CHIPS)':
 'DQS8N': CDS_PINID='DQS8N';
NODE_NAME     J9U2 196
 '@BASEBOARD_FAB2_LIB.BASEBOARD_FAB2(SCH_1):PAGE82_I64@MSTR_SCONN.SCONN288_H44441003(CHIPS)':
 'DQS8N': CDS_PINID='DQS8N';
NET_NAME
'M_J_DQS_DN<9>'
 '@BASEBOARD_FAB2_LIB.BASEBOARD_FAB2(SCH_1):M_J_DQS_DN'<9>:
 C_SIGNAL='@baseboard_fab2_lib.baseboard_fab2(sch_1):m_j_dqs_dn(9)';
NODE_NAME     U2D1 AP77
 '@BASEBOARD_FAB2_LIB.BASEBOARD_FAB2(SCH_1):PAGE59_I172@CHPSET_LIB.SKX_EXT_B(CHIPS)':
 'DDR2_DQS_DN'<9>: CDS_PINID='DDR2_DQS_DN(9)';
NODE_NAME     J1G3 8
 '@BASEBOARD_FAB2_LIB.BASEBOARD_FAB2(SCH_1):PAGE81_I67@MSTR_SCONN.SCONN288_H44441004(CHIPS)':
 'DQS9N': CDS_PINID='DQS9N';
NODE_NAME     J9U2 8
 '@BASEBOARD_FAB2_LIB.BASEBOARD_FAB2(SCH_1):PAGE82_I64@MSTR_SCONN.SCONN288_H44441003(CHIPS)':
 'DQS9N': CDS_PINID='DQS9N';
NET_NAME
'M_J_DQS_DP<0>'
 '@BASEBOARD_FAB2_LIB.BASEBOARD_FAB2(SCH_1):M_J_DQS_DP'<0>:
 C_SIGNAL='@baseboard_fab2_lib.baseboard_fab2(sch_1):m_j_dqs_dp(0)';
NODE_NAME     U2D1 AM75
 '@BASEBOARD_FAB2_LIB.BASEBOARD_FAB2(SCH_1):PAGE59_I172@CHPSET_LIB.SKX_EXT_B(CHIPS)':
 'DDR2_DQS_DP'<0>: CDS_PINID='DDR2_DQS_DP(0)';
NODE_NAME     J1G3 153
 '@BASEBOARD_FAB2_LIB.BASEBOARD_FAB2(SCH_1):PAGE81_I67@MSTR_SCONN.SCONN288_H44441004(CHIPS)':
 'DQS0P': CDS_PINID='DQS0P';
NODE_NAME     J9U2 153
 '@BASEBOARD_FAB2_LIB.BASEBOARD_FAB2(SCH_1):PAGE82_I64@MSTR_SCONN.SCONN288_H44441003(CHIPS)':
 'DQS0P': CDS_PINID='DQS0P';
NET_NAME
'M_J_DQS_DP<10>'
 '@BASEBOARD_FAB2_LIB.BASEBOARD_FAB2(SCH_1):M_J_DQS_DP'<10>:
 C_SIGNAL='@baseboard_fab2_lib.baseboard_fab2(sch_1):m_j_dqs_dp(10)';
NODE_NAME     U2D1 AC76
 '@BASEBOARD_FAB2_LIB.BASEBOARD_FAB2(SCH_1):PAGE59_I172@CHPSET_LIB.SKX_EXT_B(CHIPS)':
 'DDR2_DQS_DP'<10>: CDS_PINID='DDR2_DQS_DP(10)';
NODE_NAME     J1G3 18
 '@BASEBOARD_FAB2_LIB.BASEBOARD_FAB2(SCH_1):PAGE81_I67@MSTR_SCONN.SCONN288_H44441004(CHIPS)':
 'DQS10P': CDS_PINID='DQS10P';
NODE_NAME     J9U2 18
 '@BASEBOARD_FAB2_LIB.BASEBOARD_FAB2(SCH_1):PAGE82_I64@MSTR_SCONN.SCONN288_H44441003(CHIPS)':
 'DQS10P': CDS_PINID='DQS10P';
NET_NAME
'M_J_DQS_DP<11>'
 '@BASEBOARD_FAB2_LIB.BASEBOARD_FAB2(SCH_1):M_J_DQS_DP'<11>:
 C_SIGNAL='@baseboard_fab2_lib.baseboard_fab2(sch_1):m_j_dqs_dp(11)';
NODE_NAME     U2D1 V71
 '@BASEBOARD_FAB2_LIB.BASEBOARD_FAB2(SCH_1):PAGE59_I172@CHPSET_LIB.SKX_EXT_B(CHIPS)':
 'DDR2_DQS_DP'<11>: CDS_PINID='DDR2_DQS_DP(11)';
NODE_NAME     J1G3 29
 '@BASEBOARD_FAB2_LIB.BASEBOARD_FAB2(SCH_1):PAGE81_I67@MSTR_SCONN.SCONN288_H44441004(CHIPS)':
 'DQS11P': CDS_PINID='DQS11P';
NODE_NAME     J9U2 29
 '@BASEBOARD_FAB2_LIB.BASEBOARD_FAB2(SCH_1):PAGE82_I64@MSTR_SCONN.SCONN288_H44441003(CHIPS)':
 'DQS11P': CDS_PINID='DQS11P';
NET_NAME
'M_J_DQS_DP<12>'
 '@BASEBOARD_FAB2_LIB.BASEBOARD_FAB2(SCH_1):M_J_DQS_DP'<12>:
 C_SIGNAL='@baseboard_fab2_lib.baseboard_fab2(sch_1):m_j_dqs_dp(12)';
NODE_NAME     U2D1 AN66
 '@BASEBOARD_FAB2_LIB.BASEBOARD_FAB2(SCH_1):PAGE59_I172@CHPSET_LIB.SKX_EXT_B(CHIPS)':
 'DDR2_DQS_DP'<12>: CDS_PINID='DDR2_DQS_DP(12)';
NODE_NAME     J1G3 40
 '@BASEBOARD_FAB2_LIB.BASEBOARD_FAB2(SCH_1):PAGE81_I67@MSTR_SCONN.SCONN288_H44441004(CHIPS)':
 'DQS12P': CDS_PINID='DQS12P';
NODE_NAME     J9U2 40
 '@BASEBOARD_FAB2_LIB.BASEBOARD_FAB2(SCH_1):PAGE82_I64@MSTR_SCONN.SCONN288_H44441003(CHIPS)':
 'DQS12P': CDS_PINID='DQS12P';
NET_NAME
'M_J_DQS_DP<13>'
 '@BASEBOARD_FAB2_LIB.BASEBOARD_FAB2(SCH_1):M_J_DQS_DP'<13>:
 C_SIGNAL='@baseboard_fab2_lib.baseboard_fab2(sch_1):m_j_dqs_dp(13)';
NODE_NAME     U2D1 V39
 '@BASEBOARD_FAB2_LIB.BASEBOARD_FAB2(SCH_1):PAGE59_I172@CHPSET_LIB.SKX_EXT_B(CHIPS)':
 'DDR2_DQS_DP'<13>: CDS_PINID='DDR2_DQS_DP(13)';
NODE_NAME     J1G3 99
 '@BASEBOARD_FAB2_LIB.BASEBOARD_FAB2(SCH_1):PAGE81_I67@MSTR_SCONN.SCONN288_H44441004(CHIPS)':
 'DQS13P': CDS_PINID='DQS13P';
NODE_NAME     J9U2 99
 '@BASEBOARD_FAB2_LIB.BASEBOARD_FAB2(SCH_1):PAGE82_I64@MSTR_SCONN.SCONN288_H44441003(CHIPS)':
 'DQS13P': CDS_PINID='DQS13P';
NET_NAME
'M_J_DQS_DP<14>'
 '@BASEBOARD_FAB2_LIB.BASEBOARD_FAB2(SCH_1):M_J_DQS_DP'<14>:
 C_SIGNAL='@baseboard_fab2_lib.baseboard_fab2(sch_1):m_j_dqs_dp(14)';
NODE_NAME     U2D1 V33
 '@BASEBOARD_FAB2_LIB.BASEBOARD_FAB2(SCH_1):PAGE59_I172@CHPSET_LIB.SKX_EXT_B(CHIPS)':
 'DDR2_DQS_DP'<14>: CDS_PINID='DDR2_DQS_DP(14)';
NODE_NAME     J1G3 110
 '@BASEBOARD_FAB2_LIB.BASEBOARD_FAB2(SCH_1):PAGE81_I67@MSTR_SCONN.SCONN288_H44441004(CHIPS)':
 'DQS14P': CDS_PINID='DQS14P';
NODE_NAME     J9U2 110
 '@BASEBOARD_FAB2_LIB.BASEBOARD_FAB2(SCH_1):PAGE82_I64@MSTR_SCONN.SCONN288_H44441003(CHIPS)':
 'DQS14P': CDS_PINID='DQS14P';
NET_NAME
'M_J_DQS_DP<15>'
 '@BASEBOARD_FAB2_LIB.BASEBOARD_FAB2(SCH_1):M_J_DQS_DP'<15>:
 C_SIGNAL='@baseboard_fab2_lib.baseboard_fab2(sch_1):m_j_dqs_dp(15)';
NODE_NAME     U2D1 AE30
 '@BASEBOARD_FAB2_LIB.BASEBOARD_FAB2(SCH_1):PAGE59_I172@CHPSET_LIB.SKX_EXT_B(CHIPS)':
 'DDR2_DQS_DP'<15>: CDS_PINID='DDR2_DQS_DP(15)';
NODE_NAME     J1G3 121
 '@BASEBOARD_FAB2_LIB.BASEBOARD_FAB2(SCH_1):PAGE81_I67@MSTR_SCONN.SCONN288_H44441004(CHIPS)':
 'DQS15P': CDS_PINID='DQS15P';
NODE_NAME     J9U2 121
 '@BASEBOARD_FAB2_LIB.BASEBOARD_FAB2(SCH_1):PAGE82_I64@MSTR_SCONN.SCONN288_H44441003(CHIPS)':
 'DQS15P': CDS_PINID='DQS15P';
NET_NAME
'M_J_DQS_DP<16>'
 '@BASEBOARD_FAB2_LIB.BASEBOARD_FAB2(SCH_1):M_J_DQS_DP'<16>:
 C_SIGNAL='@baseboard_fab2_lib.baseboard_fab2(sch_1):m_j_dqs_dp(16)';
NODE_NAME     U2D1 AE24
 '@BASEBOARD_FAB2_LIB.BASEBOARD_FAB2(SCH_1):PAGE59_I172@CHPSET_LIB.SKX_EXT_B(CHIPS)':
 'DDR2_DQS_DP'<16>: CDS_PINID='DDR2_DQS_DP(16)';
NODE_NAME     J1G3 132
 '@BASEBOARD_FAB2_LIB.BASEBOARD_FAB2(SCH_1):PAGE81_I67@MSTR_SCONN.SCONN288_H44441004(CHIPS)':
 'DQS16P': CDS_PINID='DQS16P';
NODE_NAME     J9U2 132
 '@BASEBOARD_FAB2_LIB.BASEBOARD_FAB2(SCH_1):PAGE82_I64@MSTR_SCONN.SCONN288_H44441003(CHIPS)':
 'DQS16P': CDS_PINID='DQS16P';
NET_NAME
'M_J_DQS_DP<17>'
 '@BASEBOARD_FAB2_LIB.BASEBOARD_FAB2(SCH_1):M_J_DQS_DP'<17>:
 C_SIGNAL='@baseboard_fab2_lib.baseboard_fab2(sch_1):m_j_dqs_dp(17)';
NODE_NAME     U2D1 AV71
 '@BASEBOARD_FAB2_LIB.BASEBOARD_FAB2(SCH_1):PAGE59_I172@CHPSET_LIB.SKX_EXT_B(CHIPS)':
 'DDR2_DQS_DP'<17>: CDS_PINID='DDR2_DQS_DP(17)';
NODE_NAME     J1G3 51
 '@BASEBOARD_FAB2_LIB.BASEBOARD_FAB2(SCH_1):PAGE81_I67@MSTR_SCONN.SCONN288_H44441004(CHIPS)':
 'DQS17P': CDS_PINID='DQS17P';
NODE_NAME     J9U2 51
 '@BASEBOARD_FAB2_LIB.BASEBOARD_FAB2(SCH_1):PAGE82_I64@MSTR_SCONN.SCONN288_H44441003(CHIPS)':
 'DQS17P': CDS_PINID='DQS17P';
NET_NAME
'M_J_DQS_DP<1>'
 '@BASEBOARD_FAB2_LIB.BASEBOARD_FAB2(SCH_1):M_J_DQS_DP'<1>:
 C_SIGNAL='@baseboard_fab2_lib.baseboard_fab2(sch_1):m_j_dqs_dp(1)';
NODE_NAME     U2D1 AB75
 '@BASEBOARD_FAB2_LIB.BASEBOARD_FAB2(SCH_1):PAGE59_I172@CHPSET_LIB.SKX_EXT_B(CHIPS)':
 'DDR2_DQS_DP'<1>: CDS_PINID='DDR2_DQS_DP(1)';
NODE_NAME     J1G3 164
 '@BASEBOARD_FAB2_LIB.BASEBOARD_FAB2(SCH_1):PAGE81_I67@MSTR_SCONN.SCONN288_H44441004(CHIPS)':
 'DQS1P': CDS_PINID='DQS1P';
NODE_NAME     J9U2 164
 '@BASEBOARD_FAB2_LIB.BASEBOARD_FAB2(SCH_1):PAGE82_I64@MSTR_SCONN.SCONN288_H44441003(CHIPS)':
 'DQS1P': CDS_PINID='DQS1P';
NET_NAME
'M_J_DQS_DP<2>'
 '@BASEBOARD_FAB2_LIB.BASEBOARD_FAB2(SCH_1):M_J_DQS_DP'<2>:
 C_SIGNAL='@baseboard_fab2_lib.baseboard_fab2(sch_1):m_j_dqs_dp(2)';
NODE_NAME     U2D1 W70
 '@BASEBOARD_FAB2_LIB.BASEBOARD_FAB2(SCH_1):PAGE59_I172@CHPSET_LIB.SKX_EXT_B(CHIPS)':
 'DDR2_DQS_DP'<2>: CDS_PINID='DDR2_DQS_DP(2)';
NODE_NAME     J1G3 175
 '@BASEBOARD_FAB2_LIB.BASEBOARD_FAB2(SCH_1):PAGE81_I67@MSTR_SCONN.SCONN288_H44441004(CHIPS)':
 'DQS2P': CDS_PINID='DQS2P';
NODE_NAME     J9U2 175
 '@BASEBOARD_FAB2_LIB.BASEBOARD_FAB2(SCH_1):PAGE82_I64@MSTR_SCONN.SCONN288_H44441003(CHIPS)':
 'DQS2P': CDS_PINID='DQS2P';
NET_NAME
'M_J_DQS_DP<3>'
 '@BASEBOARD_FAB2_LIB.BASEBOARD_FAB2(SCH_1):M_J_DQS_DP'<3>:
 C_SIGNAL='@baseboard_fab2_lib.baseboard_fab2(sch_1):m_j_dqs_dp(3)';
NODE_NAME     U2D1 AR66
 '@BASEBOARD_FAB2_LIB.BASEBOARD_FAB2(SCH_1):PAGE59_I172@CHPSET_LIB.SKX_EXT_B(CHIPS)':
 'DDR2_DQS_DP'<3>: CDS_PINID='DDR2_DQS_DP(3)';
NODE_NAME     J1G3 186
 '@BASEBOARD_FAB2_LIB.BASEBOARD_FAB2(SCH_1):PAGE81_I67@MSTR_SCONN.SCONN288_H44441004(CHIPS)':
 'DQS3P': CDS_PINID='DQS3P';
NODE_NAME     J9U2 186
 '@BASEBOARD_FAB2_LIB.BASEBOARD_FAB2(SCH_1):PAGE82_I64@MSTR_SCONN.SCONN288_H44441003(CHIPS)':
 'DQS3P': CDS_PINID='DQS3P';
NET_NAME
'M_J_DQS_DP<4>'
 '@BASEBOARD_FAB2_LIB.BASEBOARD_FAB2(SCH_1):M_J_DQS_DP'<4>:
 C_SIGNAL='@baseboard_fab2_lib.baseboard_fab2(sch_1):m_j_dqs_dp(4)';
NODE_NAME     U2D1 Y39
 '@BASEBOARD_FAB2_LIB.BASEBOARD_FAB2(SCH_1):PAGE59_I172@CHPSET_LIB.SKX_EXT_B(CHIPS)':
 'DDR2_DQS_DP'<4>: CDS_PINID='DDR2_DQS_DP(4)';
NODE_NAME     J1G3 245
 '@BASEBOARD_FAB2_LIB.BASEBOARD_FAB2(SCH_1):PAGE81_I67@MSTR_SCONN.SCONN288_H44441004(CHIPS)':
 'DQS4P': CDS_PINID='DQS4P';
NODE_NAME     J9U2 245
 '@BASEBOARD_FAB2_LIB.BASEBOARD_FAB2(SCH_1):PAGE82_I64@MSTR_SCONN.SCONN288_H44441003(CHIPS)':
 'DQS4P': CDS_PINID='DQS4P';
NET_NAME
'M_J_DQS_DP<5>'
 '@BASEBOARD_FAB2_LIB.BASEBOARD_FAB2(SCH_1):M_J_DQS_DP'<5>:
 C_SIGNAL='@baseboard_fab2_lib.baseboard_fab2(sch_1):m_j_dqs_dp(5)';
NODE_NAME     U2D1 Y33
 '@BASEBOARD_FAB2_LIB.BASEBOARD_FAB2(SCH_1):PAGE59_I172@CHPSET_LIB.SKX_EXT_B(CHIPS)':
 'DDR2_DQS_DP'<5>: CDS_PINID='DDR2_DQS_DP(5)';
NODE_NAME     J1G3 256
 '@BASEBOARD_FAB2_LIB.BASEBOARD_FAB2(SCH_1):PAGE81_I67@MSTR_SCONN.SCONN288_H44441004(CHIPS)':
 'DQS5P': CDS_PINID='DQS5P';
NODE_NAME     J9U2 256
 '@BASEBOARD_FAB2_LIB.BASEBOARD_FAB2(SCH_1):PAGE82_I64@MSTR_SCONN.SCONN288_H44441003(CHIPS)':
 'DQS5P': CDS_PINID='DQS5P';
NET_NAME
'M_J_DQS_DP<6>'
 '@BASEBOARD_FAB2_LIB.BASEBOARD_FAB2(SCH_1):M_J_DQS_DP'<6>:
 C_SIGNAL='@baseboard_fab2_lib.baseboard_fab2(sch_1):m_j_dqs_dp(6)';
NODE_NAME     U2D1 AG30
 '@BASEBOARD_FAB2_LIB.BASEBOARD_FAB2(SCH_1):PAGE59_I172@CHPSET_LIB.SKX_EXT_B(CHIPS)':
 'DDR2_DQS_DP'<6>: CDS_PINID='DDR2_DQS_DP(6)';
NODE_NAME     J1G3 267
 '@BASEBOARD_FAB2_LIB.BASEBOARD_FAB2(SCH_1):PAGE81_I67@MSTR_SCONN.SCONN288_H44441004(CHIPS)':
 'DQS6P': CDS_PINID='DQS6P';
NODE_NAME     J9U2 267
 '@BASEBOARD_FAB2_LIB.BASEBOARD_FAB2(SCH_1):PAGE82_I64@MSTR_SCONN.SCONN288_H44441003(CHIPS)':
 'DQS6P': CDS_PINID='DQS6P';
NET_NAME
'M_J_DQS_DP<7>'
 '@BASEBOARD_FAB2_LIB.BASEBOARD_FAB2(SCH_1):M_J_DQS_DP'<7>:
 C_SIGNAL='@baseboard_fab2_lib.baseboard_fab2(sch_1):m_j_dqs_dp(7)';
NODE_NAME     U2D1 AG24
 '@BASEBOARD_FAB2_LIB.BASEBOARD_FAB2(SCH_1):PAGE59_I172@CHPSET_LIB.SKX_EXT_B(CHIPS)':
 'DDR2_DQS_DP'<7>: CDS_PINID='DDR2_DQS_DP(7)';
NODE_NAME     J1G3 278
 '@BASEBOARD_FAB2_LIB.BASEBOARD_FAB2(SCH_1):PAGE81_I67@MSTR_SCONN.SCONN288_H44441004(CHIPS)':
 'DQS7P': CDS_PINID='DQS7P';
NODE_NAME     J9U2 278
 '@BASEBOARD_FAB2_LIB.BASEBOARD_FAB2(SCH_1):PAGE82_I64@MSTR_SCONN.SCONN288_H44441003(CHIPS)':
 'DQS7P': CDS_PINID='DQS7P';
NET_NAME
'M_J_DQS_DP<8>'
 '@BASEBOARD_FAB2_LIB.BASEBOARD_FAB2(SCH_1):M_J_DQS_DP'<8>:
 C_SIGNAL='@baseboard_fab2_lib.baseboard_fab2(sch_1):m_j_dqs_dp(8)';
NODE_NAME     U2D1 AY71
 '@BASEBOARD_FAB2_LIB.BASEBOARD_FAB2(SCH_1):PAGE59_I172@CHPSET_LIB.SKX_EXT_B(CHIPS)':
 'DDR2_DQS_DP'<8>: CDS_PINID='DDR2_DQS_DP(8)';
NODE_NAME     J1G3 197
 '@BASEBOARD_FAB2_LIB.BASEBOARD_FAB2(SCH_1):PAGE81_I67@MSTR_SCONN.SCONN288_H44441004(CHIPS)':
 'DQS8P': CDS_PINID='DQS8P';
NODE_NAME     J9U2 197
 '@BASEBOARD_FAB2_LIB.BASEBOARD_FAB2(SCH_1):PAGE82_I64@MSTR_SCONN.SCONN288_H44441003(CHIPS)':
 'DQS8P': CDS_PINID='DQS8P';
NET_NAME
'M_J_DQS_DP<9>'
 '@BASEBOARD_FAB2_LIB.BASEBOARD_FAB2(SCH_1):M_J_DQS_DP'<9>:
 C_SIGNAL='@baseboard_fab2_lib.baseboard_fab2(sch_1):m_j_dqs_dp(9)';
NODE_NAME     U2D1 AN76
 '@BASEBOARD_FAB2_LIB.BASEBOARD_FAB2(SCH_1):PAGE59_I172@CHPSET_LIB.SKX_EXT_B(CHIPS)':
 'DDR2_DQS_DP'<9>: CDS_PINID='DDR2_DQS_DP(9)';
NODE_NAME     J1G3 7
 '@BASEBOARD_FAB2_LIB.BASEBOARD_FAB2(SCH_1):PAGE81_I67@MSTR_SCONN.SCONN288_H44441004(CHIPS)':
 'DQS9P': CDS_PINID='DQS9P';
NODE_NAME     J9U2 7
 '@BASEBOARD_FAB2_LIB.BASEBOARD_FAB2(SCH_1):PAGE82_I64@MSTR_SCONN.SCONN288_H44441003(CHIPS)':
 'DQS9P': CDS_PINID='DQS9P';
NET_NAME
'M_J_ECC<0>'
 '@BASEBOARD_FAB2_LIB.BASEBOARD_FAB2(SCH_1):M_J_ECC'<0>:
 C_SIGNAL='@baseboard_fab2_lib.baseboard_fab2(sch_1):m_j_ecc(0)';
NODE_NAME     U2D1 AU72
 '@BASEBOARD_FAB2_LIB.BASEBOARD_FAB2(SCH_1):PAGE59_I172@CHPSET_LIB.SKX_EXT_B(CHIPS)':
 'DDR2_ECC'<0>: CDS_PINID='DDR2_ECC(0)';
NODE_NAME     J1G3 194
 '@BASEBOARD_FAB2_LIB.BASEBOARD_FAB2(SCH_1):PAGE81_I186@MSTR_SCONN.SCONN288_H44441004(CHIPS)':
 'CB'<1>: CDS_PINID='CB(1)';
NODE_NAME     J9U2 49
 '@BASEBOARD_FAB2_LIB.BASEBOARD_FAB2(SCH_1):PAGE82_I187@MSTR_SCONN.SCONN288_H44441003(CHIPS)':
 'CB'<0>: CDS_PINID='CB(0)';
NET_NAME
'M_J_ECC<1>'
 '@BASEBOARD_FAB2_LIB.BASEBOARD_FAB2(SCH_1):M_J_ECC'<1>:
 C_SIGNAL='@baseboard_fab2_lib.baseboard_fab2(sch_1):m_j_ecc(1)';
NODE_NAME     U2D1 BA72
 '@BASEBOARD_FAB2_LIB.BASEBOARD_FAB2(SCH_1):PAGE59_I172@CHPSET_LIB.SKX_EXT_B(CHIPS)':
 'DDR2_ECC'<1>: CDS_PINID='DDR2_ECC(1)';
NODE_NAME     J1G3 49
 '@BASEBOARD_FAB2_LIB.BASEBOARD_FAB2(SCH_1):PAGE81_I186@MSTR_SCONN.SCONN288_H44441004(CHIPS)':
 'CB'<0>: CDS_PINID='CB(0)';
NODE_NAME     J9U2 194
 '@BASEBOARD_FAB2_LIB.BASEBOARD_FAB2(SCH_1):PAGE82_I187@MSTR_SCONN.SCONN288_H44441003(CHIPS)':
 'CB'<1>: CDS_PINID='CB(1)';
NET_NAME
'M_J_ECC<2>'
 '@BASEBOARD_FAB2_LIB.BASEBOARD_FAB2(SCH_1):M_J_ECC'<2>:
 C_SIGNAL='@baseboard_fab2_lib.baseboard_fab2(sch_1):m_j_ecc(2)';
NODE_NAME     U2D1 AV69
 '@BASEBOARD_FAB2_LIB.BASEBOARD_FAB2(SCH_1):PAGE59_I172@CHPSET_LIB.SKX_EXT_B(CHIPS)':
 'DDR2_ECC'<2>: CDS_PINID='DDR2_ECC(2)';
NODE_NAME     J1G3 201
 '@BASEBOARD_FAB2_LIB.BASEBOARD_FAB2(SCH_1):PAGE81_I186@MSTR_SCONN.SCONN288_H44441004(CHIPS)':
 'CB'<3>: CDS_PINID='CB(3)';
NODE_NAME     J9U2 56
 '@BASEBOARD_FAB2_LIB.BASEBOARD_FAB2(SCH_1):PAGE82_I187@MSTR_SCONN.SCONN288_H44441003(CHIPS)':
 'CB'<2>: CDS_PINID='CB(2)';
NET_NAME
'M_J_ECC<3>'
 '@BASEBOARD_FAB2_LIB.BASEBOARD_FAB2(SCH_1):M_J_ECC'<3>:
 C_SIGNAL='@baseboard_fab2_lib.baseboard_fab2(sch_1):m_j_ecc(3)';
NODE_NAME     U2D1 AY69
 '@BASEBOARD_FAB2_LIB.BASEBOARD_FAB2(SCH_1):PAGE59_I172@CHPSET_LIB.SKX_EXT_B(CHIPS)':
 'DDR2_ECC'<3>: CDS_PINID='DDR2_ECC(3)';
NODE_NAME     J1G3 56
 '@BASEBOARD_FAB2_LIB.BASEBOARD_FAB2(SCH_1):PAGE81_I186@MSTR_SCONN.SCONN288_H44441004(CHIPS)':
 'CB'<2>: CDS_PINID='CB(2)';
NODE_NAME     J9U2 201
 '@BASEBOARD_FAB2_LIB.BASEBOARD_FAB2(SCH_1):PAGE82_I187@MSTR_SCONN.SCONN288_H44441003(CHIPS)':
 'CB'<3>: CDS_PINID='CB(3)';
NET_NAME
'M_J_ECC<4>'
 '@BASEBOARD_FAB2_LIB.BASEBOARD_FAB2(SCH_1):M_J_ECC'<4>:
 C_SIGNAL='@baseboard_fab2_lib.baseboard_fab2(sch_1):m_j_ecc(4)';
NODE_NAME     U2D1 AV73
 '@BASEBOARD_FAB2_LIB.BASEBOARD_FAB2(SCH_1):PAGE59_I172@CHPSET_LIB.SKX_EXT_B(CHIPS)':
 'DDR2_ECC'<4>: CDS_PINID='DDR2_ECC(4)';
NODE_NAME     J1G3 192
 '@BASEBOARD_FAB2_LIB.BASEBOARD_FAB2(SCH_1):PAGE81_I186@MSTR_SCONN.SCONN288_H44441004(CHIPS)':
 'CB'<5>: CDS_PINID='CB(5)';
NODE_NAME     J9U2 47
 '@BASEBOARD_FAB2_LIB.BASEBOARD_FAB2(SCH_1):PAGE82_I187@MSTR_SCONN.SCONN288_H44441003(CHIPS)':
 'CB'<4>: CDS_PINID='CB(4)';
NET_NAME
'M_J_ECC<5>'
 '@BASEBOARD_FAB2_LIB.BASEBOARD_FAB2(SCH_1):M_J_ECC'<5>:
 C_SIGNAL='@baseboard_fab2_lib.baseboard_fab2(sch_1):m_j_ecc(5)';
NODE_NAME     U2D1 AY73
 '@BASEBOARD_FAB2_LIB.BASEBOARD_FAB2(SCH_1):PAGE59_I172@CHPSET_LIB.SKX_EXT_B(CHIPS)':
 'DDR2_ECC'<5>: CDS_PINID='DDR2_ECC(5)';
NODE_NAME     J1G3 47
 '@BASEBOARD_FAB2_LIB.BASEBOARD_FAB2(SCH_1):PAGE81_I186@MSTR_SCONN.SCONN288_H44441004(CHIPS)':
 'CB'<4>: CDS_PINID='CB(4)';
NODE_NAME     J9U2 192
 '@BASEBOARD_FAB2_LIB.BASEBOARD_FAB2(SCH_1):PAGE82_I187@MSTR_SCONN.SCONN288_H44441003(CHIPS)':
 'CB'<5>: CDS_PINID='CB(5)';
NET_NAME
'M_J_ECC<6>'
 '@BASEBOARD_FAB2_LIB.BASEBOARD_FAB2(SCH_1):M_J_ECC'<6>:
 C_SIGNAL='@baseboard_fab2_lib.baseboard_fab2(sch_1):m_j_ecc(6)';
NODE_NAME     U2D1 AU70
 '@BASEBOARD_FAB2_LIB.BASEBOARD_FAB2(SCH_1):PAGE59_I172@CHPSET_LIB.SKX_EXT_B(CHIPS)':
 'DDR2_ECC'<6>: CDS_PINID='DDR2_ECC(6)';
NODE_NAME     J1G3 199
 '@BASEBOARD_FAB2_LIB.BASEBOARD_FAB2(SCH_1):PAGE81_I186@MSTR_SCONN.SCONN288_H44441004(CHIPS)':
 'CB'<7>: CDS_PINID='CB(7)';
NODE_NAME     J9U2 54
 '@BASEBOARD_FAB2_LIB.BASEBOARD_FAB2(SCH_1):PAGE82_I187@MSTR_SCONN.SCONN288_H44441003(CHIPS)':
 'CB'<6>: CDS_PINID='CB(6)';
NET_NAME
'M_J_ECC<7>'
 '@BASEBOARD_FAB2_LIB.BASEBOARD_FAB2(SCH_1):M_J_ECC'<7>:
 C_SIGNAL='@baseboard_fab2_lib.baseboard_fab2(sch_1):m_j_ecc(7)';
NODE_NAME     U2D1 BA70
 '@BASEBOARD_FAB2_LIB.BASEBOARD_FAB2(SCH_1):PAGE59_I172@CHPSET_LIB.SKX_EXT_B(CHIPS)':
 'DDR2_ECC'<7>: CDS_PINID='DDR2_ECC(7)';
NODE_NAME     J1G3 54
 '@BASEBOARD_FAB2_LIB.BASEBOARD_FAB2(SCH_1):PAGE81_I186@MSTR_SCONN.SCONN288_H44441004(CHIPS)':
 'CB'<6>: CDS_PINID='CB(6)';
NODE_NAME     J9U2 199
 '@BASEBOARD_FAB2_LIB.BASEBOARD_FAB2(SCH_1):PAGE82_I187@MSTR_SCONN.SCONN288_H44441003(CHIPS)':
 'CB'<7>: CDS_PINID='CB(7)';
NET_NAME
'M_J_MA<0>'
 '@BASEBOARD_FAB2_LIB.BASEBOARD_FAB2(SCH_1):M_J_MA'<0>:
 C_SIGNAL='@baseboard_fab2_lib.baseboard_fab2(sch_1):m_j_ma(0)';
NODE_NAME     U2D1 AB53
 '@BASEBOARD_FAB2_LIB.BASEBOARD_FAB2(SCH_1):PAGE59_I172@CHPSET_LIB.SKX_EXT_B(CHIPS)':
 'DDR2_MA'<0>: CDS_PINID='DDR2_MA(0)';
NODE_NAME     J1G3 79
 '@BASEBOARD_FAB2_LIB.BASEBOARD_FAB2(SCH_1):PAGE81_I186@MSTR_SCONN.SCONN288_H44441004(CHIPS)':
 'A0': CDS_PINID='A0';
NODE_NAME     J9U2 79
 '@BASEBOARD_FAB2_LIB.BASEBOARD_FAB2(SCH_1):PAGE82_I187@MSTR_SCONN.SCONN288_H44441003(CHIPS)':
 'A0': CDS_PINID='A0';
NET_NAME
'M_J_MA<10>'
 '@BASEBOARD_FAB2_LIB.BASEBOARD_FAB2(SCH_1):M_J_MA'<10>:
 C_SIGNAL='@baseboard_fab2_lib.baseboard_fab2(sch_1):m_j_ma(10)';
NODE_NAME     U2D1 AD55
 '@BASEBOARD_FAB2_LIB.BASEBOARD_FAB2(SCH_1):PAGE59_I172@CHPSET_LIB.SKX_EXT_B(CHIPS)':
 'DDR2_MA'<10>: CDS_PINID='DDR2_MA(10)';
NODE_NAME     J1G3 225
 '@BASEBOARD_FAB2_LIB.BASEBOARD_FAB2(SCH_1):PAGE81_I186@MSTR_SCONN.SCONN288_H44441004(CHIPS)':
 'A10': CDS_PINID='A10';
NODE_NAME     J9U2 225
 '@BASEBOARD_FAB2_LIB.BASEBOARD_FAB2(SCH_1):PAGE82_I187@MSTR_SCONN.SCONN288_H44441003(CHIPS)':
 'A10': CDS_PINID='A10';
NET_NAME
'M_J_MA<11>'
 '@BASEBOARD_FAB2_LIB.BASEBOARD_FAB2(SCH_1):M_J_MA'<11>:
 C_SIGNAL='@baseboard_fab2_lib.baseboard_fab2(sch_1):m_j_ma(11)';
NODE_NAME     U2D1 AG60
 '@BASEBOARD_FAB2_LIB.BASEBOARD_FAB2(SCH_1):PAGE59_I172@CHPSET_LIB.SKX_EXT_B(CHIPS)':
 'DDR2_MA'<11>: CDS_PINID='DDR2_MA(11)';
NODE_NAME     J1G3 210
 '@BASEBOARD_FAB2_LIB.BASEBOARD_FAB2(SCH_1):PAGE81_I186@MSTR_SCONN.SCONN288_H44441004(CHIPS)':
 'A11': CDS_PINID='A11';
NODE_NAME     J9U2 210
 '@BASEBOARD_FAB2_LIB.BASEBOARD_FAB2(SCH_1):PAGE82_I187@MSTR_SCONN.SCONN288_H44441003(CHIPS)':
 'A11': CDS_PINID='A11';
NET_NAME
'M_J_MA<12>'
 '@BASEBOARD_FAB2_LIB.BASEBOARD_FAB2(SCH_1):M_J_MA'<12>:
 C_SIGNAL='@baseboard_fab2_lib.baseboard_fab2(sch_1):m_j_ma(12)';
NODE_NAME     U2D1 AG62
 '@BASEBOARD_FAB2_LIB.BASEBOARD_FAB2(SCH_1):PAGE59_I172@CHPSET_LIB.SKX_EXT_B(CHIPS)':
 'DDR2_MA'<12>: CDS_PINID='DDR2_MA(12)';
NODE_NAME     J1G3 65
 '@BASEBOARD_FAB2_LIB.BASEBOARD_FAB2(SCH_1):PAGE81_I186@MSTR_SCONN.SCONN288_H44441004(CHIPS)':
 'A12': CDS_PINID='A12';
NODE_NAME     J9U2 65
 '@BASEBOARD_FAB2_LIB.BASEBOARD_FAB2(SCH_1):PAGE82_I187@MSTR_SCONN.SCONN288_H44441003(CHIPS)':
 'A12': CDS_PINID='A12';
NET_NAME
'M_J_MA<13>'
 '@BASEBOARD_FAB2_LIB.BASEBOARD_FAB2(SCH_1):M_J_MA'<13>:
 C_SIGNAL='@baseboard_fab2_lib.baseboard_fab2(sch_1):m_j_ma(13)';
NODE_NAME     U2D1 AD53
 '@BASEBOARD_FAB2_LIB.BASEBOARD_FAB2(SCH_1):PAGE59_I172@CHPSET_LIB.SKX_EXT_B(CHIPS)':
 'DDR2_MA'<13>: CDS_PINID='DDR2_MA(13)';
NODE_NAME     J1G3 232
 '@BASEBOARD_FAB2_LIB.BASEBOARD_FAB2(SCH_1):PAGE81_I186@MSTR_SCONN.SCONN288_H44441004(CHIPS)':
 'A13': CDS_PINID='A13';
NODE_NAME     J9U2 232
 '@BASEBOARD_FAB2_LIB.BASEBOARD_FAB2(SCH_1):PAGE82_I187@MSTR_SCONN.SCONN288_H44441003(CHIPS)':
 'A13': CDS_PINID='A13';
NET_NAME
'M_J_MA<14>'
 '@BASEBOARD_FAB2_LIB.BASEBOARD_FAB2(SCH_1):M_J_MA'<14>:
 C_SIGNAL='@baseboard_fab2_lib.baseboard_fab2(sch_1):m_j_ma(14)';
NODE_NAME     U2D1 W50
 '@BASEBOARD_FAB2_LIB.BASEBOARD_FAB2(SCH_1):PAGE59_I172@CHPSET_LIB.SKX_EXT_B(CHIPS)':
 'DDR2_MA'<14>: CDS_PINID='DDR2_MA(14)';
NODE_NAME     J1G3 228
 '@BASEBOARD_FAB2_LIB.BASEBOARD_FAB2(SCH_1):PAGE81_I186@MSTR_SCONN.SCONN288_H44441004(CHIPS)':
 'A14_WE_N': CDS_PINID='A14_WE_N';
NODE_NAME     J9U2 228
 '@BASEBOARD_FAB2_LIB.BASEBOARD_FAB2(SCH_1):PAGE82_I187@MSTR_SCONN.SCONN288_H44441003(CHIPS)':
 'A14_WE_N': CDS_PINID='A14_WE_N';
NET_NAME
'M_J_MA<15>'
 '@BASEBOARD_FAB2_LIB.BASEBOARD_FAB2(SCH_1):M_J_MA'<15>:
 C_SIGNAL='@baseboard_fab2_lib.baseboard_fab2(sch_1):m_j_ma(15)';
NODE_NAME     U2D1 AE54
 '@BASEBOARD_FAB2_LIB.BASEBOARD_FAB2(SCH_1):PAGE59_I172@CHPSET_LIB.SKX_EXT_B(CHIPS)':
 'DDR2_MA'<15>: CDS_PINID='DDR2_MA(15)';
NODE_NAME     J1G3 86
 '@BASEBOARD_FAB2_LIB.BASEBOARD_FAB2(SCH_1):PAGE81_I186@MSTR_SCONN.SCONN288_H44441004(CHIPS)':
 'A15_CAS_N': CDS_PINID='A15_CAS_N';
NODE_NAME     J9U2 86
 '@BASEBOARD_FAB2_LIB.BASEBOARD_FAB2(SCH_1):PAGE82_I187@MSTR_SCONN.SCONN288_H44441003(CHIPS)':
 'A15_CAS_N': CDS_PINID='A15_CAS_N';
NET_NAME
'M_J_MA<16>'
 '@BASEBOARD_FAB2_LIB.BASEBOARD_FAB2(SCH_1):M_J_MA'<16>:
 C_SIGNAL='@baseboard_fab2_lib.baseboard_fab2(sch_1):m_j_ma(16)';
NODE_NAME     U2D1 AA52
 '@BASEBOARD_FAB2_LIB.BASEBOARD_FAB2(SCH_1):PAGE59_I172@CHPSET_LIB.SKX_EXT_B(CHIPS)':
 'DDR2_MA'<16>: CDS_PINID='DDR2_MA(16)';
NODE_NAME     J1G3 82
 '@BASEBOARD_FAB2_LIB.BASEBOARD_FAB2(SCH_1):PAGE81_I186@MSTR_SCONN.SCONN288_H44441004(CHIPS)':
 'A16_RAS_N': CDS_PINID='A16_RAS_N';
NODE_NAME     J9U2 82
 '@BASEBOARD_FAB2_LIB.BASEBOARD_FAB2(SCH_1):PAGE82_I187@MSTR_SCONN.SCONN288_H44441003(CHIPS)':
 'A16_RAS_N': CDS_PINID='A16_RAS_N';
NET_NAME
'M_J_MA<17>'
 '@BASEBOARD_FAB2_LIB.BASEBOARD_FAB2(SCH_1):M_J_MA'<17>:
 C_SIGNAL='@baseboard_fab2_lib.baseboard_fab2(sch_1):m_j_ma(17)';
NODE_NAME     U2D1 AC46
 '@BASEBOARD_FAB2_LIB.BASEBOARD_FAB2(SCH_1):PAGE59_I172@CHPSET_LIB.SKX_EXT_B(CHIPS)':
 'DDR2_MA'<17>: CDS_PINID='DDR2_MA(17)';
NODE_NAME     J1G3 234
 '@BASEBOARD_FAB2_LIB.BASEBOARD_FAB2(SCH_1):PAGE81_I186@MSTR_SCONN.SCONN288_H44441004(CHIPS)':
 'A17': CDS_PINID='A17';
NODE_NAME     J9U2 234
 '@BASEBOARD_FAB2_LIB.BASEBOARD_FAB2(SCH_1):PAGE82_I187@MSTR_SCONN.SCONN288_H44441003(CHIPS)':
 'A17': CDS_PINID='A17';
NET_NAME
'M_J_MA<1>'
 '@BASEBOARD_FAB2_LIB.BASEBOARD_FAB2(SCH_1):M_J_MA'<1>:
 C_SIGNAL='@baseboard_fab2_lib.baseboard_fab2(sch_1):m_j_ma(1)';
NODE_NAME     U2D1 AE58
 '@BASEBOARD_FAB2_LIB.BASEBOARD_FAB2(SCH_1):PAGE59_I172@CHPSET_LIB.SKX_EXT_B(CHIPS)':
 'DDR2_MA'<1>: CDS_PINID='DDR2_MA(1)';
NODE_NAME     J1G3 72
 '@BASEBOARD_FAB2_LIB.BASEBOARD_FAB2(SCH_1):PAGE81_I186@MSTR_SCONN.SCONN288_H44441004(CHIPS)':
 'A1': CDS_PINID='A1';
NODE_NAME     J9U2 72
 '@BASEBOARD_FAB2_LIB.BASEBOARD_FAB2(SCH_1):PAGE82_I187@MSTR_SCONN.SCONN288_H44441003(CHIPS)':
 'A1': CDS_PINID='A1';
NET_NAME
'M_J_MA<2>'
 '@BASEBOARD_FAB2_LIB.BASEBOARD_FAB2(SCH_1):M_J_MA'<2>:
 C_SIGNAL='@baseboard_fab2_lib.baseboard_fab2(sch_1):m_j_ma(2)';
NODE_NAME     U2D1 AD57
 '@BASEBOARD_FAB2_LIB.BASEBOARD_FAB2(SCH_1):PAGE59_I172@CHPSET_LIB.SKX_EXT_B(CHIPS)':
 'DDR2_MA'<2>: CDS_PINID='DDR2_MA(2)';
NODE_NAME     J1G3 216
 '@BASEBOARD_FAB2_LIB.BASEBOARD_FAB2(SCH_1):PAGE81_I186@MSTR_SCONN.SCONN288_H44441004(CHIPS)':
 'A2': CDS_PINID='A2';
NODE_NAME     J9U2 216
 '@BASEBOARD_FAB2_LIB.BASEBOARD_FAB2(SCH_1):PAGE82_I187@MSTR_SCONN.SCONN288_H44441003(CHIPS)':
 'A2': CDS_PINID='A2';
NET_NAME
'M_J_MA<3>'
 '@BASEBOARD_FAB2_LIB.BASEBOARD_FAB2(SCH_1):M_J_MA'<3>:
 C_SIGNAL='@baseboard_fab2_lib.baseboard_fab2(sch_1):m_j_ma(3)';
NODE_NAME     U2D1 W58
 '@BASEBOARD_FAB2_LIB.BASEBOARD_FAB2(SCH_1):PAGE59_I172@CHPSET_LIB.SKX_EXT_B(CHIPS)':
 'DDR2_MA'<3>: CDS_PINID='DDR2_MA(3)';
NODE_NAME     J1G3 71
 '@BASEBOARD_FAB2_LIB.BASEBOARD_FAB2(SCH_1):PAGE81_I186@MSTR_SCONN.SCONN288_H44441004(CHIPS)':
 'A3': CDS_PINID='A3';
NODE_NAME     J9U2 71
 '@BASEBOARD_FAB2_LIB.BASEBOARD_FAB2(SCH_1):PAGE82_I187@MSTR_SCONN.SCONN288_H44441003(CHIPS)':
 'A3': CDS_PINID='A3';
NET_NAME
'M_J_MA<4>'
 '@BASEBOARD_FAB2_LIB.BASEBOARD_FAB2(SCH_1):M_J_MA'<4>:
 C_SIGNAL='@baseboard_fab2_lib.baseboard_fab2(sch_1):m_j_ma(4)';
NODE_NAME     U2D1 AA58
 '@BASEBOARD_FAB2_LIB.BASEBOARD_FAB2(SCH_1):PAGE59_I172@CHPSET_LIB.SKX_EXT_B(CHIPS)':
 'DDR2_MA'<4>: CDS_PINID='DDR2_MA(4)';
NODE_NAME     J1G3 214
 '@BASEBOARD_FAB2_LIB.BASEBOARD_FAB2(SCH_1):PAGE81_I186@MSTR_SCONN.SCONN288_H44441004(CHIPS)':
 'A4': CDS_PINID='A4';
NODE_NAME     J9U2 214
 '@BASEBOARD_FAB2_LIB.BASEBOARD_FAB2(SCH_1):PAGE82_I187@MSTR_SCONN.SCONN288_H44441003(CHIPS)':
 'A4': CDS_PINID='A4';
NET_NAME
'M_J_MA<5>'
 '@BASEBOARD_FAB2_LIB.BASEBOARD_FAB2(SCH_1):M_J_MA'<5>:
 C_SIGNAL='@baseboard_fab2_lib.baseboard_fab2(sch_1):m_j_ma(5)';
NODE_NAME     U2D1 V59
 '@BASEBOARD_FAB2_LIB.BASEBOARD_FAB2(SCH_1):PAGE59_I172@CHPSET_LIB.SKX_EXT_B(CHIPS)':
 'DDR2_MA'<5>: CDS_PINID='DDR2_MA(5)';
NODE_NAME     J1G3 213
 '@BASEBOARD_FAB2_LIB.BASEBOARD_FAB2(SCH_1):PAGE81_I186@MSTR_SCONN.SCONN288_H44441004(CHIPS)':
 'A5': CDS_PINID='A5';
NODE_NAME     J9U2 213
 '@BASEBOARD_FAB2_LIB.BASEBOARD_FAB2(SCH_1):PAGE82_I187@MSTR_SCONN.SCONN288_H44441003(CHIPS)':
 'A5': CDS_PINID='A5';
NET_NAME
'M_J_MA<6>'
 '@BASEBOARD_FAB2_LIB.BASEBOARD_FAB2(SCH_1):M_J_MA'<6>:
 C_SIGNAL='@baseboard_fab2_lib.baseboard_fab2(sch_1):m_j_ma(6)';
NODE_NAME     U2D1 AB59
 '@BASEBOARD_FAB2_LIB.BASEBOARD_FAB2(SCH_1):PAGE59_I172@CHPSET_LIB.SKX_EXT_B(CHIPS)':
 'DDR2_MA'<6>: CDS_PINID='DDR2_MA(6)';
NODE_NAME     J1G3 69
 '@BASEBOARD_FAB2_LIB.BASEBOARD_FAB2(SCH_1):PAGE81_I186@MSTR_SCONN.SCONN288_H44441004(CHIPS)':
 'A6': CDS_PINID='A6';
NODE_NAME     J9U2 69
 '@BASEBOARD_FAB2_LIB.BASEBOARD_FAB2(SCH_1):PAGE82_I187@MSTR_SCONN.SCONN288_H44441003(CHIPS)':
 'A6': CDS_PINID='A6';
NET_NAME
'M_J_MA<7>'
 '@BASEBOARD_FAB2_LIB.BASEBOARD_FAB2(SCH_1):M_J_MA'<7>:
 C_SIGNAL='@baseboard_fab2_lib.baseboard_fab2(sch_1):m_j_ma(7)';
NODE_NAME     U2D1 AE60
 '@BASEBOARD_FAB2_LIB.BASEBOARD_FAB2(SCH_1):PAGE59_I172@CHPSET_LIB.SKX_EXT_B(CHIPS)':
 'DDR2_MA'<7>: CDS_PINID='DDR2_MA(7)';
NODE_NAME     J1G3 211
 '@BASEBOARD_FAB2_LIB.BASEBOARD_FAB2(SCH_1):PAGE81_I186@MSTR_SCONN.SCONN288_H44441004(CHIPS)':
 'A7': CDS_PINID='A7';
NODE_NAME     J9U2 211
 '@BASEBOARD_FAB2_LIB.BASEBOARD_FAB2(SCH_1):PAGE82_I187@MSTR_SCONN.SCONN288_H44441003(CHIPS)':
 'A7': CDS_PINID='A7';
NET_NAME
'M_J_MA<8>'
 '@BASEBOARD_FAB2_LIB.BASEBOARD_FAB2(SCH_1):M_J_MA'<8>:
 C_SIGNAL='@baseboard_fab2_lib.baseboard_fab2(sch_1):m_j_ma(8)';
NODE_NAME     U2D1 AD59
 '@BASEBOARD_FAB2_LIB.BASEBOARD_FAB2(SCH_1):PAGE59_I172@CHPSET_LIB.SKX_EXT_B(CHIPS)':
 'DDR2_MA'<8>: CDS_PINID='DDR2_MA(8)';
NODE_NAME     J1G3 68
 '@BASEBOARD_FAB2_LIB.BASEBOARD_FAB2(SCH_1):PAGE81_I186@MSTR_SCONN.SCONN288_H44441004(CHIPS)':
 'A8': CDS_PINID='A8';
NODE_NAME     J9U2 68
 '@BASEBOARD_FAB2_LIB.BASEBOARD_FAB2(SCH_1):PAGE82_I187@MSTR_SCONN.SCONN288_H44441003(CHIPS)':
 'A8': CDS_PINID='A8';
NET_NAME
'M_J_MA<9>'
 '@BASEBOARD_FAB2_LIB.BASEBOARD_FAB2(SCH_1):M_J_MA'<9>:
 C_SIGNAL='@baseboard_fab2_lib.baseboard_fab2(sch_1):m_j_ma(9)';
NODE_NAME     U2D1 AG58
 '@BASEBOARD_FAB2_LIB.BASEBOARD_FAB2(SCH_1):PAGE59_I172@CHPSET_LIB.SKX_EXT_B(CHIPS)':
 'DDR2_MA'<9>: CDS_PINID='DDR2_MA(9)';
NODE_NAME     J1G3 66
 '@BASEBOARD_FAB2_LIB.BASEBOARD_FAB2(SCH_1):PAGE81_I186@MSTR_SCONN.SCONN288_H44441004(CHIPS)':
 'A9': CDS_PINID='A9';
NODE_NAME     J9U2 66
 '@BASEBOARD_FAB2_LIB.BASEBOARD_FAB2(SCH_1):PAGE82_I187@MSTR_SCONN.SCONN288_H44441003(CHIPS)':
 'A9': CDS_PINID='A9';
NET_NAME
'M_J_ODT<0>'
 '@BASEBOARD_FAB2_LIB.BASEBOARD_FAB2(SCH_1):M_J_ODT'<0>:
 C_SIGNAL='@baseboard_fab2_lib.baseboard_fab2(sch_1):m_j_odt(0)';
NODE_NAME     U2D1 AA50
 '@BASEBOARD_FAB2_LIB.BASEBOARD_FAB2(SCH_1):PAGE59_I172@CHPSET_LIB.SKX_EXT_B(CHIPS)':
 'DDR2_ODT'<0>: CDS_PINID='DDR2_ODT(0)';
NODE_NAME     J1G3 87
 '@BASEBOARD_FAB2_LIB.BASEBOARD_FAB2(SCH_1):PAGE81_I186@MSTR_SCONN.SCONN288_H44441004(CHIPS)':
 'ODT'<0>: CDS_PINID='ODT(0)';
NET_NAME
'M_J_ODT<1>'
 '@BASEBOARD_FAB2_LIB.BASEBOARD_FAB2(SCH_1):M_J_ODT'<1>:
 C_SIGNAL='@baseboard_fab2_lib.baseboard_fab2(sch_1):m_j_odt(1)';
NODE_NAME     U2D1 AA48
 '@BASEBOARD_FAB2_LIB.BASEBOARD_FAB2(SCH_1):PAGE59_I172@CHPSET_LIB.SKX_EXT_B(CHIPS)':
 'DDR2_ODT'<1>: CDS_PINID='DDR2_ODT(1)';
NODE_NAME     J1G3 91
 '@BASEBOARD_FAB2_LIB.BASEBOARD_FAB2(SCH_1):PAGE81_I186@MSTR_SCONN.SCONN288_H44441004(CHIPS)':
 'ODT'<1>: CDS_PINID='ODT(1)';
NET_NAME
'M_J_ODT<2>'
 '@BASEBOARD_FAB2_LIB.BASEBOARD_FAB2(SCH_1):M_J_ODT'<2>:
 C_SIGNAL='@baseboard_fab2_lib.baseboard_fab2(sch_1):m_j_odt(2)';
NODE_NAME     U2D1 V49
 '@BASEBOARD_FAB2_LIB.BASEBOARD_FAB2(SCH_1):PAGE59_I172@CHPSET_LIB.SKX_EXT_B(CHIPS)':
 'DDR2_ODT'<2>: CDS_PINID='DDR2_ODT(2)';
NODE_NAME     J9U2 87
 '@BASEBOARD_FAB2_LIB.BASEBOARD_FAB2(SCH_1):PAGE82_I187@MSTR_SCONN.SCONN288_H44441003(CHIPS)':
 'ODT'<0>: CDS_PINID='ODT(0)';
NET_NAME
'M_J_ODT<3>'
 '@BASEBOARD_FAB2_LIB.BASEBOARD_FAB2(SCH_1):M_J_ODT'<3>:
 C_SIGNAL='@baseboard_fab2_lib.baseboard_fab2(sch_1):m_j_odt(3)';
NODE_NAME     U2D1 AB47
 '@BASEBOARD_FAB2_LIB.BASEBOARD_FAB2(SCH_1):PAGE59_I172@CHPSET_LIB.SKX_EXT_B(CHIPS)':
 'DDR2_ODT'<3>: CDS_PINID='DDR2_ODT(3)';
NODE_NAME     J9U2 91
 '@BASEBOARD_FAB2_LIB.BASEBOARD_FAB2(SCH_1):PAGE82_I187@MSTR_SCONN.SCONN288_H44441003(CHIPS)':
 'ODT'<1>: CDS_PINID='ODT(1)';
NET_NAME
'M_J_PAR'
 '@BASEBOARD_FAB2_LIB.BASEBOARD_FAB2(SCH_1):M_J_PAR':
 C_SIGNAL='@baseboard_fab2_lib.baseboard_fab2(sch_1):m_j_par';
NODE_NAME     U2D1 V53
 '@BASEBOARD_FAB2_LIB.BASEBOARD_FAB2(SCH_1):PAGE59_I172@CHPSET_LIB.SKX_EXT_B(CHIPS)':
 'DDR2_PAR': CDS_PINID='DDR2_PAR';
NODE_NAME     J1G3 222
 '@BASEBOARD_FAB2_LIB.BASEBOARD_FAB2(SCH_1):PAGE81_I186@MSTR_SCONN.SCONN288_H44441004(CHIPS)':
 'PAR': CDS_PINID='PAR';
NODE_NAME     J9U2 222
 '@BASEBOARD_FAB2_LIB.BASEBOARD_FAB2(SCH_1):PAGE82_I187@MSTR_SCONN.SCONN288_H44441003(CHIPS)':
 'PAR': CDS_PINID='PAR';
NET_NAME
'M_J_VREF'
 '@BASEBOARD_FAB2_LIB.BASEBOARD_FAB2(SCH_1):M_J_VREF':
 C_SIGNAL='@baseboard_fab2_lib.baseboard_fab2(sch_1):m_j_vref';
NODE_NAME     C9U10 1
 '@BASEBOARD_FAB2_LIB.BASEBOARD_FAB2(SCH_1):PAGE81_I178@DEV_DISCRETE.CAP_A(CHIPS)':
 'A': CDS_PINID='A';
NODE_NAME     J1G3 146
 '@BASEBOARD_FAB2_LIB.BASEBOARD_FAB2(SCH_1):PAGE81_I186@MSTR_SCONN.SCONN288_H44441004(CHIPS)':
 'VREFCA': CDS_PINID='VREFCA';
NODE_NAME     C1G19 1
 '@BASEBOARD_FAB2_LIB.BASEBOARD_FAB2(SCH_1):PAGE82_I180@DEV_DISCRETE.CAP_A(CHIPS)':
 'A': CDS_PINID='A';
NODE_NAME     J9U2 146
 '@BASEBOARD_FAB2_LIB.BASEBOARD_FAB2(SCH_1):PAGE82_I187@MSTR_SCONN.SCONN288_H44441003(CHIPS)':
 'VREFCA': CDS_PINID='VREFCA';
NODE_NAME     R1G15 2
 '@BASEBOARD_FAB2_LIB.BASEBOARD_FAB2(SCH_1):PAGE100_I35@MSTR_DISCRETE.RES(CHIPS)':
 'B': CDS_PINID='B';
NODE_NAME     R1G17 1
 '@BASEBOARD_FAB2_LIB.BASEBOARD_FAB2(SCH_1):PAGE100_I36@MSTR_DISCRETE.RES(CHIPS)':
 'A': CDS_PINID='A';
NODE_NAME     R1G14 2
 '@BASEBOARD_FAB2_LIB.BASEBOARD_FAB2(SCH_1):PAGE100_I41@MSTR_DISCRETE.RES(CHIPS)':
 'B': CDS_PINID='B';
NET_NAME
'M_KLM_RST_N'
 '@BASEBOARD_FAB2_LIB.BASEBOARD_FAB2(SCH_1):M_KLM_RST_N':
 C_SIGNAL='@baseboard_fab2_lib.baseboard_fab2(sch_1):m_klm_rst_n';
NODE_NAME     U2D1 DV63
 '@BASEBOARD_FAB2_LIB.BASEBOARD_FAB2(SCH_1):PAGE55_I172@CHPSET_LIB.SKX_EXT_B(CHIPS)':
 'DDR345_RESET_N': CDS_PINID='DDR345_RESET_N';
NODE_NAME     J1B1 58
 '@BASEBOARD_FAB2_LIB.BASEBOARD_FAB2(SCH_1):PAGE83_I111@MSTR_SCONN.SCONN288_H44441004(CHIPS)':
 'RESET_N': CDS_PINID='RESET_N';
NODE_NAME     J9M1 58
 '@BASEBOARD_FAB2_LIB.BASEBOARD_FAB2(SCH_1):PAGE84_I14@MSTR_SCONN.SCONN288_H44441003(CHIPS)':
 'RESET_N': CDS_PINID='RESET_N';
NODE_NAME     J1A2 58
 '@BASEBOARD_FAB2_LIB.BASEBOARD_FAB2(SCH_1):PAGE85_I111@MSTR_SCONN.SCONN288_H44441004(CHIPS)':
 'RESET_N': CDS_PINID='RESET_N';
NODE_NAME     J9L2 58
 '@BASEBOARD_FAB2_LIB.BASEBOARD_FAB2(SCH_1):PAGE86_I12@MSTR_SCONN.SCONN288_H44441003(CHIPS)':
 'RESET_N': CDS_PINID='RESET_N';
NODE_NAME     J1A1 58
 '@BASEBOARD_FAB2_LIB.BASEBOARD_FAB2(SCH_1):PAGE87_I186@MSTR_SCONN.SCONN288_H44441004(CHIPS)':
 'RESET_N': CDS_PINID='RESET_N';
NODE_NAME     J9L1 58
 '@BASEBOARD_FAB2_LIB.BASEBOARD_FAB2(SCH_1):PAGE88_I111@MSTR_SCONN.SCONN288_H44441003(CHIPS)':
 'RESET_N': CDS_PINID='RESET_N';
NET_NAME
'M_K_ACT_N'
 '@BASEBOARD_FAB2_LIB.BASEBOARD_FAB2(SCH_1):M_K_ACT_N':
 C_SIGNAL='@baseboard_fab2_lib.baseboard_fab2(sch_1):m_k_act_n';
NODE_NAME     U2D1 DW60
 '@BASEBOARD_FAB2_LIB.BASEBOARD_FAB2(SCH_1):PAGE60_I172@CHPSET_LIB.SKX_EXT_B(CHIPS)':
 'DDR3_ACT_N': CDS_PINID='DDR3_ACT_N';
NODE_NAME     J1B1 62
 '@BASEBOARD_FAB2_LIB.BASEBOARD_FAB2(SCH_1):PAGE83_I111@MSTR_SCONN.SCONN288_H44441004(CHIPS)':
 'ACT_N': CDS_PINID='ACT_N';
NODE_NAME     J9M1 62
 '@BASEBOARD_FAB2_LIB.BASEBOARD_FAB2(SCH_1):PAGE84_I14@MSTR_SCONN.SCONN288_H44441003(CHIPS)':
 'ACT_N': CDS_PINID='ACT_N';
NET_NAME
'M_K_ALERT_N'
 '@BASEBOARD_FAB2_LIB.BASEBOARD_FAB2(SCH_1):M_K_ALERT_N':
 C_SIGNAL='@baseboard_fab2_lib.baseboard_fab2(sch_1):m_k_alert_n';
NODE_NAME     U2D1 ED63
 '@BASEBOARD_FAB2_LIB.BASEBOARD_FAB2(SCH_1):PAGE60_I172@CHPSET_LIB.SKX_EXT_B(CHIPS)':
 'DDR3_ALERT_N': CDS_PINID='DDR3_ALERT_N';
NODE_NAME     J1B1 208
 '@BASEBOARD_FAB2_LIB.BASEBOARD_FAB2(SCH_1):PAGE83_I111@MSTR_SCONN.SCONN288_H44441004(CHIPS)':
 'ALERT_N': CDS_PINID='ALERT_N';
NODE_NAME     J9M1 208
 '@BASEBOARD_FAB2_LIB.BASEBOARD_FAB2(SCH_1):PAGE84_I14@MSTR_SCONN.SCONN288_H44441003(CHIPS)':
 'ALERT_N': CDS_PINID='ALERT_N';
NET_NAME
'M_K_BA<0>'
 '@BASEBOARD_FAB2_LIB.BASEBOARD_FAB2(SCH_1):M_K_BA'<0>:
 C_SIGNAL='@baseboard_fab2_lib.baseboard_fab2(sch_1):m_k_ba(0)';
NODE_NAME     U2D1 EE52
 '@BASEBOARD_FAB2_LIB.BASEBOARD_FAB2(SCH_1):PAGE60_I172@CHPSET_LIB.SKX_EXT_B(CHIPS)':
 'DDR3_BA'<0>: CDS_PINID='DDR3_BA(0)';
NODE_NAME     J1B1 81
 '@BASEBOARD_FAB2_LIB.BASEBOARD_FAB2(SCH_1):PAGE83_I111@MSTR_SCONN.SCONN288_H44441004(CHIPS)':
 'BA'<0>: CDS_PINID='BA(0)';
NODE_NAME     J9M1 81
 '@BASEBOARD_FAB2_LIB.BASEBOARD_FAB2(SCH_1):PAGE84_I14@MSTR_SCONN.SCONN288_H44441003(CHIPS)':
 'BA'<0>: CDS_PINID='BA(0)';
NET_NAME
'M_K_BA<1>'
 '@BASEBOARD_FAB2_LIB.BASEBOARD_FAB2(SCH_1):M_K_BA'<1>:
 C_SIGNAL='@baseboard_fab2_lib.baseboard_fab2(sch_1):m_k_ba(1)';
NODE_NAME     U2D1 EA54
 '@BASEBOARD_FAB2_LIB.BASEBOARD_FAB2(SCH_1):PAGE60_I172@CHPSET_LIB.SKX_EXT_B(CHIPS)':
 'DDR3_BA'<1>: CDS_PINID='DDR3_BA(1)';
NODE_NAME     J1B1 224
 '@BASEBOARD_FAB2_LIB.BASEBOARD_FAB2(SCH_1):PAGE83_I111@MSTR_SCONN.SCONN288_H44441004(CHIPS)':
 'BA'<1>: CDS_PINID='BA(1)';
NODE_NAME     J9M1 224
 '@BASEBOARD_FAB2_LIB.BASEBOARD_FAB2(SCH_1):PAGE84_I14@MSTR_SCONN.SCONN288_H44441003(CHIPS)':
 'BA'<1>: CDS_PINID='BA(1)';
NET_NAME
'M_K_BG<0>'
 '@BASEBOARD_FAB2_LIB.BASEBOARD_FAB2(SCH_1):M_K_BG'<0>:
 C_SIGNAL='@baseboard_fab2_lib.baseboard_fab2(sch_1):m_k_bg(0)';
NODE_NAME     U2D1 ED61
 '@BASEBOARD_FAB2_LIB.BASEBOARD_FAB2(SCH_1):PAGE60_I172@CHPSET_LIB.SKX_EXT_B(CHIPS)':
 'DDR3_BG'<0>: CDS_PINID='DDR3_BG(0)';
NODE_NAME     J1B1 63
 '@BASEBOARD_FAB2_LIB.BASEBOARD_FAB2(SCH_1):PAGE83_I111@MSTR_SCONN.SCONN288_H44441004(CHIPS)':
 'BG'<0>: CDS_PINID='BG(0)';
NODE_NAME     J9M1 63
 '@BASEBOARD_FAB2_LIB.BASEBOARD_FAB2(SCH_1):PAGE84_I14@MSTR_SCONN.SCONN288_H44441003(CHIPS)':
 'BG'<0>: CDS_PINID='BG(0)';
NET_NAME
'M_K_BG<1>'
 '@BASEBOARD_FAB2_LIB.BASEBOARD_FAB2(SCH_1):M_K_BG'<1>:
 C_SIGNAL='@baseboard_fab2_lib.baseboard_fab2(sch_1):m_k_bg(1)';
NODE_NAME     U2D1 DW62
 '@BASEBOARD_FAB2_LIB.BASEBOARD_FAB2(SCH_1):PAGE60_I172@CHPSET_LIB.SKX_EXT_B(CHIPS)':
 'DDR3_BG'<1>: CDS_PINID='DDR3_BG(1)';
NODE_NAME     J1B1 207
 '@BASEBOARD_FAB2_LIB.BASEBOARD_FAB2(SCH_1):PAGE83_I111@MSTR_SCONN.SCONN288_H44441004(CHIPS)':
 'BG'<1>: CDS_PINID='BG(1)';
NODE_NAME     J9M1 207
 '@BASEBOARD_FAB2_LIB.BASEBOARD_FAB2(SCH_1):PAGE84_I14@MSTR_SCONN.SCONN288_H44441003(CHIPS)':
 'BG'<1>: CDS_PINID='BG(1)';
NET_NAME
'M_K_C<2>'
 '@BASEBOARD_FAB2_LIB.BASEBOARD_FAB2(SCH_1):M_K_C'<2>:
 C_SIGNAL='@baseboard_fab2_lib.baseboard_fab2(sch_1):m_k_c(2)';
NODE_NAME     U2D1 DV47
 '@BASEBOARD_FAB2_LIB.BASEBOARD_FAB2(SCH_1):PAGE60_I172@CHPSET_LIB.SKX_EXT_B(CHIPS)':
 'DDR3_CID'<2>: CDS_PINID='DDR3_CID(2)';
NODE_NAME     J1B1 235
 '@BASEBOARD_FAB2_LIB.BASEBOARD_FAB2(SCH_1):PAGE83_I111@MSTR_SCONN.SCONN288_H44441004(CHIPS)':
 'C'<2>: CDS_PINID='C(2)';
NODE_NAME     J9M1 235
 '@BASEBOARD_FAB2_LIB.BASEBOARD_FAB2(SCH_1):PAGE84_I14@MSTR_SCONN.SCONN288_H44441003(CHIPS)':
 'C'<2>: CDS_PINID='C(2)';
NET_NAME
'M_K_CKE<0>'
 '@BASEBOARD_FAB2_LIB.BASEBOARD_FAB2(SCH_1):M_K_CKE'<0>:
 C_SIGNAL='@baseboard_fab2_lib.baseboard_fab2(sch_1):m_k_cke(0)';
NODE_NAME     U2D1 EE62
 '@BASEBOARD_FAB2_LIB.BASEBOARD_FAB2(SCH_1):PAGE60_I172@CHPSET_LIB.SKX_EXT_B(CHIPS)':
 'DDR3_CKE'<0>: CDS_PINID='DDR3_CKE(0)';
NODE_NAME     J1B1 60
 '@BASEBOARD_FAB2_LIB.BASEBOARD_FAB2(SCH_1):PAGE83_I111@MSTR_SCONN.SCONN288_H44441004(CHIPS)':
 'CKE'<0>: CDS_PINID='CKE(0)';
NET_NAME
'M_K_CKE<1>'
 '@BASEBOARD_FAB2_LIB.BASEBOARD_FAB2(SCH_1):M_K_CKE'<1>:
 C_SIGNAL='@baseboard_fab2_lib.baseboard_fab2(sch_1):m_k_cke(1)';
NODE_NAME     U2D1 EF63
 '@BASEBOARD_FAB2_LIB.BASEBOARD_FAB2(SCH_1):PAGE60_I172@CHPSET_LIB.SKX_EXT_B(CHIPS)':
 'DDR3_CKE'<1>: CDS_PINID='DDR3_CKE(1)';
NODE_NAME     J1B1 203
 '@BASEBOARD_FAB2_LIB.BASEBOARD_FAB2(SCH_1):PAGE83_I111@MSTR_SCONN.SCONN288_H44441004(CHIPS)':
 'CKE'<1>: CDS_PINID='CKE(1)';
NET_NAME
'M_K_CKE<2>'
 '@BASEBOARD_FAB2_LIB.BASEBOARD_FAB2(SCH_1):M_K_CKE'<2>:
 C_SIGNAL='@baseboard_fab2_lib.baseboard_fab2(sch_1):m_k_cke(2)';
NODE_NAME     U2D1 EA62
 '@BASEBOARD_FAB2_LIB.BASEBOARD_FAB2(SCH_1):PAGE60_I172@CHPSET_LIB.SKX_EXT_B(CHIPS)':
 'DDR3_CKE'<2>: CDS_PINID='DDR3_CKE(2)';
NODE_NAME     J9M1 60
 '@BASEBOARD_FAB2_LIB.BASEBOARD_FAB2(SCH_1):PAGE84_I14@MSTR_SCONN.SCONN288_H44441003(CHIPS)':
 'CKE'<0>: CDS_PINID='CKE(0)';
NET_NAME
'M_K_CKE<3>'
 '@BASEBOARD_FAB2_LIB.BASEBOARD_FAB2(SCH_1):M_K_CKE'<3>:
 C_SIGNAL='@baseboard_fab2_lib.baseboard_fab2(sch_1):m_k_cke(3)';
NODE_NAME     U2D1 EB63
 '@BASEBOARD_FAB2_LIB.BASEBOARD_FAB2(SCH_1):PAGE60_I172@CHPSET_LIB.SKX_EXT_B(CHIPS)':
 'DDR3_CKE'<3>: CDS_PINID='DDR3_CKE(3)';
NODE_NAME     J9M1 203
 '@BASEBOARD_FAB2_LIB.BASEBOARD_FAB2(SCH_1):PAGE84_I14@MSTR_SCONN.SCONN288_H44441003(CHIPS)':
 'CKE'<1>: CDS_PINID='CKE(1)';
NET_NAME
'M_K_CLK_DN<0>'
 '@BASEBOARD_FAB2_LIB.BASEBOARD_FAB2(SCH_1):M_K_CLK_DN'<0>:
 C_SIGNAL='@baseboard_fab2_lib.baseboard_fab2(sch_1):m_k_clk_dn(0)';
NODE_NAME     U2D1 ED55
 '@BASEBOARD_FAB2_LIB.BASEBOARD_FAB2(SCH_1):PAGE60_I172@CHPSET_LIB.SKX_EXT_B(CHIPS)':
 'DDR3_CLK_DN'<0>: CDS_PINID='DDR3_CLK_DN(0)';
NODE_NAME     J1B1 75
 '@BASEBOARD_FAB2_LIB.BASEBOARD_FAB2(SCH_1):PAGE83_I111@MSTR_SCONN.SCONN288_H44441004(CHIPS)':
 'CK0N': CDS_PINID='CK0N';
NET_NAME
'M_K_CLK_DN<1>'
 '@BASEBOARD_FAB2_LIB.BASEBOARD_FAB2(SCH_1):M_K_CLK_DN'<1>:
 C_SIGNAL='@baseboard_fab2_lib.baseboard_fab2(sch_1):m_k_clk_dn(1)';
NODE_NAME     U2D1 EF55
 '@BASEBOARD_FAB2_LIB.BASEBOARD_FAB2(SCH_1):PAGE60_I172@CHPSET_LIB.SKX_EXT_B(CHIPS)':
 'DDR3_CLK_DN'<1>: CDS_PINID='DDR3_CLK_DN(1)';
NODE_NAME     J1B1 219
 '@BASEBOARD_FAB2_LIB.BASEBOARD_FAB2(SCH_1):PAGE83_I111@MSTR_SCONN.SCONN288_H44441004(CHIPS)':
 'CK1N': CDS_PINID='CK1N';
NET_NAME
'M_K_CLK_DN<2>'
 '@BASEBOARD_FAB2_LIB.BASEBOARD_FAB2(SCH_1):M_K_CLK_DN'<2>:
 C_SIGNAL='@baseboard_fab2_lib.baseboard_fab2(sch_1):m_k_clk_dn(2)';
NODE_NAME     U2D1 DW56
 '@BASEBOARD_FAB2_LIB.BASEBOARD_FAB2(SCH_1):PAGE60_I172@CHPSET_LIB.SKX_EXT_B(CHIPS)':
 'DDR3_CLK_DN'<2>: CDS_PINID='DDR3_CLK_DN(2)';
NODE_NAME     J9M1 75
 '@BASEBOARD_FAB2_LIB.BASEBOARD_FAB2(SCH_1):PAGE84_I14@MSTR_SCONN.SCONN288_H44441003(CHIPS)':
 'CK0N': CDS_PINID='CK0N';
NET_NAME
'M_K_CLK_DN<3>'
 '@BASEBOARD_FAB2_LIB.BASEBOARD_FAB2(SCH_1):M_K_CLK_DN'<3>:
 C_SIGNAL='@baseboard_fab2_lib.baseboard_fab2(sch_1):m_k_clk_dn(3)';
NODE_NAME     U2D1 EF57
 '@BASEBOARD_FAB2_LIB.BASEBOARD_FAB2(SCH_1):PAGE60_I172@CHPSET_LIB.SKX_EXT_B(CHIPS)':
 'DDR3_CLK_DN'<3>: CDS_PINID='DDR3_CLK_DN(3)';
NODE_NAME     J9M1 219
 '@BASEBOARD_FAB2_LIB.BASEBOARD_FAB2(SCH_1):PAGE84_I14@MSTR_SCONN.SCONN288_H44441003(CHIPS)':
 'CK1N': CDS_PINID='CK1N';
NET_NAME
'M_K_CLK_DP<0>'
 '@BASEBOARD_FAB2_LIB.BASEBOARD_FAB2(SCH_1):M_K_CLK_DP'<0>:
 C_SIGNAL='@baseboard_fab2_lib.baseboard_fab2(sch_1):m_k_clk_dp(0)';
NODE_NAME     U2D1 EB55
 '@BASEBOARD_FAB2_LIB.BASEBOARD_FAB2(SCH_1):PAGE60_I172@CHPSET_LIB.SKX_EXT_B(CHIPS)':
 'DDR3_CLK_DP'<0>: CDS_PINID='DDR3_CLK_DP(0)';
NODE_NAME     J1B1 74
 '@BASEBOARD_FAB2_LIB.BASEBOARD_FAB2(SCH_1):PAGE83_I111@MSTR_SCONN.SCONN288_H44441004(CHIPS)':
 'CK0P': CDS_PINID='CK0P';
NET_NAME
'M_K_CLK_DP<1>'
 '@BASEBOARD_FAB2_LIB.BASEBOARD_FAB2(SCH_1):M_K_CLK_DP'<1>:
 C_SIGNAL='@baseboard_fab2_lib.baseboard_fab2(sch_1):m_k_clk_dp(1)';
NODE_NAME     U2D1 EE54
 '@BASEBOARD_FAB2_LIB.BASEBOARD_FAB2(SCH_1):PAGE60_I172@CHPSET_LIB.SKX_EXT_B(CHIPS)':
 'DDR3_CLK_DP'<1>: CDS_PINID='DDR3_CLK_DP(1)';
NODE_NAME     J1B1 218
 '@BASEBOARD_FAB2_LIB.BASEBOARD_FAB2(SCH_1):PAGE83_I111@MSTR_SCONN.SCONN288_H44441004(CHIPS)':
 'CK1P': CDS_PINID='CK1P';
NET_NAME
'M_K_CLK_DP<2>'
 '@BASEBOARD_FAB2_LIB.BASEBOARD_FAB2(SCH_1):M_K_CLK_DP'<2>:
 C_SIGNAL='@baseboard_fab2_lib.baseboard_fab2(sch_1):m_k_clk_dp(2)';
NODE_NAME     U2D1 EA56
 '@BASEBOARD_FAB2_LIB.BASEBOARD_FAB2(SCH_1):PAGE60_I172@CHPSET_LIB.SKX_EXT_B(CHIPS)':
 'DDR3_CLK_DP'<2>: CDS_PINID='DDR3_CLK_DP(2)';
NODE_NAME     J9M1 74
 '@BASEBOARD_FAB2_LIB.BASEBOARD_FAB2(SCH_1):PAGE84_I14@MSTR_SCONN.SCONN288_H44441003(CHIPS)':
 'CK0P': CDS_PINID='CK0P';
NET_NAME
'M_K_CLK_DP<3>'
 '@BASEBOARD_FAB2_LIB.BASEBOARD_FAB2(SCH_1):M_K_CLK_DP'<3>:
 C_SIGNAL='@baseboard_fab2_lib.baseboard_fab2(sch_1):m_k_clk_dp(3)';
NODE_NAME     U2D1 EE56
 '@BASEBOARD_FAB2_LIB.BASEBOARD_FAB2(SCH_1):PAGE60_I172@CHPSET_LIB.SKX_EXT_B(CHIPS)':
 'DDR3_CLK_DP'<3>: CDS_PINID='DDR3_CLK_DP(3)';
NODE_NAME     J9M1 218
 '@BASEBOARD_FAB2_LIB.BASEBOARD_FAB2(SCH_1):PAGE84_I14@MSTR_SCONN.SCONN288_H44441003(CHIPS)':
 'CK1P': CDS_PINID='CK1P';
NET_NAME
'M_K_CPU_VREF'
 '@BASEBOARD_FAB2_LIB.BASEBOARD_FAB2(SCH_1):M_K_CPU_VREF':
 C_SIGNAL='@baseboard_fab2_lib.baseboard_fab2(sch_1):m_k_cpu_vref';
NODE_NAME     U2D1 CP61
 '@BASEBOARD_FAB2_LIB.BASEBOARD_FAB2(SCH_1):PAGE55_I172@CHPSET_LIB.SKX_EXT_B(CHIPS)':
 'DDR3_CAVREF': CDS_PINID='DDR3_CAVREF';
NODE_NAME     R9M2 1
 '@BASEBOARD_FAB2_LIB.BASEBOARD_FAB2(SCH_1):PAGE100_I13@MSTR_DISCRETE.RES(CHIPS)':
 'A': CDS_PINID='A';
NODE_NAME     C9M2 1
 '@BASEBOARD_FAB2_LIB.BASEBOARD_FAB2(SCH_1):PAGE100_I15@DEV_DISCRETE.CAP_A(CHIPS)':
 'A': CDS_PINID='A';
NET_NAME
'M_K_CS_N<0>'
 '@BASEBOARD_FAB2_LIB.BASEBOARD_FAB2(SCH_1):M_K_CS_N'<0>:
 C_SIGNAL='@baseboard_fab2_lib.baseboard_fab2(sch_1):m_k_cs_n(0)';
NODE_NAME     U2D1 EF51
 '@BASEBOARD_FAB2_LIB.BASEBOARD_FAB2(SCH_1):PAGE60_I172@CHPSET_LIB.SKX_EXT_B(CHIPS)':
 'DDR3_CS_N'<0>: CDS_PINID='DDR3_CS_N(0)';
NODE_NAME     J1B1 84
 '@BASEBOARD_FAB2_LIB.BASEBOARD_FAB2(SCH_1):PAGE83_I111@MSTR_SCONN.SCONN288_H44441004(CHIPS)':
 'S0_N': CDS_PINID='S0_N';
NET_NAME
'M_K_CS_N<1>'
 '@BASEBOARD_FAB2_LIB.BASEBOARD_FAB2(SCH_1):M_K_CS_N'<1>:
 C_SIGNAL='@baseboard_fab2_lib.baseboard_fab2(sch_1):m_k_cs_n(1)';
NODE_NAME     U2D1 ED49
 '@BASEBOARD_FAB2_LIB.BASEBOARD_FAB2(SCH_1):PAGE60_I172@CHPSET_LIB.SKX_EXT_B(CHIPS)':
 'DDR3_CS_N'<1>: CDS_PINID='DDR3_CS_N(1)';
NODE_NAME     J1B1 89
 '@BASEBOARD_FAB2_LIB.BASEBOARD_FAB2(SCH_1):PAGE83_I111@MSTR_SCONN.SCONN288_H44441004(CHIPS)':
 'S1_N': CDS_PINID='S1_N';
NET_NAME
'M_K_CS_N<2>'
 '@BASEBOARD_FAB2_LIB.BASEBOARD_FAB2(SCH_1):M_K_CS_N'<2>:
 C_SIGNAL='@baseboard_fab2_lib.baseboard_fab2(sch_1):m_k_cs_n(2)';
NODE_NAME     U2D1 ED47
 '@BASEBOARD_FAB2_LIB.BASEBOARD_FAB2(SCH_1):PAGE60_I172@CHPSET_LIB.SKX_EXT_B(CHIPS)':
 'DDR3_CS_N'<2>: CDS_PINID='DDR3_CS_N(2)';
NODE_NAME     J1B1 93
 '@BASEBOARD_FAB2_LIB.BASEBOARD_FAB2(SCH_1):PAGE83_I111@MSTR_SCONN.SCONN288_H44441004(CHIPS)':
 'S2_N_C'<0>: CDS_PINID='S2_N_C(0)';
NET_NAME
'M_K_CS_N<3>'
 '@BASEBOARD_FAB2_LIB.BASEBOARD_FAB2(SCH_1):M_K_CS_N'<3>:
 C_SIGNAL='@baseboard_fab2_lib.baseboard_fab2(sch_1):m_k_cs_n(3)';
NODE_NAME     U2D1 EB47
 '@BASEBOARD_FAB2_LIB.BASEBOARD_FAB2(SCH_1):PAGE60_I172@CHPSET_LIB.SKX_EXT_B(CHIPS)':
 'DDR3_CS_N'<3>: CDS_PINID='DDR3_CS_N(3)';
NODE_NAME     J1B1 237
 '@BASEBOARD_FAB2_LIB.BASEBOARD_FAB2(SCH_1):PAGE83_I111@MSTR_SCONN.SCONN288_H44441004(CHIPS)':
 'S3_N_C'<1>: CDS_PINID='S3_N_C(1)';
NET_NAME
'M_K_CS_N<4>'
 '@BASEBOARD_FAB2_LIB.BASEBOARD_FAB2(SCH_1):M_K_CS_N'<4>:
 C_SIGNAL='@baseboard_fab2_lib.baseboard_fab2(sch_1):m_k_cs_n(4)';
NODE_NAME     U2D1 EB51
 '@BASEBOARD_FAB2_LIB.BASEBOARD_FAB2(SCH_1):PAGE60_I172@CHPSET_LIB.SKX_EXT_B(CHIPS)':
 'DDR3_CS_N'<4>: CDS_PINID='DDR3_CS_N(4)';
NODE_NAME     J9M1 84
 '@BASEBOARD_FAB2_LIB.BASEBOARD_FAB2(SCH_1):PAGE84_I14@MSTR_SCONN.SCONN288_H44441003(CHIPS)':
 'S0_N': CDS_PINID='S0_N';
NET_NAME
'M_K_CS_N<5>'
 '@BASEBOARD_FAB2_LIB.BASEBOARD_FAB2(SCH_1):M_K_CS_N'<5>:
 C_SIGNAL='@baseboard_fab2_lib.baseboard_fab2(sch_1):m_k_cs_n(5)';
NODE_NAME     U2D1 EB49
 '@BASEBOARD_FAB2_LIB.BASEBOARD_FAB2(SCH_1):PAGE60_I172@CHPSET_LIB.SKX_EXT_B(CHIPS)':
 'DDR3_CS_N'<5>: CDS_PINID='DDR3_CS_N(5)';
NODE_NAME     J9M1 89
 '@BASEBOARD_FAB2_LIB.BASEBOARD_FAB2(SCH_1):PAGE84_I14@MSTR_SCONN.SCONN288_H44441003(CHIPS)':
 'S1_N': CDS_PINID='S1_N';
NET_NAME
'M_K_CS_N<6>'
 '@BASEBOARD_FAB2_LIB.BASEBOARD_FAB2(SCH_1):M_K_CS_N'<6>:
 C_SIGNAL='@baseboard_fab2_lib.baseboard_fab2(sch_1):m_k_cs_n(6)';
NODE_NAME     U2D1 DV45
 '@BASEBOARD_FAB2_LIB.BASEBOARD_FAB2(SCH_1):PAGE60_I172@CHPSET_LIB.SKX_EXT_B(CHIPS)':
 'DDR3_CS_N'<6>: CDS_PINID='DDR3_CS_N(6)';
NODE_NAME     J9M1 93
 '@BASEBOARD_FAB2_LIB.BASEBOARD_FAB2(SCH_1):PAGE84_I14@MSTR_SCONN.SCONN288_H44441003(CHIPS)':
 'S2_N_C'<0>: CDS_PINID='S2_N_C(0)';
NET_NAME
'M_K_CS_N<7>'
 '@BASEBOARD_FAB2_LIB.BASEBOARD_FAB2(SCH_1):M_K_CS_N'<7>:
 C_SIGNAL='@baseboard_fab2_lib.baseboard_fab2(sch_1):m_k_cs_n(7)';
NODE_NAME     U2D1 EB45
 '@BASEBOARD_FAB2_LIB.BASEBOARD_FAB2(SCH_1):PAGE60_I172@CHPSET_LIB.SKX_EXT_B(CHIPS)':
 'DDR3_CS_N'<7>: CDS_PINID='DDR3_CS_N(7)';
NODE_NAME     J9M1 237
 '@BASEBOARD_FAB2_LIB.BASEBOARD_FAB2(SCH_1):PAGE84_I14@MSTR_SCONN.SCONN288_H44441003(CHIPS)':
 'S3_N_C'<1>: CDS_PINID='S3_N_C(1)';
NET_NAME
'M_K_DQ<0>'
 '@BASEBOARD_FAB2_LIB.BASEBOARD_FAB2(SCH_1):M_K_DQ'<0>:
 C_SIGNAL='@baseboard_fab2_lib.baseboard_fab2(sch_1):m_k_dq(0)';
NODE_NAME     U2D1 CN84
 '@BASEBOARD_FAB2_LIB.BASEBOARD_FAB2(SCH_1):PAGE60_I172@CHPSET_LIB.SKX_EXT_B(CHIPS)':
 'DDR3_DQ'<0>: CDS_PINID='DDR3_DQ(0)';
NODE_NAME     J1B1 150
 '@BASEBOARD_FAB2_LIB.BASEBOARD_FAB2(SCH_1):PAGE83_I111@MSTR_SCONN.SCONN288_H44441004(CHIPS)':
 'DQ'<1>: CDS_PINID='DQ(1)';
NODE_NAME     J9M1 5
 '@BASEBOARD_FAB2_LIB.BASEBOARD_FAB2(SCH_1):PAGE84_I14@MSTR_SCONN.SCONN288_H44441003(CHIPS)':
 'DQ'<0>: CDS_PINID='DQ(0)';
NET_NAME
'M_K_DQ<10>'
 '@BASEBOARD_FAB2_LIB.BASEBOARD_FAB2(SCH_1):M_K_DQ'<10>:
 C_SIGNAL='@baseboard_fab2_lib.baseboard_fab2(sch_1):m_k_dq(10)';
NODE_NAME     U2D1 DV83
 '@BASEBOARD_FAB2_LIB.BASEBOARD_FAB2(SCH_1):PAGE60_I172@CHPSET_LIB.SKX_EXT_B(CHIPS)':
 'DDR3_DQ'<10>: CDS_PINID='DDR3_DQ(10)';
NODE_NAME     J1B1 168
 '@BASEBOARD_FAB2_LIB.BASEBOARD_FAB2(SCH_1):PAGE83_I111@MSTR_SCONN.SCONN288_H44441004(CHIPS)':
 'DQ'<11>: CDS_PINID='DQ(11)';
NODE_NAME     J9M1 23
 '@BASEBOARD_FAB2_LIB.BASEBOARD_FAB2(SCH_1):PAGE84_I14@MSTR_SCONN.SCONN288_H44441003(CHIPS)':
 'DQ'<10>: CDS_PINID='DQ(10)';
NET_NAME
'M_K_DQ<11>'
 '@BASEBOARD_FAB2_LIB.BASEBOARD_FAB2(SCH_1):M_K_DQ'<11>:
 C_SIGNAL='@baseboard_fab2_lib.baseboard_fab2(sch_1):m_k_dq(11)';
NODE_NAME     U2D1 DY83
 '@BASEBOARD_FAB2_LIB.BASEBOARD_FAB2(SCH_1):PAGE60_I172@CHPSET_LIB.SKX_EXT_B(CHIPS)':
 'DDR3_DQ'<11>: CDS_PINID='DDR3_DQ(11)';
NODE_NAME     J1B1 23
 '@BASEBOARD_FAB2_LIB.BASEBOARD_FAB2(SCH_1):PAGE83_I111@MSTR_SCONN.SCONN288_H44441004(CHIPS)':
 'DQ'<10>: CDS_PINID='DQ(10)';
NODE_NAME     J9M1 168
 '@BASEBOARD_FAB2_LIB.BASEBOARD_FAB2(SCH_1):PAGE84_I14@MSTR_SCONN.SCONN288_H44441003(CHIPS)':
 'DQ'<11>: CDS_PINID='DQ(11)';
NET_NAME
'M_K_DQ<12>'
 '@BASEBOARD_FAB2_LIB.BASEBOARD_FAB2(SCH_1):M_K_DQ'<12>:
 C_SIGNAL='@baseboard_fab2_lib.baseboard_fab2(sch_1):m_k_dq(12)';
NODE_NAME     U2D1 DD85
 '@BASEBOARD_FAB2_LIB.BASEBOARD_FAB2(SCH_1):PAGE60_I172@CHPSET_LIB.SKX_EXT_B(CHIPS)':
 'DDR3_DQ'<12>: CDS_PINID='DDR3_DQ(12)';
NODE_NAME     J1B1 159
 '@BASEBOARD_FAB2_LIB.BASEBOARD_FAB2(SCH_1):PAGE83_I111@MSTR_SCONN.SCONN288_H44441004(CHIPS)':
 'DQ'<13>: CDS_PINID='DQ(13)';
NODE_NAME     J9M1 14
 '@BASEBOARD_FAB2_LIB.BASEBOARD_FAB2(SCH_1):PAGE84_I14@MSTR_SCONN.SCONN288_H44441003(CHIPS)':
 'DQ'<12>: CDS_PINID='DQ(12)';
NET_NAME
'M_K_DQ<13>'
 '@BASEBOARD_FAB2_LIB.BASEBOARD_FAB2(SCH_1):M_K_DQ'<13>:
 C_SIGNAL='@baseboard_fab2_lib.baseboard_fab2(sch_1):m_k_dq(13)';
NODE_NAME     U2D1 DE84
 '@BASEBOARD_FAB2_LIB.BASEBOARD_FAB2(SCH_1):PAGE60_I172@CHPSET_LIB.SKX_EXT_B(CHIPS)':
 'DDR3_DQ'<13>: CDS_PINID='DDR3_DQ(13)';
NODE_NAME     J1B1 14
 '@BASEBOARD_FAB2_LIB.BASEBOARD_FAB2(SCH_1):PAGE83_I111@MSTR_SCONN.SCONN288_H44441004(CHIPS)':
 'DQ'<12>: CDS_PINID='DQ(12)';
NODE_NAME     J9M1 159
 '@BASEBOARD_FAB2_LIB.BASEBOARD_FAB2(SCH_1):PAGE84_I14@MSTR_SCONN.SCONN288_H44441003(CHIPS)':
 'DQ'<13>: CDS_PINID='DQ(13)';
NET_NAME
'M_K_DQ<14>'
 '@BASEBOARD_FAB2_LIB.BASEBOARD_FAB2(SCH_1):M_K_DQ'<14>:
 C_SIGNAL='@baseboard_fab2_lib.baseboard_fab2(sch_1):m_k_dq(14)';
NODE_NAME     U2D1 DR84
 '@BASEBOARD_FAB2_LIB.BASEBOARD_FAB2(SCH_1):PAGE60_I172@CHPSET_LIB.SKX_EXT_B(CHIPS)':
 'DDR3_DQ'<14>: CDS_PINID='DDR3_DQ(14)';
NODE_NAME     J1B1 166
 '@BASEBOARD_FAB2_LIB.BASEBOARD_FAB2(SCH_1):PAGE83_I111@MSTR_SCONN.SCONN288_H44441004(CHIPS)':
 'DQ'<15>: CDS_PINID='DQ(15)';
NODE_NAME     J9M1 21
 '@BASEBOARD_FAB2_LIB.BASEBOARD_FAB2(SCH_1):PAGE84_I14@MSTR_SCONN.SCONN288_H44441003(CHIPS)':
 'DQ'<14>: CDS_PINID='DQ(14)';
NET_NAME
'M_K_DQ<15>'
 '@BASEBOARD_FAB2_LIB.BASEBOARD_FAB2(SCH_1):M_K_DQ'<15>:
 C_SIGNAL='@baseboard_fab2_lib.baseboard_fab2(sch_1):m_k_dq(15)';
NODE_NAME     U2D1 DV85
 '@BASEBOARD_FAB2_LIB.BASEBOARD_FAB2(SCH_1):PAGE60_I172@CHPSET_LIB.SKX_EXT_B(CHIPS)':
 'DDR3_DQ'<15>: CDS_PINID='DDR3_DQ(15)';
NODE_NAME     J1B1 21
 '@BASEBOARD_FAB2_LIB.BASEBOARD_FAB2(SCH_1):PAGE83_I111@MSTR_SCONN.SCONN288_H44441004(CHIPS)':
 'DQ'<14>: CDS_PINID='DQ(14)';
NODE_NAME     J9M1 166
 '@BASEBOARD_FAB2_LIB.BASEBOARD_FAB2(SCH_1):PAGE84_I14@MSTR_SCONN.SCONN288_H44441003(CHIPS)':
 'DQ'<15>: CDS_PINID='DQ(15)';
NET_NAME
'M_K_DQ<16>'
 '@BASEBOARD_FAB2_LIB.BASEBOARD_FAB2(SCH_1):M_K_DQ'<16>:
 C_SIGNAL='@baseboard_fab2_lib.baseboard_fab2(sch_1):m_k_dq(16)';
NODE_NAME     U2D1 DM79
 '@BASEBOARD_FAB2_LIB.BASEBOARD_FAB2(SCH_1):PAGE60_I172@CHPSET_LIB.SKX_EXT_B(CHIPS)':
 'DDR3_DQ'<16>: CDS_PINID='DDR3_DQ(16)';
NODE_NAME     J1B1 172
 '@BASEBOARD_FAB2_LIB.BASEBOARD_FAB2(SCH_1):PAGE83_I111@MSTR_SCONN.SCONN288_H44441004(CHIPS)':
 'DQ'<17>: CDS_PINID='DQ(17)';
NODE_NAME     J9M1 27
 '@BASEBOARD_FAB2_LIB.BASEBOARD_FAB2(SCH_1):PAGE84_I14@MSTR_SCONN.SCONN288_H44441003(CHIPS)':
 'DQ'<16>: CDS_PINID='DQ(16)';
NET_NAME
'M_K_DQ<17>'
 '@BASEBOARD_FAB2_LIB.BASEBOARD_FAB2(SCH_1):M_K_DQ'<17>:
 C_SIGNAL='@baseboard_fab2_lib.baseboard_fab2(sch_1):m_k_dq(17)';
NODE_NAME     U2D1 DK81
 '@BASEBOARD_FAB2_LIB.BASEBOARD_FAB2(SCH_1):PAGE60_I172@CHPSET_LIB.SKX_EXT_B(CHIPS)':
 'DDR3_DQ'<17>: CDS_PINID='DDR3_DQ(17)';
NODE_NAME     J1B1 27
 '@BASEBOARD_FAB2_LIB.BASEBOARD_FAB2(SCH_1):PAGE83_I111@MSTR_SCONN.SCONN288_H44441004(CHIPS)':
 'DQ'<16>: CDS_PINID='DQ(16)';
NODE_NAME     J9M1 172
 '@BASEBOARD_FAB2_LIB.BASEBOARD_FAB2(SCH_1):PAGE84_I14@MSTR_SCONN.SCONN288_H44441003(CHIPS)':
 'DQ'<17>: CDS_PINID='DQ(17)';
NET_NAME
'M_K_DQ<18>'
 '@BASEBOARD_FAB2_LIB.BASEBOARD_FAB2(SCH_1):M_K_DQ'<18>:
 C_SIGNAL='@baseboard_fab2_lib.baseboard_fab2(sch_1):m_k_dq(18)';
NODE_NAME     U2D1 DT81
 '@BASEBOARD_FAB2_LIB.BASEBOARD_FAB2(SCH_1):PAGE60_I172@CHPSET_LIB.SKX_EXT_B(CHIPS)':
 'DDR3_DQ'<18>: CDS_PINID='DDR3_DQ(18)';
NODE_NAME     J1B1 179
 '@BASEBOARD_FAB2_LIB.BASEBOARD_FAB2(SCH_1):PAGE83_I111@MSTR_SCONN.SCONN288_H44441004(CHIPS)':
 'DQ'<19>: CDS_PINID='DQ(19)';
NODE_NAME     J9M1 34
 '@BASEBOARD_FAB2_LIB.BASEBOARD_FAB2(SCH_1):PAGE84_I14@MSTR_SCONN.SCONN288_H44441003(CHIPS)':
 'DQ'<18>: CDS_PINID='DQ(18)';
NET_NAME
'M_K_DQ<19>'
 '@BASEBOARD_FAB2_LIB.BASEBOARD_FAB2(SCH_1):M_K_DQ'<19>:
 C_SIGNAL='@baseboard_fab2_lib.baseboard_fab2(sch_1):m_k_dq(19)';
NODE_NAME     U2D1 DR82
 '@BASEBOARD_FAB2_LIB.BASEBOARD_FAB2(SCH_1):PAGE60_I172@CHPSET_LIB.SKX_EXT_B(CHIPS)':
 'DDR3_DQ'<19>: CDS_PINID='DDR3_DQ(19)';
NODE_NAME     J1B1 34
 '@BASEBOARD_FAB2_LIB.BASEBOARD_FAB2(SCH_1):PAGE83_I111@MSTR_SCONN.SCONN288_H44441004(CHIPS)':
 'DQ'<18>: CDS_PINID='DQ(18)';
NODE_NAME     J9M1 179
 '@BASEBOARD_FAB2_LIB.BASEBOARD_FAB2(SCH_1):PAGE84_I14@MSTR_SCONN.SCONN288_H44441003(CHIPS)':
 'DQ'<19>: CDS_PINID='DQ(19)';
NET_NAME
'M_K_DQ<1>'
 '@BASEBOARD_FAB2_LIB.BASEBOARD_FAB2(SCH_1):M_K_DQ'<1>:
 C_SIGNAL='@baseboard_fab2_lib.baseboard_fab2(sch_1):m_k_dq(1)';
NODE_NAME     U2D1 CN86
 '@BASEBOARD_FAB2_LIB.BASEBOARD_FAB2(SCH_1):PAGE60_I172@CHPSET_LIB.SKX_EXT_B(CHIPS)':
 'DDR3_DQ'<1>: CDS_PINID='DDR3_DQ(1)';
NODE_NAME     J1B1 5
 '@BASEBOARD_FAB2_LIB.BASEBOARD_FAB2(SCH_1):PAGE83_I111@MSTR_SCONN.SCONN288_H44441004(CHIPS)':
 'DQ'<0>: CDS_PINID='DQ(0)';
NODE_NAME     J9M1 150
 '@BASEBOARD_FAB2_LIB.BASEBOARD_FAB2(SCH_1):PAGE84_I14@MSTR_SCONN.SCONN288_H44441003(CHIPS)':
 'DQ'<1>: CDS_PINID='DQ(1)';
NET_NAME
'M_K_DQ<20>'
 '@BASEBOARD_FAB2_LIB.BASEBOARD_FAB2(SCH_1):M_K_DQ'<20>:
 C_SIGNAL='@baseboard_fab2_lib.baseboard_fab2(sch_1):m_k_dq(20)';
NODE_NAME     U2D1 DK79
 '@BASEBOARD_FAB2_LIB.BASEBOARD_FAB2(SCH_1):PAGE60_I172@CHPSET_LIB.SKX_EXT_B(CHIPS)':
 'DDR3_DQ'<20>: CDS_PINID='DDR3_DQ(20)';
NODE_NAME     J1B1 170
 '@BASEBOARD_FAB2_LIB.BASEBOARD_FAB2(SCH_1):PAGE83_I111@MSTR_SCONN.SCONN288_H44441004(CHIPS)':
 'DQ'<21>: CDS_PINID='DQ(21)';
NODE_NAME     J9M1 25
 '@BASEBOARD_FAB2_LIB.BASEBOARD_FAB2(SCH_1):PAGE84_I14@MSTR_SCONN.SCONN288_H44441003(CHIPS)':
 'DQ'<20>: CDS_PINID='DQ(20)';
NET_NAME
'M_K_DQ<21>'
 '@BASEBOARD_FAB2_LIB.BASEBOARD_FAB2(SCH_1):M_K_DQ'<21>:
 C_SIGNAL='@baseboard_fab2_lib.baseboard_fab2(sch_1):m_k_dq(21)';
NODE_NAME     U2D1 DJ80
 '@BASEBOARD_FAB2_LIB.BASEBOARD_FAB2(SCH_1):PAGE60_I172@CHPSET_LIB.SKX_EXT_B(CHIPS)':
 'DDR3_DQ'<21>: CDS_PINID='DDR3_DQ(21)';
NODE_NAME     J1B1 25
 '@BASEBOARD_FAB2_LIB.BASEBOARD_FAB2(SCH_1):PAGE83_I111@MSTR_SCONN.SCONN288_H44441004(CHIPS)':
 'DQ'<20>: CDS_PINID='DQ(20)';
NODE_NAME     J9M1 170
 '@BASEBOARD_FAB2_LIB.BASEBOARD_FAB2(SCH_1):PAGE84_I14@MSTR_SCONN.SCONN288_H44441003(CHIPS)':
 'DQ'<21>: CDS_PINID='DQ(21)';
NET_NAME
'M_K_DQ<22>'
 '@BASEBOARD_FAB2_LIB.BASEBOARD_FAB2(SCH_1):M_K_DQ'<22>:
 C_SIGNAL='@baseboard_fab2_lib.baseboard_fab2(sch_1):m_k_dq(22)';
NODE_NAME     U2D1 DR80
 '@BASEBOARD_FAB2_LIB.BASEBOARD_FAB2(SCH_1):PAGE60_I172@CHPSET_LIB.SKX_EXT_B(CHIPS)':
 'DDR3_DQ'<22>: CDS_PINID='DDR3_DQ(22)';
NODE_NAME     J1B1 177
 '@BASEBOARD_FAB2_LIB.BASEBOARD_FAB2(SCH_1):PAGE83_I111@MSTR_SCONN.SCONN288_H44441004(CHIPS)':
 'DQ'<23>: CDS_PINID='DQ(23)';
NODE_NAME     J9M1 32
 '@BASEBOARD_FAB2_LIB.BASEBOARD_FAB2(SCH_1):PAGE84_I14@MSTR_SCONN.SCONN288_H44441003(CHIPS)':
 'DQ'<22>: CDS_PINID='DQ(22)';
NET_NAME
'M_K_DQ<23>'
 '@BASEBOARD_FAB2_LIB.BASEBOARD_FAB2(SCH_1):M_K_DQ'<23>:
 C_SIGNAL='@baseboard_fab2_lib.baseboard_fab2(sch_1):m_k_dq(23)';
NODE_NAME     U2D1 DN82
 '@BASEBOARD_FAB2_LIB.BASEBOARD_FAB2(SCH_1):PAGE60_I172@CHPSET_LIB.SKX_EXT_B(CHIPS)':
 'DDR3_DQ'<23>: CDS_PINID='DDR3_DQ(23)';
NODE_NAME     J1B1 32
 '@BASEBOARD_FAB2_LIB.BASEBOARD_FAB2(SCH_1):PAGE83_I111@MSTR_SCONN.SCONN288_H44441004(CHIPS)':
 'DQ'<22>: CDS_PINID='DQ(22)';
NODE_NAME     J9M1 177
 '@BASEBOARD_FAB2_LIB.BASEBOARD_FAB2(SCH_1):PAGE84_I14@MSTR_SCONN.SCONN288_H44441003(CHIPS)':
 'DQ'<23>: CDS_PINID='DQ(23)';
NET_NAME
'M_K_DQ<24>'
 '@BASEBOARD_FAB2_LIB.BASEBOARD_FAB2(SCH_1):M_K_DQ'<24>:
 C_SIGNAL='@baseboard_fab2_lib.baseboard_fab2(sch_1):m_k_dq(24)';
NODE_NAME     U2D1 DN76
 '@BASEBOARD_FAB2_LIB.BASEBOARD_FAB2(SCH_1):PAGE60_I172@CHPSET_LIB.SKX_EXT_B(CHIPS)':
 'DDR3_DQ'<24>: CDS_PINID='DDR3_DQ(24)';
NODE_NAME     J1B1 183
 '@BASEBOARD_FAB2_LIB.BASEBOARD_FAB2(SCH_1):PAGE83_I111@MSTR_SCONN.SCONN288_H44441004(CHIPS)':
 'DQ'<25>: CDS_PINID='DQ(25)';
NODE_NAME     J9M1 38
 '@BASEBOARD_FAB2_LIB.BASEBOARD_FAB2(SCH_1):PAGE84_I14@MSTR_SCONN.SCONN288_H44441003(CHIPS)':
 'DQ'<24>: CDS_PINID='DQ(24)';
NET_NAME
'M_K_DQ<25>'
 '@BASEBOARD_FAB2_LIB.BASEBOARD_FAB2(SCH_1):M_K_DQ'<25>:
 C_SIGNAL='@baseboard_fab2_lib.baseboard_fab2(sch_1):m_k_dq(25)';
NODE_NAME     U2D1 DU76
 '@BASEBOARD_FAB2_LIB.BASEBOARD_FAB2(SCH_1):PAGE60_I172@CHPSET_LIB.SKX_EXT_B(CHIPS)':
 'DDR3_DQ'<25>: CDS_PINID='DDR3_DQ(25)';
NODE_NAME     J1B1 38
 '@BASEBOARD_FAB2_LIB.BASEBOARD_FAB2(SCH_1):PAGE83_I111@MSTR_SCONN.SCONN288_H44441004(CHIPS)':
 'DQ'<24>: CDS_PINID='DQ(24)';
NODE_NAME     J9M1 183
 '@BASEBOARD_FAB2_LIB.BASEBOARD_FAB2(SCH_1):PAGE84_I14@MSTR_SCONN.SCONN288_H44441003(CHIPS)':
 'DQ'<25>: CDS_PINID='DQ(25)';
NET_NAME
'M_K_DQ<26>'
 '@BASEBOARD_FAB2_LIB.BASEBOARD_FAB2(SCH_1):M_K_DQ'<26>:
 C_SIGNAL='@baseboard_fab2_lib.baseboard_fab2(sch_1):m_k_dq(26)';
NODE_NAME     U2D1 DP73
 '@BASEBOARD_FAB2_LIB.BASEBOARD_FAB2(SCH_1):PAGE60_I172@CHPSET_LIB.SKX_EXT_B(CHIPS)':
 'DDR3_DQ'<26>: CDS_PINID='DDR3_DQ(26)';
NODE_NAME     J1B1 190
 '@BASEBOARD_FAB2_LIB.BASEBOARD_FAB2(SCH_1):PAGE83_I111@MSTR_SCONN.SCONN288_H44441004(CHIPS)':
 'DQ'<27>: CDS_PINID='DQ(27)';
NODE_NAME     J9M1 45
 '@BASEBOARD_FAB2_LIB.BASEBOARD_FAB2(SCH_1):PAGE84_I14@MSTR_SCONN.SCONN288_H44441003(CHIPS)':
 'DQ'<26>: CDS_PINID='DQ(26)';
NET_NAME
'M_K_DQ<27>'
 '@BASEBOARD_FAB2_LIB.BASEBOARD_FAB2(SCH_1):M_K_DQ'<27>:
 C_SIGNAL='@baseboard_fab2_lib.baseboard_fab2(sch_1):m_k_dq(27)';
NODE_NAME     U2D1 DT73
 '@BASEBOARD_FAB2_LIB.BASEBOARD_FAB2(SCH_1):PAGE60_I172@CHPSET_LIB.SKX_EXT_B(CHIPS)':
 'DDR3_DQ'<27>: CDS_PINID='DDR3_DQ(27)';
NODE_NAME     J1B1 45
 '@BASEBOARD_FAB2_LIB.BASEBOARD_FAB2(SCH_1):PAGE83_I111@MSTR_SCONN.SCONN288_H44441004(CHIPS)':
 'DQ'<26>: CDS_PINID='DQ(26)';
NODE_NAME     J9M1 190
 '@BASEBOARD_FAB2_LIB.BASEBOARD_FAB2(SCH_1):PAGE84_I14@MSTR_SCONN.SCONN288_H44441003(CHIPS)':
 'DQ'<27>: CDS_PINID='DQ(27)';
NET_NAME
'M_K_DQ<28>'
 '@BASEBOARD_FAB2_LIB.BASEBOARD_FAB2(SCH_1):M_K_DQ'<28>:
 C_SIGNAL='@baseboard_fab2_lib.baseboard_fab2(sch_1):m_k_dq(28)';
NODE_NAME     U2D1 DP77
 '@BASEBOARD_FAB2_LIB.BASEBOARD_FAB2(SCH_1):PAGE60_I172@CHPSET_LIB.SKX_EXT_B(CHIPS)':
 'DDR3_DQ'<28>: CDS_PINID='DDR3_DQ(28)';
NODE_NAME     J1B1 181
 '@BASEBOARD_FAB2_LIB.BASEBOARD_FAB2(SCH_1):PAGE83_I111@MSTR_SCONN.SCONN288_H44441004(CHIPS)':
 'DQ'<29>: CDS_PINID='DQ(29)';
NODE_NAME     J9M1 36
 '@BASEBOARD_FAB2_LIB.BASEBOARD_FAB2(SCH_1):PAGE84_I14@MSTR_SCONN.SCONN288_H44441003(CHIPS)':
 'DQ'<28>: CDS_PINID='DQ(28)';
NET_NAME
'M_K_DQ<29>'
 '@BASEBOARD_FAB2_LIB.BASEBOARD_FAB2(SCH_1):M_K_DQ'<29>:
 C_SIGNAL='@baseboard_fab2_lib.baseboard_fab2(sch_1):m_k_dq(29)';
NODE_NAME     U2D1 DT77
 '@BASEBOARD_FAB2_LIB.BASEBOARD_FAB2(SCH_1):PAGE60_I172@CHPSET_LIB.SKX_EXT_B(CHIPS)':
 'DDR3_DQ'<29>: CDS_PINID='DDR3_DQ(29)';
NODE_NAME     J1B1 36
 '@BASEBOARD_FAB2_LIB.BASEBOARD_FAB2(SCH_1):PAGE83_I111@MSTR_SCONN.SCONN288_H44441004(CHIPS)':
 'DQ'<28>: CDS_PINID='DQ(28)';
NODE_NAME     J9M1 181
 '@BASEBOARD_FAB2_LIB.BASEBOARD_FAB2(SCH_1):PAGE84_I14@MSTR_SCONN.SCONN288_H44441003(CHIPS)':
 'DQ'<29>: CDS_PINID='DQ(29)';
NET_NAME
'M_K_DQ<2>'
 '@BASEBOARD_FAB2_LIB.BASEBOARD_FAB2(SCH_1):M_K_DQ'<2>:
 C_SIGNAL='@baseboard_fab2_lib.baseboard_fab2(sch_1):m_k_dq(2)';
NODE_NAME     U2D1 DA86
 '@BASEBOARD_FAB2_LIB.BASEBOARD_FAB2(SCH_1):PAGE60_I172@CHPSET_LIB.SKX_EXT_B(CHIPS)':
 'DDR3_DQ'<2>: CDS_PINID='DDR3_DQ(2)';
NODE_NAME     J1B1 157
 '@BASEBOARD_FAB2_LIB.BASEBOARD_FAB2(SCH_1):PAGE83_I111@MSTR_SCONN.SCONN288_H44441004(CHIPS)':
 'DQ'<3>: CDS_PINID='DQ(3)';
NODE_NAME     J9M1 12
 '@BASEBOARD_FAB2_LIB.BASEBOARD_FAB2(SCH_1):PAGE84_I14@MSTR_SCONN.SCONN288_H44441003(CHIPS)':
 'DQ'<2>: CDS_PINID='DQ(2)';
NET_NAME
'M_K_DQ<30>'
 '@BASEBOARD_FAB2_LIB.BASEBOARD_FAB2(SCH_1):M_K_DQ'<30>:
 C_SIGNAL='@baseboard_fab2_lib.baseboard_fab2(sch_1):m_k_dq(30)';
NODE_NAME     U2D1 DN74
 '@BASEBOARD_FAB2_LIB.BASEBOARD_FAB2(SCH_1):PAGE60_I172@CHPSET_LIB.SKX_EXT_B(CHIPS)':
 'DDR3_DQ'<30>: CDS_PINID='DDR3_DQ(30)';
NODE_NAME     J1B1 188
 '@BASEBOARD_FAB2_LIB.BASEBOARD_FAB2(SCH_1):PAGE83_I111@MSTR_SCONN.SCONN288_H44441004(CHIPS)':
 'DQ'<31>: CDS_PINID='DQ(31)';
NODE_NAME     J9M1 43
 '@BASEBOARD_FAB2_LIB.BASEBOARD_FAB2(SCH_1):PAGE84_I14@MSTR_SCONN.SCONN288_H44441003(CHIPS)':
 'DQ'<30>: CDS_PINID='DQ(30)';
NET_NAME
'M_K_DQ<31>'
 '@BASEBOARD_FAB2_LIB.BASEBOARD_FAB2(SCH_1):M_K_DQ'<31>:
 C_SIGNAL='@baseboard_fab2_lib.baseboard_fab2(sch_1):m_k_dq(31)';
NODE_NAME     U2D1 DU74
 '@BASEBOARD_FAB2_LIB.BASEBOARD_FAB2(SCH_1):PAGE60_I172@CHPSET_LIB.SKX_EXT_B(CHIPS)':
 'DDR3_DQ'<31>: CDS_PINID='DDR3_DQ(31)';
NODE_NAME     J1B1 43
 '@BASEBOARD_FAB2_LIB.BASEBOARD_FAB2(SCH_1):PAGE83_I111@MSTR_SCONN.SCONN288_H44441004(CHIPS)':
 'DQ'<30>: CDS_PINID='DQ(30)';
NODE_NAME     J9M1 188
 '@BASEBOARD_FAB2_LIB.BASEBOARD_FAB2(SCH_1):PAGE84_I14@MSTR_SCONN.SCONN288_H44441003(CHIPS)':
 'DQ'<31>: CDS_PINID='DQ(31)';
NET_NAME
'M_K_DQ<32>'
 '@BASEBOARD_FAB2_LIB.BASEBOARD_FAB2(SCH_1):M_K_DQ'<32>:
 C_SIGNAL='@baseboard_fab2_lib.baseboard_fab2(sch_1):m_k_dq(32)';
NODE_NAME     U2D1 EC40
 '@BASEBOARD_FAB2_LIB.BASEBOARD_FAB2(SCH_1):PAGE60_I172@CHPSET_LIB.SKX_EXT_B(CHIPS)':
 'DDR3_DQ'<32>: CDS_PINID='DDR3_DQ(32)';
NODE_NAME     J1B1 242
 '@BASEBOARD_FAB2_LIB.BASEBOARD_FAB2(SCH_1):PAGE83_I111@MSTR_SCONN.SCONN288_H44441004(CHIPS)':
 'DQ'<33>: CDS_PINID='DQ(33)';
NODE_NAME     J9M1 97
 '@BASEBOARD_FAB2_LIB.BASEBOARD_FAB2(SCH_1):PAGE84_I14@MSTR_SCONN.SCONN288_H44441003(CHIPS)':
 'DQ'<32>: CDS_PINID='DQ(32)';
NET_NAME
'M_K_DQ<33>'
 '@BASEBOARD_FAB2_LIB.BASEBOARD_FAB2(SCH_1):M_K_DQ'<33>:
 C_SIGNAL='@baseboard_fab2_lib.baseboard_fab2(sch_1):m_k_dq(33)';
NODE_NAME     U2D1 ED39
 '@BASEBOARD_FAB2_LIB.BASEBOARD_FAB2(SCH_1):PAGE60_I172@CHPSET_LIB.SKX_EXT_B(CHIPS)':
 'DDR3_DQ'<33>: CDS_PINID='DDR3_DQ(33)';
NODE_NAME     J1B1 97
 '@BASEBOARD_FAB2_LIB.BASEBOARD_FAB2(SCH_1):PAGE83_I111@MSTR_SCONN.SCONN288_H44441004(CHIPS)':
 'DQ'<32>: CDS_PINID='DQ(32)';
NODE_NAME     J9M1 242
 '@BASEBOARD_FAB2_LIB.BASEBOARD_FAB2(SCH_1):PAGE84_I14@MSTR_SCONN.SCONN288_H44441003(CHIPS)':
 'DQ'<33>: CDS_PINID='DQ(33)';
NET_NAME
'M_K_DQ<34>'
 '@BASEBOARD_FAB2_LIB.BASEBOARD_FAB2(SCH_1):M_K_DQ'<34>:
 C_SIGNAL='@baseboard_fab2_lib.baseboard_fab2(sch_1):m_k_dq(34)';
NODE_NAME     U2D1 EA36
 '@BASEBOARD_FAB2_LIB.BASEBOARD_FAB2(SCH_1):PAGE60_I172@CHPSET_LIB.SKX_EXT_B(CHIPS)':
 'DDR3_DQ'<34>: CDS_PINID='DDR3_DQ(34)';
NODE_NAME     J1B1 249
 '@BASEBOARD_FAB2_LIB.BASEBOARD_FAB2(SCH_1):PAGE83_I111@MSTR_SCONN.SCONN288_H44441004(CHIPS)':
 'DQ'<35>: CDS_PINID='DQ(35)';
NODE_NAME     J9M1 104
 '@BASEBOARD_FAB2_LIB.BASEBOARD_FAB2(SCH_1):PAGE84_I14@MSTR_SCONN.SCONN288_H44441003(CHIPS)':
 'DQ'<34>: CDS_PINID='DQ(34)';
NET_NAME
'M_K_DQ<35>'
 '@BASEBOARD_FAB2_LIB.BASEBOARD_FAB2(SCH_1):M_K_DQ'<35>:
 C_SIGNAL='@baseboard_fab2_lib.baseboard_fab2(sch_1):m_k_dq(35)';
NODE_NAME     U2D1 EC36
 '@BASEBOARD_FAB2_LIB.BASEBOARD_FAB2(SCH_1):PAGE60_I172@CHPSET_LIB.SKX_EXT_B(CHIPS)':
 'DDR3_DQ'<35>: CDS_PINID='DDR3_DQ(35)';
NODE_NAME     J1B1 104
 '@BASEBOARD_FAB2_LIB.BASEBOARD_FAB2(SCH_1):PAGE83_I111@MSTR_SCONN.SCONN288_H44441004(CHIPS)':
 'DQ'<34>: CDS_PINID='DQ(34)';
NODE_NAME     J9M1 249
 '@BASEBOARD_FAB2_LIB.BASEBOARD_FAB2(SCH_1):PAGE84_I14@MSTR_SCONN.SCONN288_H44441003(CHIPS)':
 'DQ'<35>: CDS_PINID='DQ(35)';
NET_NAME
'M_K_DQ<36>'
 '@BASEBOARD_FAB2_LIB.BASEBOARD_FAB2(SCH_1):M_K_DQ'<36>:
 C_SIGNAL='@baseboard_fab2_lib.baseboard_fab2(sch_1):m_k_dq(36)';
NODE_NAME     U2D1 DY39
 '@BASEBOARD_FAB2_LIB.BASEBOARD_FAB2(SCH_1):PAGE60_I172@CHPSET_LIB.SKX_EXT_B(CHIPS)':
 'DDR3_DQ'<36>: CDS_PINID='DDR3_DQ(36)';
NODE_NAME     J1B1 240
 '@BASEBOARD_FAB2_LIB.BASEBOARD_FAB2(SCH_1):PAGE83_I111@MSTR_SCONN.SCONN288_H44441004(CHIPS)':
 'DQ'<37>: CDS_PINID='DQ(37)';
NODE_NAME     J9M1 95
 '@BASEBOARD_FAB2_LIB.BASEBOARD_FAB2(SCH_1):PAGE84_I14@MSTR_SCONN.SCONN288_H44441003(CHIPS)':
 'DQ'<36>: CDS_PINID='DQ(36)';
NET_NAME
'M_K_DQ<37>'
 '@BASEBOARD_FAB2_LIB.BASEBOARD_FAB2(SCH_1):M_K_DQ'<37>:
 C_SIGNAL='@baseboard_fab2_lib.baseboard_fab2(sch_1):m_k_dq(37)';
NODE_NAME     U2D1 EA40
 '@BASEBOARD_FAB2_LIB.BASEBOARD_FAB2(SCH_1):PAGE60_I172@CHPSET_LIB.SKX_EXT_B(CHIPS)':
 'DDR3_DQ'<37>: CDS_PINID='DDR3_DQ(37)';
NODE_NAME     J1B1 95
 '@BASEBOARD_FAB2_LIB.BASEBOARD_FAB2(SCH_1):PAGE83_I111@MSTR_SCONN.SCONN288_H44441004(CHIPS)':
 'DQ'<36>: CDS_PINID='DQ(36)';
NODE_NAME     J9M1 240
 '@BASEBOARD_FAB2_LIB.BASEBOARD_FAB2(SCH_1):PAGE84_I14@MSTR_SCONN.SCONN288_H44441003(CHIPS)':
 'DQ'<37>: CDS_PINID='DQ(37)';
NET_NAME
'M_K_DQ<38>'
 '@BASEBOARD_FAB2_LIB.BASEBOARD_FAB2(SCH_1):M_K_DQ'<38>:
 C_SIGNAL='@baseboard_fab2_lib.baseboard_fab2(sch_1):m_k_dq(38)';
NODE_NAME     U2D1 DY37
 '@BASEBOARD_FAB2_LIB.BASEBOARD_FAB2(SCH_1):PAGE60_I172@CHPSET_LIB.SKX_EXT_B(CHIPS)':
 'DDR3_DQ'<38>: CDS_PINID='DDR3_DQ(38)';
NODE_NAME     J1B1 247
 '@BASEBOARD_FAB2_LIB.BASEBOARD_FAB2(SCH_1):PAGE83_I111@MSTR_SCONN.SCONN288_H44441004(CHIPS)':
 'DQ'<39>: CDS_PINID='DQ(39)';
NODE_NAME     J9M1 102
 '@BASEBOARD_FAB2_LIB.BASEBOARD_FAB2(SCH_1):PAGE84_I14@MSTR_SCONN.SCONN288_H44441003(CHIPS)':
 'DQ'<38>: CDS_PINID='DQ(38)';
NET_NAME
'M_K_DQ<39>'
 '@BASEBOARD_FAB2_LIB.BASEBOARD_FAB2(SCH_1):M_K_DQ'<39>:
 C_SIGNAL='@baseboard_fab2_lib.baseboard_fab2(sch_1):m_k_dq(39)';
NODE_NAME     U2D1 ED37
 '@BASEBOARD_FAB2_LIB.BASEBOARD_FAB2(SCH_1):PAGE60_I172@CHPSET_LIB.SKX_EXT_B(CHIPS)':
 'DDR3_DQ'<39>: CDS_PINID='DDR3_DQ(39)';
NODE_NAME     J1B1 102
 '@BASEBOARD_FAB2_LIB.BASEBOARD_FAB2(SCH_1):PAGE83_I111@MSTR_SCONN.SCONN288_H44441004(CHIPS)':
 'DQ'<38>: CDS_PINID='DQ(38)';
NODE_NAME     J9M1 247
 '@BASEBOARD_FAB2_LIB.BASEBOARD_FAB2(SCH_1):PAGE84_I14@MSTR_SCONN.SCONN288_H44441003(CHIPS)':
 'DQ'<39>: CDS_PINID='DQ(39)';
NET_NAME
'M_K_DQ<3>'
 '@BASEBOARD_FAB2_LIB.BASEBOARD_FAB2(SCH_1):M_K_DQ'<3>:
 C_SIGNAL='@baseboard_fab2_lib.baseboard_fab2(sch_1):m_k_dq(3)';
NODE_NAME     U2D1 DA84
 '@BASEBOARD_FAB2_LIB.BASEBOARD_FAB2(SCH_1):PAGE60_I172@CHPSET_LIB.SKX_EXT_B(CHIPS)':
 'DDR3_DQ'<3>: CDS_PINID='DDR3_DQ(3)';
NODE_NAME     J1B1 12
 '@BASEBOARD_FAB2_LIB.BASEBOARD_FAB2(SCH_1):PAGE83_I111@MSTR_SCONN.SCONN288_H44441004(CHIPS)':
 'DQ'<2>: CDS_PINID='DQ(2)';
NODE_NAME     J9M1 157
 '@BASEBOARD_FAB2_LIB.BASEBOARD_FAB2(SCH_1):PAGE84_I14@MSTR_SCONN.SCONN288_H44441003(CHIPS)':
 'DQ'<3>: CDS_PINID='DQ(3)';
NET_NAME
'M_K_DQ<40>'
 '@BASEBOARD_FAB2_LIB.BASEBOARD_FAB2(SCH_1):M_K_DQ'<40>:
 C_SIGNAL='@baseboard_fab2_lib.baseboard_fab2(sch_1):m_k_dq(40)';
NODE_NAME     U2D1 DN36
 '@BASEBOARD_FAB2_LIB.BASEBOARD_FAB2(SCH_1):PAGE60_I172@CHPSET_LIB.SKX_EXT_B(CHIPS)':
 'DDR3_DQ'<40>: CDS_PINID='DDR3_DQ(40)';
NODE_NAME     J1B1 253
 '@BASEBOARD_FAB2_LIB.BASEBOARD_FAB2(SCH_1):PAGE83_I111@MSTR_SCONN.SCONN288_H44441004(CHIPS)':
 'DQ'<41>: CDS_PINID='DQ(41)';
NODE_NAME     J9M1 108
 '@BASEBOARD_FAB2_LIB.BASEBOARD_FAB2(SCH_1):PAGE84_I14@MSTR_SCONN.SCONN288_H44441003(CHIPS)':
 'DQ'<40>: CDS_PINID='DQ(40)';
NET_NAME
'M_K_DQ<41>'
 '@BASEBOARD_FAB2_LIB.BASEBOARD_FAB2(SCH_1):M_K_DQ'<41>:
 C_SIGNAL='@baseboard_fab2_lib.baseboard_fab2(sch_1):m_k_dq(41)';
NODE_NAME     U2D1 DU36
 '@BASEBOARD_FAB2_LIB.BASEBOARD_FAB2(SCH_1):PAGE60_I172@CHPSET_LIB.SKX_EXT_B(CHIPS)':
 'DDR3_DQ'<41>: CDS_PINID='DDR3_DQ(41)';
NODE_NAME     J1B1 108
 '@BASEBOARD_FAB2_LIB.BASEBOARD_FAB2(SCH_1):PAGE83_I111@MSTR_SCONN.SCONN288_H44441004(CHIPS)':
 'DQ'<40>: CDS_PINID='DQ(40)';
NODE_NAME     J9M1 253
 '@BASEBOARD_FAB2_LIB.BASEBOARD_FAB2(SCH_1):PAGE84_I14@MSTR_SCONN.SCONN288_H44441003(CHIPS)':
 'DQ'<41>: CDS_PINID='DQ(41)';
NET_NAME
'M_K_DQ<42>'
 '@BASEBOARD_FAB2_LIB.BASEBOARD_FAB2(SCH_1):M_K_DQ'<42>:
 C_SIGNAL='@baseboard_fab2_lib.baseboard_fab2(sch_1):m_k_dq(42)';
NODE_NAME     U2D1 DP33
 '@BASEBOARD_FAB2_LIB.BASEBOARD_FAB2(SCH_1):PAGE60_I172@CHPSET_LIB.SKX_EXT_B(CHIPS)':
 'DDR3_DQ'<42>: CDS_PINID='DDR3_DQ(42)';
NODE_NAME     J1B1 260
 '@BASEBOARD_FAB2_LIB.BASEBOARD_FAB2(SCH_1):PAGE83_I111@MSTR_SCONN.SCONN288_H44441004(CHIPS)':
 'DQ'<43>: CDS_PINID='DQ(43)';
NODE_NAME     J9M1 115
 '@BASEBOARD_FAB2_LIB.BASEBOARD_FAB2(SCH_1):PAGE84_I14@MSTR_SCONN.SCONN288_H44441003(CHIPS)':
 'DQ'<42>: CDS_PINID='DQ(42)';
NET_NAME
'M_K_DQ<43>'
 '@BASEBOARD_FAB2_LIB.BASEBOARD_FAB2(SCH_1):M_K_DQ'<43>:
 C_SIGNAL='@baseboard_fab2_lib.baseboard_fab2(sch_1):m_k_dq(43)';
NODE_NAME     U2D1 DT33
 '@BASEBOARD_FAB2_LIB.BASEBOARD_FAB2(SCH_1):PAGE60_I172@CHPSET_LIB.SKX_EXT_B(CHIPS)':
 'DDR3_DQ'<43>: CDS_PINID='DDR3_DQ(43)';
NODE_NAME     J1B1 115
 '@BASEBOARD_FAB2_LIB.BASEBOARD_FAB2(SCH_1):PAGE83_I111@MSTR_SCONN.SCONN288_H44441004(CHIPS)':
 'DQ'<42>: CDS_PINID='DQ(42)';
NODE_NAME     J9M1 260
 '@BASEBOARD_FAB2_LIB.BASEBOARD_FAB2(SCH_1):PAGE84_I14@MSTR_SCONN.SCONN288_H44441003(CHIPS)':
 'DQ'<43>: CDS_PINID='DQ(43)';
NET_NAME
'M_K_DQ<44>'
 '@BASEBOARD_FAB2_LIB.BASEBOARD_FAB2(SCH_1):M_K_DQ'<44>:
 C_SIGNAL='@baseboard_fab2_lib.baseboard_fab2(sch_1):m_k_dq(44)';
NODE_NAME     U2D1 DP37
 '@BASEBOARD_FAB2_LIB.BASEBOARD_FAB2(SCH_1):PAGE60_I172@CHPSET_LIB.SKX_EXT_B(CHIPS)':
 'DDR3_DQ'<44>: CDS_PINID='DDR3_DQ(44)';
NODE_NAME     J1B1 251
 '@BASEBOARD_FAB2_LIB.BASEBOARD_FAB2(SCH_1):PAGE83_I111@MSTR_SCONN.SCONN288_H44441004(CHIPS)':
 'DQ'<45>: CDS_PINID='DQ(45)';
NODE_NAME     J9M1 106
 '@BASEBOARD_FAB2_LIB.BASEBOARD_FAB2(SCH_1):PAGE84_I14@MSTR_SCONN.SCONN288_H44441003(CHIPS)':
 'DQ'<44>: CDS_PINID='DQ(44)';
NET_NAME
'M_K_DQ<45>'
 '@BASEBOARD_FAB2_LIB.BASEBOARD_FAB2(SCH_1):M_K_DQ'<45>:
 C_SIGNAL='@baseboard_fab2_lib.baseboard_fab2(sch_1):m_k_dq(45)';
NODE_NAME     U2D1 DT37
 '@BASEBOARD_FAB2_LIB.BASEBOARD_FAB2(SCH_1):PAGE60_I172@CHPSET_LIB.SKX_EXT_B(CHIPS)':
 'DDR3_DQ'<45>: CDS_PINID='DDR3_DQ(45)';
NODE_NAME     J1B1 106
 '@BASEBOARD_FAB2_LIB.BASEBOARD_FAB2(SCH_1):PAGE83_I111@MSTR_SCONN.SCONN288_H44441004(CHIPS)':
 'DQ'<44>: CDS_PINID='DQ(44)';
NODE_NAME     J9M1 251
 '@BASEBOARD_FAB2_LIB.BASEBOARD_FAB2(SCH_1):PAGE84_I14@MSTR_SCONN.SCONN288_H44441003(CHIPS)':
 'DQ'<45>: CDS_PINID='DQ(45)';
NET_NAME
'M_K_DQ<46>'
 '@BASEBOARD_FAB2_LIB.BASEBOARD_FAB2(SCH_1):M_K_DQ'<46>:
 C_SIGNAL='@baseboard_fab2_lib.baseboard_fab2(sch_1):m_k_dq(46)';
NODE_NAME     U2D1 DN34
 '@BASEBOARD_FAB2_LIB.BASEBOARD_FAB2(SCH_1):PAGE60_I172@CHPSET_LIB.SKX_EXT_B(CHIPS)':
 'DDR3_DQ'<46>: CDS_PINID='DDR3_DQ(46)';
NODE_NAME     J1B1 258
 '@BASEBOARD_FAB2_LIB.BASEBOARD_FAB2(SCH_1):PAGE83_I111@MSTR_SCONN.SCONN288_H44441004(CHIPS)':
 'DQ'<47>: CDS_PINID='DQ(47)';
NODE_NAME     J9M1 113
 '@BASEBOARD_FAB2_LIB.BASEBOARD_FAB2(SCH_1):PAGE84_I14@MSTR_SCONN.SCONN288_H44441003(CHIPS)':
 'DQ'<46>: CDS_PINID='DQ(46)';
NET_NAME
'M_K_DQ<47>'
 '@BASEBOARD_FAB2_LIB.BASEBOARD_FAB2(SCH_1):M_K_DQ'<47>:
 C_SIGNAL='@baseboard_fab2_lib.baseboard_fab2(sch_1):m_k_dq(47)';
NODE_NAME     U2D1 DU34
 '@BASEBOARD_FAB2_LIB.BASEBOARD_FAB2(SCH_1):PAGE60_I172@CHPSET_LIB.SKX_EXT_B(CHIPS)':
 'DDR3_DQ'<47>: CDS_PINID='DDR3_DQ(47)';
NODE_NAME     J1B1 113
 '@BASEBOARD_FAB2_LIB.BASEBOARD_FAB2(SCH_1):PAGE83_I111@MSTR_SCONN.SCONN288_H44441004(CHIPS)':
 'DQ'<46>: CDS_PINID='DQ(46)';
NODE_NAME     J9M1 258
 '@BASEBOARD_FAB2_LIB.BASEBOARD_FAB2(SCH_1):PAGE84_I14@MSTR_SCONN.SCONN288_H44441003(CHIPS)':
 'DQ'<47>: CDS_PINID='DQ(47)';
NET_NAME
'M_K_DQ<48>'
 '@BASEBOARD_FAB2_LIB.BASEBOARD_FAB2(SCH_1):M_K_DQ'<48>:
 C_SIGNAL='@baseboard_fab2_lib.baseboard_fab2(sch_1):m_k_dq(48)';
NODE_NAME     U2D1 DN30
 '@BASEBOARD_FAB2_LIB.BASEBOARD_FAB2(SCH_1):PAGE60_I172@CHPSET_LIB.SKX_EXT_B(CHIPS)':
 'DDR3_DQ'<48>: CDS_PINID='DDR3_DQ(48)';
NODE_NAME     J1B1 264
 '@BASEBOARD_FAB2_LIB.BASEBOARD_FAB2(SCH_1):PAGE83_I111@MSTR_SCONN.SCONN288_H44441004(CHIPS)':
 'DQ'<49>: CDS_PINID='DQ(49)';
NODE_NAME     J9M1 119
 '@BASEBOARD_FAB2_LIB.BASEBOARD_FAB2(SCH_1):PAGE84_I14@MSTR_SCONN.SCONN288_H44441003(CHIPS)':
 'DQ'<48>: CDS_PINID='DQ(48)';
NET_NAME
'M_K_DQ<49>'
 '@BASEBOARD_FAB2_LIB.BASEBOARD_FAB2(SCH_1):M_K_DQ'<49>:
 C_SIGNAL='@baseboard_fab2_lib.baseboard_fab2(sch_1):m_k_dq(49)';
NODE_NAME     U2D1 DU30
 '@BASEBOARD_FAB2_LIB.BASEBOARD_FAB2(SCH_1):PAGE60_I172@CHPSET_LIB.SKX_EXT_B(CHIPS)':
 'DDR3_DQ'<49>: CDS_PINID='DDR3_DQ(49)';
NODE_NAME     J1B1 119
 '@BASEBOARD_FAB2_LIB.BASEBOARD_FAB2(SCH_1):PAGE83_I111@MSTR_SCONN.SCONN288_H44441004(CHIPS)':
 'DQ'<48>: CDS_PINID='DQ(48)';
NODE_NAME     J9M1 264
 '@BASEBOARD_FAB2_LIB.BASEBOARD_FAB2(SCH_1):PAGE84_I14@MSTR_SCONN.SCONN288_H44441003(CHIPS)':
 'DQ'<49>: CDS_PINID='DQ(49)';
NET_NAME
'M_K_DQ<4>'
 '@BASEBOARD_FAB2_LIB.BASEBOARD_FAB2(SCH_1):M_K_DQ'<4>:
 C_SIGNAL='@baseboard_fab2_lib.baseboard_fab2(sch_1):m_k_dq(4)';
NODE_NAME     U2D1 CL84
 '@BASEBOARD_FAB2_LIB.BASEBOARD_FAB2(SCH_1):PAGE60_I172@CHPSET_LIB.SKX_EXT_B(CHIPS)':
 'DDR3_DQ'<4>: CDS_PINID='DDR3_DQ(4)';
NODE_NAME     J1B1 148
 '@BASEBOARD_FAB2_LIB.BASEBOARD_FAB2(SCH_1):PAGE83_I111@MSTR_SCONN.SCONN288_H44441004(CHIPS)':
 'DQ'<5>: CDS_PINID='DQ(5)';
NODE_NAME     J9M1 3
 '@BASEBOARD_FAB2_LIB.BASEBOARD_FAB2(SCH_1):PAGE84_I14@MSTR_SCONN.SCONN288_H44441003(CHIPS)':
 'DQ'<4>: CDS_PINID='DQ(4)';
NET_NAME
'M_K_DQ<50>'
 '@BASEBOARD_FAB2_LIB.BASEBOARD_FAB2(SCH_1):M_K_DQ'<50>:
 C_SIGNAL='@baseboard_fab2_lib.baseboard_fab2(sch_1):m_k_dq(50)';
NODE_NAME     U2D1 DP27
 '@BASEBOARD_FAB2_LIB.BASEBOARD_FAB2(SCH_1):PAGE60_I172@CHPSET_LIB.SKX_EXT_B(CHIPS)':
 'DDR3_DQ'<50>: CDS_PINID='DDR3_DQ(50)';
NODE_NAME     J1B1 271
 '@BASEBOARD_FAB2_LIB.BASEBOARD_FAB2(SCH_1):PAGE83_I111@MSTR_SCONN.SCONN288_H44441004(CHIPS)':
 'DQ'<51>: CDS_PINID='DQ(51)';
NODE_NAME     J9M1 126
 '@BASEBOARD_FAB2_LIB.BASEBOARD_FAB2(SCH_1):PAGE84_I14@MSTR_SCONN.SCONN288_H44441003(CHIPS)':
 'DQ'<50>: CDS_PINID='DQ(50)';
NET_NAME
'M_K_DQ<51>'
 '@BASEBOARD_FAB2_LIB.BASEBOARD_FAB2(SCH_1):M_K_DQ'<51>:
 C_SIGNAL='@baseboard_fab2_lib.baseboard_fab2(sch_1):m_k_dq(51)';
NODE_NAME     U2D1 DT27
 '@BASEBOARD_FAB2_LIB.BASEBOARD_FAB2(SCH_1):PAGE60_I172@CHPSET_LIB.SKX_EXT_B(CHIPS)':
 'DDR3_DQ'<51>: CDS_PINID='DDR3_DQ(51)';
NODE_NAME     J1B1 126
 '@BASEBOARD_FAB2_LIB.BASEBOARD_FAB2(SCH_1):PAGE83_I111@MSTR_SCONN.SCONN288_H44441004(CHIPS)':
 'DQ'<50>: CDS_PINID='DQ(50)';
NODE_NAME     J9M1 271
 '@BASEBOARD_FAB2_LIB.BASEBOARD_FAB2(SCH_1):PAGE84_I14@MSTR_SCONN.SCONN288_H44441003(CHIPS)':
 'DQ'<51>: CDS_PINID='DQ(51)';
NET_NAME
'M_K_DQ<52>'
 '@BASEBOARD_FAB2_LIB.BASEBOARD_FAB2(SCH_1):M_K_DQ'<52>:
 C_SIGNAL='@baseboard_fab2_lib.baseboard_fab2(sch_1):m_k_dq(52)';
NODE_NAME     U2D1 DP31
 '@BASEBOARD_FAB2_LIB.BASEBOARD_FAB2(SCH_1):PAGE60_I172@CHPSET_LIB.SKX_EXT_B(CHIPS)':
 'DDR3_DQ'<52>: CDS_PINID='DDR3_DQ(52)';
NODE_NAME     J1B1 262
 '@BASEBOARD_FAB2_LIB.BASEBOARD_FAB2(SCH_1):PAGE83_I111@MSTR_SCONN.SCONN288_H44441004(CHIPS)':
 'DQ'<53>: CDS_PINID='DQ(53)';
NODE_NAME     J9M1 117
 '@BASEBOARD_FAB2_LIB.BASEBOARD_FAB2(SCH_1):PAGE84_I14@MSTR_SCONN.SCONN288_H44441003(CHIPS)':
 'DQ'<52>: CDS_PINID='DQ(52)';
NET_NAME
'M_K_DQ<53>'
 '@BASEBOARD_FAB2_LIB.BASEBOARD_FAB2(SCH_1):M_K_DQ'<53>:
 C_SIGNAL='@baseboard_fab2_lib.baseboard_fab2(sch_1):m_k_dq(53)';
NODE_NAME     U2D1 DT31
 '@BASEBOARD_FAB2_LIB.BASEBOARD_FAB2(SCH_1):PAGE60_I172@CHPSET_LIB.SKX_EXT_B(CHIPS)':
 'DDR3_DQ'<53>: CDS_PINID='DDR3_DQ(53)';
NODE_NAME     J1B1 117
 '@BASEBOARD_FAB2_LIB.BASEBOARD_FAB2(SCH_1):PAGE83_I111@MSTR_SCONN.SCONN288_H44441004(CHIPS)':
 'DQ'<52>: CDS_PINID='DQ(52)';
NODE_NAME     J9M1 262
 '@BASEBOARD_FAB2_LIB.BASEBOARD_FAB2(SCH_1):PAGE84_I14@MSTR_SCONN.SCONN288_H44441003(CHIPS)':
 'DQ'<53>: CDS_PINID='DQ(53)';
NET_NAME
'M_K_DQ<54>'
 '@BASEBOARD_FAB2_LIB.BASEBOARD_FAB2(SCH_1):M_K_DQ'<54>:
 C_SIGNAL='@baseboard_fab2_lib.baseboard_fab2(sch_1):m_k_dq(54)';
NODE_NAME     U2D1 DN28
 '@BASEBOARD_FAB2_LIB.BASEBOARD_FAB2(SCH_1):PAGE60_I172@CHPSET_LIB.SKX_EXT_B(CHIPS)':
 'DDR3_DQ'<54>: CDS_PINID='DDR3_DQ(54)';
NODE_NAME     J1B1 269
 '@BASEBOARD_FAB2_LIB.BASEBOARD_FAB2(SCH_1):PAGE83_I111@MSTR_SCONN.SCONN288_H44441004(CHIPS)':
 'DQ'<55>: CDS_PINID='DQ(55)';
NODE_NAME     J9M1 124
 '@BASEBOARD_FAB2_LIB.BASEBOARD_FAB2(SCH_1):PAGE84_I14@MSTR_SCONN.SCONN288_H44441003(CHIPS)':
 'DQ'<54>: CDS_PINID='DQ(54)';
NET_NAME
'M_K_DQ<55>'
 '@BASEBOARD_FAB2_LIB.BASEBOARD_FAB2(SCH_1):M_K_DQ'<55>:
 C_SIGNAL='@baseboard_fab2_lib.baseboard_fab2(sch_1):m_k_dq(55)';
NODE_NAME     U2D1 DU28
 '@BASEBOARD_FAB2_LIB.BASEBOARD_FAB2(SCH_1):PAGE60_I172@CHPSET_LIB.SKX_EXT_B(CHIPS)':
 'DDR3_DQ'<55>: CDS_PINID='DDR3_DQ(55)';
NODE_NAME     J1B1 124
 '@BASEBOARD_FAB2_LIB.BASEBOARD_FAB2(SCH_1):PAGE83_I111@MSTR_SCONN.SCONN288_H44441004(CHIPS)':
 'DQ'<54>: CDS_PINID='DQ(54)';
NODE_NAME     J9M1 269
 '@BASEBOARD_FAB2_LIB.BASEBOARD_FAB2(SCH_1):PAGE84_I14@MSTR_SCONN.SCONN288_H44441003(CHIPS)':
 'DQ'<55>: CDS_PINID='DQ(55)';
NET_NAME
'M_K_DQ<56>'
 '@BASEBOARD_FAB2_LIB.BASEBOARD_FAB2(SCH_1):M_K_DQ'<56>:
 C_SIGNAL='@baseboard_fab2_lib.baseboard_fab2(sch_1):m_k_dq(56)';
NODE_NAME     U2D1 DN24
 '@BASEBOARD_FAB2_LIB.BASEBOARD_FAB2(SCH_1):PAGE60_I172@CHPSET_LIB.SKX_EXT_B(CHIPS)':
 'DDR3_DQ'<56>: CDS_PINID='DDR3_DQ(56)';
NODE_NAME     J1B1 275
 '@BASEBOARD_FAB2_LIB.BASEBOARD_FAB2(SCH_1):PAGE83_I111@MSTR_SCONN.SCONN288_H44441004(CHIPS)':
 'DQ'<57>: CDS_PINID='DQ(57)';
NODE_NAME     J9M1 130
 '@BASEBOARD_FAB2_LIB.BASEBOARD_FAB2(SCH_1):PAGE84_I14@MSTR_SCONN.SCONN288_H44441003(CHIPS)':
 'DQ'<56>: CDS_PINID='DQ(56)';
NET_NAME
'M_K_DQ<57>'
 '@BASEBOARD_FAB2_LIB.BASEBOARD_FAB2(SCH_1):M_K_DQ'<57>:
 C_SIGNAL='@baseboard_fab2_lib.baseboard_fab2(sch_1):m_k_dq(57)';
NODE_NAME     U2D1 DU24
 '@BASEBOARD_FAB2_LIB.BASEBOARD_FAB2(SCH_1):PAGE60_I172@CHPSET_LIB.SKX_EXT_B(CHIPS)':
 'DDR3_DQ'<57>: CDS_PINID='DDR3_DQ(57)';
NODE_NAME     J1B1 130
 '@BASEBOARD_FAB2_LIB.BASEBOARD_FAB2(SCH_1):PAGE83_I111@MSTR_SCONN.SCONN288_H44441004(CHIPS)':
 'DQ'<56>: CDS_PINID='DQ(56)';
NODE_NAME     J9M1 275
 '@BASEBOARD_FAB2_LIB.BASEBOARD_FAB2(SCH_1):PAGE84_I14@MSTR_SCONN.SCONN288_H44441003(CHIPS)':
 'DQ'<57>: CDS_PINID='DQ(57)';
NET_NAME
'M_K_DQ<58>'
 '@BASEBOARD_FAB2_LIB.BASEBOARD_FAB2(SCH_1):M_K_DQ'<58>:
 C_SIGNAL='@baseboard_fab2_lib.baseboard_fab2(sch_1):m_k_dq(58)';
NODE_NAME     U2D1 DY21
 '@BASEBOARD_FAB2_LIB.BASEBOARD_FAB2(SCH_1):PAGE60_I172@CHPSET_LIB.SKX_EXT_B(CHIPS)':
 'DDR3_DQ'<58>: CDS_PINID='DDR3_DQ(58)';
NODE_NAME     J1B1 282
 '@BASEBOARD_FAB2_LIB.BASEBOARD_FAB2(SCH_1):PAGE83_I111@MSTR_SCONN.SCONN288_H44441004(CHIPS)':
 'DQ'<59>: CDS_PINID='DQ(59)';
NODE_NAME     J9M1 137
 '@BASEBOARD_FAB2_LIB.BASEBOARD_FAB2(SCH_1):PAGE84_I14@MSTR_SCONN.SCONN288_H44441003(CHIPS)':
 'DQ'<58>: CDS_PINID='DQ(58)';
NET_NAME
'M_K_DQ<59>'
 '@BASEBOARD_FAB2_LIB.BASEBOARD_FAB2(SCH_1):M_K_DQ'<59>:
 C_SIGNAL='@baseboard_fab2_lib.baseboard_fab2(sch_1):m_k_dq(59)';
NODE_NAME     U2D1 EB21
 '@BASEBOARD_FAB2_LIB.BASEBOARD_FAB2(SCH_1):PAGE60_I172@CHPSET_LIB.SKX_EXT_B(CHIPS)':
 'DDR3_DQ'<59>: CDS_PINID='DDR3_DQ(59)';
NODE_NAME     J1B1 137
 '@BASEBOARD_FAB2_LIB.BASEBOARD_FAB2(SCH_1):PAGE83_I111@MSTR_SCONN.SCONN288_H44441004(CHIPS)':
 'DQ'<58>: CDS_PINID='DQ(58)';
NODE_NAME     J9M1 282
 '@BASEBOARD_FAB2_LIB.BASEBOARD_FAB2(SCH_1):PAGE84_I14@MSTR_SCONN.SCONN288_H44441003(CHIPS)':
 'DQ'<59>: CDS_PINID='DQ(59)';
NET_NAME
'M_K_DQ<5>'
 '@BASEBOARD_FAB2_LIB.BASEBOARD_FAB2(SCH_1):M_K_DQ'<5>:
 C_SIGNAL='@baseboard_fab2_lib.baseboard_fab2(sch_1):m_k_dq(5)';
NODE_NAME     U2D1 CL86
 '@BASEBOARD_FAB2_LIB.BASEBOARD_FAB2(SCH_1):PAGE60_I172@CHPSET_LIB.SKX_EXT_B(CHIPS)':
 'DDR3_DQ'<5>: CDS_PINID='DDR3_DQ(5)';
NODE_NAME     J1B1 3
 '@BASEBOARD_FAB2_LIB.BASEBOARD_FAB2(SCH_1):PAGE83_I111@MSTR_SCONN.SCONN288_H44441004(CHIPS)':
 'DQ'<4>: CDS_PINID='DQ(4)';
NODE_NAME     J9M1 148
 '@BASEBOARD_FAB2_LIB.BASEBOARD_FAB2(SCH_1):PAGE84_I14@MSTR_SCONN.SCONN288_H44441003(CHIPS)':
 'DQ'<5>: CDS_PINID='DQ(5)';
NET_NAME
'M_K_DQ<60>'
 '@BASEBOARD_FAB2_LIB.BASEBOARD_FAB2(SCH_1):M_K_DQ'<60>:
 C_SIGNAL='@baseboard_fab2_lib.baseboard_fab2(sch_1):m_k_dq(60)';
NODE_NAME     U2D1 DP25
 '@BASEBOARD_FAB2_LIB.BASEBOARD_FAB2(SCH_1):PAGE60_I172@CHPSET_LIB.SKX_EXT_B(CHIPS)':
 'DDR3_DQ'<60>: CDS_PINID='DDR3_DQ(60)';
NODE_NAME     J1B1 273
 '@BASEBOARD_FAB2_LIB.BASEBOARD_FAB2(SCH_1):PAGE83_I111@MSTR_SCONN.SCONN288_H44441004(CHIPS)':
 'DQ'<61>: CDS_PINID='DQ(61)';
NODE_NAME     J9M1 128
 '@BASEBOARD_FAB2_LIB.BASEBOARD_FAB2(SCH_1):PAGE84_I14@MSTR_SCONN.SCONN288_H44441003(CHIPS)':
 'DQ'<60>: CDS_PINID='DQ(60)';
NET_NAME
'M_K_DQ<61>'
 '@BASEBOARD_FAB2_LIB.BASEBOARD_FAB2(SCH_1):M_K_DQ'<61>:
 C_SIGNAL='@baseboard_fab2_lib.baseboard_fab2(sch_1):m_k_dq(61)';
NODE_NAME     U2D1 DT25
 '@BASEBOARD_FAB2_LIB.BASEBOARD_FAB2(SCH_1):PAGE60_I172@CHPSET_LIB.SKX_EXT_B(CHIPS)':
 'DDR3_DQ'<61>: CDS_PINID='DDR3_DQ(61)';
NODE_NAME     J1B1 128
 '@BASEBOARD_FAB2_LIB.BASEBOARD_FAB2(SCH_1):PAGE83_I111@MSTR_SCONN.SCONN288_H44441004(CHIPS)':
 'DQ'<60>: CDS_PINID='DQ(60)';
NODE_NAME     J9M1 273
 '@BASEBOARD_FAB2_LIB.BASEBOARD_FAB2(SCH_1):PAGE84_I14@MSTR_SCONN.SCONN288_H44441003(CHIPS)':
 'DQ'<61>: CDS_PINID='DQ(61)';
NET_NAME
'M_K_DQ<62>'
 '@BASEBOARD_FAB2_LIB.BASEBOARD_FAB2(SCH_1):M_K_DQ'<62>:
 C_SIGNAL='@baseboard_fab2_lib.baseboard_fab2(sch_1):m_k_dq(62)';
NODE_NAME     U2D1 EC22
 '@BASEBOARD_FAB2_LIB.BASEBOARD_FAB2(SCH_1):PAGE60_I172@CHPSET_LIB.SKX_EXT_B(CHIPS)':
 'DDR3_DQ'<62>: CDS_PINID='DDR3_DQ(62)';
NODE_NAME     J1B1 280
 '@BASEBOARD_FAB2_LIB.BASEBOARD_FAB2(SCH_1):PAGE83_I111@MSTR_SCONN.SCONN288_H44441004(CHIPS)':
 'DQ'<63>: CDS_PINID='DQ(63)';
NODE_NAME     J9M1 135
 '@BASEBOARD_FAB2_LIB.BASEBOARD_FAB2(SCH_1):PAGE84_I14@MSTR_SCONN.SCONN288_H44441003(CHIPS)':
 'DQ'<62>: CDS_PINID='DQ(62)';
NET_NAME
'M_K_DQ<63>'
 '@BASEBOARD_FAB2_LIB.BASEBOARD_FAB2(SCH_1):M_K_DQ'<63>:
 C_SIGNAL='@baseboard_fab2_lib.baseboard_fab2(sch_1):m_k_dq(63)';
NODE_NAME     U2D1 DW22
 '@BASEBOARD_FAB2_LIB.BASEBOARD_FAB2(SCH_1):PAGE60_I172@CHPSET_LIB.SKX_EXT_B(CHIPS)':
 'DDR3_DQ'<63>: CDS_PINID='DDR3_DQ(63)';
NODE_NAME     J1B1 135
 '@BASEBOARD_FAB2_LIB.BASEBOARD_FAB2(SCH_1):PAGE83_I111@MSTR_SCONN.SCONN288_H44441004(CHIPS)':
 'DQ'<62>: CDS_PINID='DQ(62)';
NODE_NAME     J9M1 280
 '@BASEBOARD_FAB2_LIB.BASEBOARD_FAB2(SCH_1):PAGE84_I14@MSTR_SCONN.SCONN288_H44441003(CHIPS)':
 'DQ'<63>: CDS_PINID='DQ(63)';
NET_NAME
'M_K_DQ<6>'
 '@BASEBOARD_FAB2_LIB.BASEBOARD_FAB2(SCH_1):M_K_DQ'<6>:
 C_SIGNAL='@baseboard_fab2_lib.baseboard_fab2(sch_1):m_k_dq(6)';
NODE_NAME     U2D1 CW86
 '@BASEBOARD_FAB2_LIB.BASEBOARD_FAB2(SCH_1):PAGE60_I172@CHPSET_LIB.SKX_EXT_B(CHIPS)':
 'DDR3_DQ'<6>: CDS_PINID='DDR3_DQ(6)';
NODE_NAME     J1B1 155
 '@BASEBOARD_FAB2_LIB.BASEBOARD_FAB2(SCH_1):PAGE83_I111@MSTR_SCONN.SCONN288_H44441004(CHIPS)':
 'DQ'<7>: CDS_PINID='DQ(7)';
NODE_NAME     J9M1 10
 '@BASEBOARD_FAB2_LIB.BASEBOARD_FAB2(SCH_1):PAGE84_I14@MSTR_SCONN.SCONN288_H44441003(CHIPS)':
 'DQ'<6>: CDS_PINID='DQ(6)';
NET_NAME
'M_K_DQ<7>'
 '@BASEBOARD_FAB2_LIB.BASEBOARD_FAB2(SCH_1):M_K_DQ'<7>:
 C_SIGNAL='@baseboard_fab2_lib.baseboard_fab2(sch_1):m_k_dq(7)';
NODE_NAME     U2D1 CW84
 '@BASEBOARD_FAB2_LIB.BASEBOARD_FAB2(SCH_1):PAGE60_I172@CHPSET_LIB.SKX_EXT_B(CHIPS)':
 'DDR3_DQ'<7>: CDS_PINID='DDR3_DQ(7)';
NODE_NAME     J1B1 10
 '@BASEBOARD_FAB2_LIB.BASEBOARD_FAB2(SCH_1):PAGE83_I111@MSTR_SCONN.SCONN288_H44441004(CHIPS)':
 'DQ'<6>: CDS_PINID='DQ(6)';
NODE_NAME     J9M1 155
 '@BASEBOARD_FAB2_LIB.BASEBOARD_FAB2(SCH_1):PAGE84_I14@MSTR_SCONN.SCONN288_H44441003(CHIPS)':
 'DQ'<7>: CDS_PINID='DQ(7)';
NET_NAME
'M_K_DQ<8>'
 '@BASEBOARD_FAB2_LIB.BASEBOARD_FAB2(SCH_1):M_K_DQ'<8>:
 C_SIGNAL='@baseboard_fab2_lib.baseboard_fab2(sch_1):m_k_dq(8)';
NODE_NAME     U2D1 DG84
 '@BASEBOARD_FAB2_LIB.BASEBOARD_FAB2(SCH_1):PAGE60_I172@CHPSET_LIB.SKX_EXT_B(CHIPS)':
 'DDR3_DQ'<8>: CDS_PINID='DDR3_DQ(8)';
NODE_NAME     J1B1 161
 '@BASEBOARD_FAB2_LIB.BASEBOARD_FAB2(SCH_1):PAGE83_I111@MSTR_SCONN.SCONN288_H44441004(CHIPS)':
 'DQ'<9>: CDS_PINID='DQ(9)';
NODE_NAME     J9M1 16
 '@BASEBOARD_FAB2_LIB.BASEBOARD_FAB2(SCH_1):PAGE84_I14@MSTR_SCONN.SCONN288_H44441003(CHIPS)':
 'DQ'<8>: CDS_PINID='DQ(8)';
NET_NAME
'M_K_DQ<9>'
 '@BASEBOARD_FAB2_LIB.BASEBOARD_FAB2(SCH_1):M_K_DQ'<9>:
 C_SIGNAL='@baseboard_fab2_lib.baseboard_fab2(sch_1):m_k_dq(9)';
NODE_NAME     U2D1 DH85
 '@BASEBOARD_FAB2_LIB.BASEBOARD_FAB2(SCH_1):PAGE60_I172@CHPSET_LIB.SKX_EXT_B(CHIPS)':
 'DDR3_DQ'<9>: CDS_PINID='DDR3_DQ(9)';
NODE_NAME     J1B1 16
 '@BASEBOARD_FAB2_LIB.BASEBOARD_FAB2(SCH_1):PAGE83_I111@MSTR_SCONN.SCONN288_H44441004(CHIPS)':
 'DQ'<8>: CDS_PINID='DQ(8)';
NODE_NAME     J9M1 161
 '@BASEBOARD_FAB2_LIB.BASEBOARD_FAB2(SCH_1):PAGE84_I14@MSTR_SCONN.SCONN288_H44441003(CHIPS)':
 'DQ'<9>: CDS_PINID='DQ(9)';
NET_NAME
'M_K_DQS_DN<0>'
 '@BASEBOARD_FAB2_LIB.BASEBOARD_FAB2(SCH_1):M_K_DQS_DN'<0>:
 C_SIGNAL='@baseboard_fab2_lib.baseboard_fab2(sch_1):m_k_dqs_dn(0)';
NODE_NAME     U2D1 CU84
 '@BASEBOARD_FAB2_LIB.BASEBOARD_FAB2(SCH_1):PAGE60_I172@CHPSET_LIB.SKX_EXT_B(CHIPS)':
 'DDR3_DQS_DN'<0>: CDS_PINID='DDR3_DQS_DN(0)';
NODE_NAME     J1B1 152
 '@BASEBOARD_FAB2_LIB.BASEBOARD_FAB2(SCH_1):PAGE83_I66@MSTR_SCONN.SCONN288_H44441004(CHIPS)':
 'DQS0N': CDS_PINID='DQS0N';
NODE_NAME     J9M1 152
 '@BASEBOARD_FAB2_LIB.BASEBOARD_FAB2(SCH_1):PAGE84_I102@MSTR_SCONN.SCONN288_H44441003(CHIPS)':
 'DQS0N': CDS_PINID='DQS0N';
NET_NAME
'M_K_DQS_DN<10>'
 '@BASEBOARD_FAB2_LIB.BASEBOARD_FAB2(SCH_1):M_K_DQS_DN'<10>:
 C_SIGNAL='@baseboard_fab2_lib.baseboard_fab2(sch_1):m_k_dqs_dn(10)';
NODE_NAME     U2D1 DM85
 '@BASEBOARD_FAB2_LIB.BASEBOARD_FAB2(SCH_1):PAGE60_I172@CHPSET_LIB.SKX_EXT_B(CHIPS)':
 'DDR3_DQS_DN'<10>: CDS_PINID='DDR3_DQS_DN(10)';
NODE_NAME     J1B1 19
 '@BASEBOARD_FAB2_LIB.BASEBOARD_FAB2(SCH_1):PAGE83_I66@MSTR_SCONN.SCONN288_H44441004(CHIPS)':
 'DQS10N': CDS_PINID='DQS10N';
NODE_NAME     J9M1 19
 '@BASEBOARD_FAB2_LIB.BASEBOARD_FAB2(SCH_1):PAGE84_I102@MSTR_SCONN.SCONN288_H44441003(CHIPS)':
 'DQS10N': CDS_PINID='DQS10N';
NET_NAME
'M_K_DQS_DN<11>'
 '@BASEBOARD_FAB2_LIB.BASEBOARD_FAB2(SCH_1):M_K_DQS_DN'<11>:
 C_SIGNAL='@baseboard_fab2_lib.baseboard_fab2(sch_1):m_k_dqs_dn(11)';
NODE_NAME     U2D1 DN80
 '@BASEBOARD_FAB2_LIB.BASEBOARD_FAB2(SCH_1):PAGE60_I172@CHPSET_LIB.SKX_EXT_B(CHIPS)':
 'DDR3_DQS_DN'<11>: CDS_PINID='DDR3_DQS_DN(11)';
NODE_NAME     J1B1 30
 '@BASEBOARD_FAB2_LIB.BASEBOARD_FAB2(SCH_1):PAGE83_I66@MSTR_SCONN.SCONN288_H44441004(CHIPS)':
 'DQS11N': CDS_PINID='DQS11N';
NODE_NAME     J9M1 30
 '@BASEBOARD_FAB2_LIB.BASEBOARD_FAB2(SCH_1):PAGE84_I102@MSTR_SCONN.SCONN288_H44441003(CHIPS)':
 'DQS11N': CDS_PINID='DQS11N';
NET_NAME
'M_K_DQS_DN<12>'
 '@BASEBOARD_FAB2_LIB.BASEBOARD_FAB2(SCH_1):M_K_DQS_DN'<12>:
 C_SIGNAL='@baseboard_fab2_lib.baseboard_fab2(sch_1):m_k_dqs_dn(12)';
NODE_NAME     U2D1 DP75
 '@BASEBOARD_FAB2_LIB.BASEBOARD_FAB2(SCH_1):PAGE60_I172@CHPSET_LIB.SKX_EXT_B(CHIPS)':
 'DDR3_DQS_DN'<12>: CDS_PINID='DDR3_DQS_DN(12)';
NODE_NAME     J1B1 41
 '@BASEBOARD_FAB2_LIB.BASEBOARD_FAB2(SCH_1):PAGE83_I66@MSTR_SCONN.SCONN288_H44441004(CHIPS)':
 'DQS12N': CDS_PINID='DQS12N';
NODE_NAME     J9M1 41
 '@BASEBOARD_FAB2_LIB.BASEBOARD_FAB2(SCH_1):PAGE84_I102@MSTR_SCONN.SCONN288_H44441003(CHIPS)':
 'DQS12N': CDS_PINID='DQS12N';
NET_NAME
'M_K_DQS_DN<13>'
 '@BASEBOARD_FAB2_LIB.BASEBOARD_FAB2(SCH_1):M_K_DQS_DN'<13>:
 C_SIGNAL='@baseboard_fab2_lib.baseboard_fab2(sch_1):m_k_dqs_dn(13)';
NODE_NAME     U2D1 EA38
 '@BASEBOARD_FAB2_LIB.BASEBOARD_FAB2(SCH_1):PAGE60_I172@CHPSET_LIB.SKX_EXT_B(CHIPS)':
 'DDR3_DQS_DN'<13>: CDS_PINID='DDR3_DQS_DN(13)';
NODE_NAME     J1B1 100
 '@BASEBOARD_FAB2_LIB.BASEBOARD_FAB2(SCH_1):PAGE83_I66@MSTR_SCONN.SCONN288_H44441004(CHIPS)':
 'DQS13N': CDS_PINID='DQS13N';
NODE_NAME     J9M1 100
 '@BASEBOARD_FAB2_LIB.BASEBOARD_FAB2(SCH_1):PAGE84_I102@MSTR_SCONN.SCONN288_H44441003(CHIPS)':
 'DQS13N': CDS_PINID='DQS13N';
NET_NAME
'M_K_DQS_DN<14>'
 '@BASEBOARD_FAB2_LIB.BASEBOARD_FAB2(SCH_1):M_K_DQS_DN'<14>:
 C_SIGNAL='@baseboard_fab2_lib.baseboard_fab2(sch_1):m_k_dqs_dn(14)';
NODE_NAME     U2D1 DP35
 '@BASEBOARD_FAB2_LIB.BASEBOARD_FAB2(SCH_1):PAGE60_I172@CHPSET_LIB.SKX_EXT_B(CHIPS)':
 'DDR3_DQS_DN'<14>: CDS_PINID='DDR3_DQS_DN(14)';
NODE_NAME     J1B1 111
 '@BASEBOARD_FAB2_LIB.BASEBOARD_FAB2(SCH_1):PAGE83_I66@MSTR_SCONN.SCONN288_H44441004(CHIPS)':
 'DQS14N': CDS_PINID='DQS14N';
NODE_NAME     J9M1 111
 '@BASEBOARD_FAB2_LIB.BASEBOARD_FAB2(SCH_1):PAGE84_I102@MSTR_SCONN.SCONN288_H44441003(CHIPS)':
 'DQS14N': CDS_PINID='DQS14N';
NET_NAME
'M_K_DQS_DN<15>'
 '@BASEBOARD_FAB2_LIB.BASEBOARD_FAB2(SCH_1):M_K_DQS_DN'<15>:
 C_SIGNAL='@baseboard_fab2_lib.baseboard_fab2(sch_1):m_k_dqs_dn(15)';
NODE_NAME     U2D1 DM29
 '@BASEBOARD_FAB2_LIB.BASEBOARD_FAB2(SCH_1):PAGE60_I172@CHPSET_LIB.SKX_EXT_B(CHIPS)':
 'DDR3_DQS_DN'<15>: CDS_PINID='DDR3_DQS_DN(15)';
NODE_NAME     J1B1 122
 '@BASEBOARD_FAB2_LIB.BASEBOARD_FAB2(SCH_1):PAGE83_I66@MSTR_SCONN.SCONN288_H44441004(CHIPS)':
 'DQS15N': CDS_PINID='DQS15N';
NODE_NAME     J9M1 122
 '@BASEBOARD_FAB2_LIB.BASEBOARD_FAB2(SCH_1):PAGE84_I102@MSTR_SCONN.SCONN288_H44441003(CHIPS)':
 'DQS15N': CDS_PINID='DQS15N';
NET_NAME
'M_K_DQS_DN<16>'
 '@BASEBOARD_FAB2_LIB.BASEBOARD_FAB2(SCH_1):M_K_DQS_DN'<16>:
 C_SIGNAL='@baseboard_fab2_lib.baseboard_fab2(sch_1):m_k_dqs_dn(16)';
NODE_NAME     U2D1 DM23
 '@BASEBOARD_FAB2_LIB.BASEBOARD_FAB2(SCH_1):PAGE60_I172@CHPSET_LIB.SKX_EXT_B(CHIPS)':
 'DDR3_DQS_DN'<16>: CDS_PINID='DDR3_DQS_DN(16)';
NODE_NAME     J1B1 133
 '@BASEBOARD_FAB2_LIB.BASEBOARD_FAB2(SCH_1):PAGE83_I66@MSTR_SCONN.SCONN288_H44441004(CHIPS)':
 'DQS16N': CDS_PINID='DQS16N';
NODE_NAME     J9M1 133
 '@BASEBOARD_FAB2_LIB.BASEBOARD_FAB2(SCH_1):PAGE84_I102@MSTR_SCONN.SCONN288_H44441003(CHIPS)':
 'DQS16N': CDS_PINID='DQS16N';
NET_NAME
'M_K_DQS_DN<17>'
 '@BASEBOARD_FAB2_LIB.BASEBOARD_FAB2(SCH_1):M_K_DQS_DN'<17>:
 C_SIGNAL='@baseboard_fab2_lib.baseboard_fab2(sch_1):m_k_dqs_dn(17)';
NODE_NAME     U2D1 DB67
 '@BASEBOARD_FAB2_LIB.BASEBOARD_FAB2(SCH_1):PAGE60_I172@CHPSET_LIB.SKX_EXT_B(CHIPS)':
 'DDR3_DQS_DN'<17>: CDS_PINID='DDR3_DQS_DN(17)';
NODE_NAME     J1B1 52
 '@BASEBOARD_FAB2_LIB.BASEBOARD_FAB2(SCH_1):PAGE83_I66@MSTR_SCONN.SCONN288_H44441004(CHIPS)':
 'DQS17N': CDS_PINID='DQS17N';
NODE_NAME     J9M1 52
 '@BASEBOARD_FAB2_LIB.BASEBOARD_FAB2(SCH_1):PAGE84_I102@MSTR_SCONN.SCONN288_H44441003(CHIPS)':
 'DQS17N': CDS_PINID='DQS17N';
NET_NAME
'M_K_DQS_DN<1>'
 '@BASEBOARD_FAB2_LIB.BASEBOARD_FAB2(SCH_1):M_K_DQS_DN'<1>:
 C_SIGNAL='@baseboard_fab2_lib.baseboard_fab2(sch_1):m_k_dqs_dn(1)';
NODE_NAME     U2D1 DN84
 '@BASEBOARD_FAB2_LIB.BASEBOARD_FAB2(SCH_1):PAGE60_I172@CHPSET_LIB.SKX_EXT_B(CHIPS)':
 'DDR3_DQS_DN'<1>: CDS_PINID='DDR3_DQS_DN(1)';
NODE_NAME     J1B1 163
 '@BASEBOARD_FAB2_LIB.BASEBOARD_FAB2(SCH_1):PAGE83_I66@MSTR_SCONN.SCONN288_H44441004(CHIPS)':
 'DQS1N': CDS_PINID='DQS1N';
NODE_NAME     J9M1 163
 '@BASEBOARD_FAB2_LIB.BASEBOARD_FAB2(SCH_1):PAGE84_I102@MSTR_SCONN.SCONN288_H44441003(CHIPS)':
 'DQS1N': CDS_PINID='DQS1N';
NET_NAME
'M_K_DQS_DN<2>'
 '@BASEBOARD_FAB2_LIB.BASEBOARD_FAB2(SCH_1):M_K_DQS_DN'<2>:
 C_SIGNAL='@baseboard_fab2_lib.baseboard_fab2(sch_1):m_k_dqs_dn(2)';
NODE_NAME     U2D1 DL82
 '@BASEBOARD_FAB2_LIB.BASEBOARD_FAB2(SCH_1):PAGE60_I172@CHPSET_LIB.SKX_EXT_B(CHIPS)':
 'DDR3_DQS_DN'<2>: CDS_PINID='DDR3_DQS_DN(2)';
NODE_NAME     J1B1 174
 '@BASEBOARD_FAB2_LIB.BASEBOARD_FAB2(SCH_1):PAGE83_I66@MSTR_SCONN.SCONN288_H44441004(CHIPS)':
 'DQS2N': CDS_PINID='DQS2N';
NODE_NAME     J9M1 174
 '@BASEBOARD_FAB2_LIB.BASEBOARD_FAB2(SCH_1):PAGE84_I102@MSTR_SCONN.SCONN288_H44441003(CHIPS)':
 'DQS2N': CDS_PINID='DQS2N';
NET_NAME
'M_K_DQS_DN<3>'
 '@BASEBOARD_FAB2_LIB.BASEBOARD_FAB2(SCH_1):M_K_DQS_DN'<3>:
 C_SIGNAL='@baseboard_fab2_lib.baseboard_fab2(sch_1):m_k_dqs_dn(3)';
NODE_NAME     U2D1 DV75
 '@BASEBOARD_FAB2_LIB.BASEBOARD_FAB2(SCH_1):PAGE60_I172@CHPSET_LIB.SKX_EXT_B(CHIPS)':
 'DDR3_DQS_DN'<3>: CDS_PINID='DDR3_DQS_DN(3)';
NODE_NAME     J1B1 185
 '@BASEBOARD_FAB2_LIB.BASEBOARD_FAB2(SCH_1):PAGE83_I66@MSTR_SCONN.SCONN288_H44441004(CHIPS)':
 'DQS3N': CDS_PINID='DQS3N';
NODE_NAME     J9M1 185
 '@BASEBOARD_FAB2_LIB.BASEBOARD_FAB2(SCH_1):PAGE84_I102@MSTR_SCONN.SCONN288_H44441003(CHIPS)':
 'DQS3N': CDS_PINID='DQS3N';
NET_NAME
'M_K_DQS_DN<4>'
 '@BASEBOARD_FAB2_LIB.BASEBOARD_FAB2(SCH_1):M_K_DQS_DN'<4>:
 C_SIGNAL='@baseboard_fab2_lib.baseboard_fab2(sch_1):m_k_dqs_dn(4)';
NODE_NAME     U2D1 EE38
 '@BASEBOARD_FAB2_LIB.BASEBOARD_FAB2(SCH_1):PAGE60_I172@CHPSET_LIB.SKX_EXT_B(CHIPS)':
 'DDR3_DQS_DN'<4>: CDS_PINID='DDR3_DQS_DN(4)';
NODE_NAME     J1B1 244
 '@BASEBOARD_FAB2_LIB.BASEBOARD_FAB2(SCH_1):PAGE83_I66@MSTR_SCONN.SCONN288_H44441004(CHIPS)':
 'DQS4N': CDS_PINID='DQS4N';
NODE_NAME     J9M1 244
 '@BASEBOARD_FAB2_LIB.BASEBOARD_FAB2(SCH_1):PAGE84_I102@MSTR_SCONN.SCONN288_H44441003(CHIPS)':
 'DQS4N': CDS_PINID='DQS4N';
NET_NAME
'M_K_DQS_DN<5>'
 '@BASEBOARD_FAB2_LIB.BASEBOARD_FAB2(SCH_1):M_K_DQS_DN'<5>:
 C_SIGNAL='@baseboard_fab2_lib.baseboard_fab2(sch_1):m_k_dqs_dn(5)';
NODE_NAME     U2D1 DV35
 '@BASEBOARD_FAB2_LIB.BASEBOARD_FAB2(SCH_1):PAGE60_I172@CHPSET_LIB.SKX_EXT_B(CHIPS)':
 'DDR3_DQS_DN'<5>: CDS_PINID='DDR3_DQS_DN(5)';
NODE_NAME     J1B1 255
 '@BASEBOARD_FAB2_LIB.BASEBOARD_FAB2(SCH_1):PAGE83_I66@MSTR_SCONN.SCONN288_H44441004(CHIPS)':
 'DQS5N': CDS_PINID='DQS5N';
NODE_NAME     J9M1 255
 '@BASEBOARD_FAB2_LIB.BASEBOARD_FAB2(SCH_1):PAGE84_I102@MSTR_SCONN.SCONN288_H44441003(CHIPS)':
 'DQS5N': CDS_PINID='DQS5N';
NET_NAME
'M_K_DQS_DN<6>'
 '@BASEBOARD_FAB2_LIB.BASEBOARD_FAB2(SCH_1):M_K_DQS_DN'<6>:
 C_SIGNAL='@baseboard_fab2_lib.baseboard_fab2(sch_1):m_k_dqs_dn(6)';
NODE_NAME     U2D1 DV29
 '@BASEBOARD_FAB2_LIB.BASEBOARD_FAB2(SCH_1):PAGE60_I172@CHPSET_LIB.SKX_EXT_B(CHIPS)':
 'DDR3_DQS_DN'<6>: CDS_PINID='DDR3_DQS_DN(6)';
NODE_NAME     J1B1 266
 '@BASEBOARD_FAB2_LIB.BASEBOARD_FAB2(SCH_1):PAGE83_I66@MSTR_SCONN.SCONN288_H44441004(CHIPS)':
 'DQS6N': CDS_PINID='DQS6N';
NODE_NAME     J9M1 266
 '@BASEBOARD_FAB2_LIB.BASEBOARD_FAB2(SCH_1):PAGE84_I102@MSTR_SCONN.SCONN288_H44441003(CHIPS)':
 'DQS6N': CDS_PINID='DQS6N';
NET_NAME
'M_K_DQS_DN<7>'
 '@BASEBOARD_FAB2_LIB.BASEBOARD_FAB2(SCH_1):M_K_DQS_DN'<7>:
 C_SIGNAL='@baseboard_fab2_lib.baseboard_fab2(sch_1):m_k_dqs_dn(7)';
NODE_NAME     U2D1 DV23
 '@BASEBOARD_FAB2_LIB.BASEBOARD_FAB2(SCH_1):PAGE60_I172@CHPSET_LIB.SKX_EXT_B(CHIPS)':
 'DDR3_DQS_DN'<7>: CDS_PINID='DDR3_DQS_DN(7)';
NODE_NAME     J1B1 277
 '@BASEBOARD_FAB2_LIB.BASEBOARD_FAB2(SCH_1):PAGE83_I66@MSTR_SCONN.SCONN288_H44441004(CHIPS)':
 'DQS7N': CDS_PINID='DQS7N';
NODE_NAME     J9M1 277
 '@BASEBOARD_FAB2_LIB.BASEBOARD_FAB2(SCH_1):PAGE84_I102@MSTR_SCONN.SCONN288_H44441003(CHIPS)':
 'DQS7N': CDS_PINID='DQS7N';
NET_NAME
'M_K_DQS_DN<8>'
 '@BASEBOARD_FAB2_LIB.BASEBOARD_FAB2(SCH_1):M_K_DQS_DN'<8>:
 C_SIGNAL='@baseboard_fab2_lib.baseboard_fab2(sch_1):m_k_dqs_dn(8)';
NODE_NAME     U2D1 DF67
 '@BASEBOARD_FAB2_LIB.BASEBOARD_FAB2(SCH_1):PAGE60_I172@CHPSET_LIB.SKX_EXT_B(CHIPS)':
 'DDR3_DQS_DN'<8>: CDS_PINID='DDR3_DQS_DN(8)';
NODE_NAME     J1B1 196
 '@BASEBOARD_FAB2_LIB.BASEBOARD_FAB2(SCH_1):PAGE83_I66@MSTR_SCONN.SCONN288_H44441004(CHIPS)':
 'DQS8N': CDS_PINID='DQS8N';
NODE_NAME     J9M1 196
 '@BASEBOARD_FAB2_LIB.BASEBOARD_FAB2(SCH_1):PAGE84_I102@MSTR_SCONN.SCONN288_H44441003(CHIPS)':
 'DQS8N': CDS_PINID='DQS8N';
NET_NAME
'M_K_DQS_DN<9>'
 '@BASEBOARD_FAB2_LIB.BASEBOARD_FAB2(SCH_1):M_K_DQS_DN'<9>:
 C_SIGNAL='@baseboard_fab2_lib.baseboard_fab2(sch_1):m_k_dqs_dn(9)';
NODE_NAME     U2D1 CR84
 '@BASEBOARD_FAB2_LIB.BASEBOARD_FAB2(SCH_1):PAGE60_I172@CHPSET_LIB.SKX_EXT_B(CHIPS)':
 'DDR3_DQS_DN'<9>: CDS_PINID='DDR3_DQS_DN(9)';
NODE_NAME     J1B1 8
 '@BASEBOARD_FAB2_LIB.BASEBOARD_FAB2(SCH_1):PAGE83_I66@MSTR_SCONN.SCONN288_H44441004(CHIPS)':
 'DQS9N': CDS_PINID='DQS9N';
NODE_NAME     J9M1 8
 '@BASEBOARD_FAB2_LIB.BASEBOARD_FAB2(SCH_1):PAGE84_I102@MSTR_SCONN.SCONN288_H44441003(CHIPS)':
 'DQS9N': CDS_PINID='DQS9N';
NET_NAME
'M_K_DQS_DP<0>'
 '@BASEBOARD_FAB2_LIB.BASEBOARD_FAB2(SCH_1):M_K_DQS_DP'<0>:
 C_SIGNAL='@baseboard_fab2_lib.baseboard_fab2(sch_1):m_k_dqs_dp(0)';
NODE_NAME     U2D1 CV85
 '@BASEBOARD_FAB2_LIB.BASEBOARD_FAB2(SCH_1):PAGE60_I172@CHPSET_LIB.SKX_EXT_B(CHIPS)':
 'DDR3_DQS_DP'<0>: CDS_PINID='DDR3_DQS_DP(0)';
NODE_NAME     J1B1 153
 '@BASEBOARD_FAB2_LIB.BASEBOARD_FAB2(SCH_1):PAGE83_I66@MSTR_SCONN.SCONN288_H44441004(CHIPS)':
 'DQS0P': CDS_PINID='DQS0P';
NODE_NAME     J9M1 153
 '@BASEBOARD_FAB2_LIB.BASEBOARD_FAB2(SCH_1):PAGE84_I102@MSTR_SCONN.SCONN288_H44441003(CHIPS)':
 'DQS0P': CDS_PINID='DQS0P';
NET_NAME
'M_K_DQS_DP<10>'
 '@BASEBOARD_FAB2_LIB.BASEBOARD_FAB2(SCH_1):M_K_DQS_DP'<10>:
 C_SIGNAL='@baseboard_fab2_lib.baseboard_fab2(sch_1):m_k_dqs_dp(10)';
NODE_NAME     U2D1 DL84
 '@BASEBOARD_FAB2_LIB.BASEBOARD_FAB2(SCH_1):PAGE60_I172@CHPSET_LIB.SKX_EXT_B(CHIPS)':
 'DDR3_DQS_DP'<10>: CDS_PINID='DDR3_DQS_DP(10)';
NODE_NAME     J1B1 18
 '@BASEBOARD_FAB2_LIB.BASEBOARD_FAB2(SCH_1):PAGE83_I66@MSTR_SCONN.SCONN288_H44441004(CHIPS)':
 'DQS10P': CDS_PINID='DQS10P';
NODE_NAME     J9M1 18
 '@BASEBOARD_FAB2_LIB.BASEBOARD_FAB2(SCH_1):PAGE84_I102@MSTR_SCONN.SCONN288_H44441003(CHIPS)':
 'DQS10P': CDS_PINID='DQS10P';
NET_NAME
'M_K_DQS_DP<11>'
 '@BASEBOARD_FAB2_LIB.BASEBOARD_FAB2(SCH_1):M_K_DQS_DP'<11>:
 C_SIGNAL='@baseboard_fab2_lib.baseboard_fab2(sch_1):m_k_dqs_dp(11)';
NODE_NAME     U2D1 DP79
 '@BASEBOARD_FAB2_LIB.BASEBOARD_FAB2(SCH_1):PAGE60_I172@CHPSET_LIB.SKX_EXT_B(CHIPS)':
 'DDR3_DQS_DP'<11>: CDS_PINID='DDR3_DQS_DP(11)';
NODE_NAME     J1B1 29
 '@BASEBOARD_FAB2_LIB.BASEBOARD_FAB2(SCH_1):PAGE83_I66@MSTR_SCONN.SCONN288_H44441004(CHIPS)':
 'DQS11P': CDS_PINID='DQS11P';
NODE_NAME     J9M1 29
 '@BASEBOARD_FAB2_LIB.BASEBOARD_FAB2(SCH_1):PAGE84_I102@MSTR_SCONN.SCONN288_H44441003(CHIPS)':
 'DQS11P': CDS_PINID='DQS11P';
NET_NAME
'M_K_DQS_DP<12>'
 '@BASEBOARD_FAB2_LIB.BASEBOARD_FAB2(SCH_1):M_K_DQS_DP'<12>:
 C_SIGNAL='@baseboard_fab2_lib.baseboard_fab2(sch_1):m_k_dqs_dp(12)';
NODE_NAME     U2D1 DM75
 '@BASEBOARD_FAB2_LIB.BASEBOARD_FAB2(SCH_1):PAGE60_I172@CHPSET_LIB.SKX_EXT_B(CHIPS)':
 'DDR3_DQS_DP'<12>: CDS_PINID='DDR3_DQS_DP(12)';
NODE_NAME     J1B1 40
 '@BASEBOARD_FAB2_LIB.BASEBOARD_FAB2(SCH_1):PAGE83_I66@MSTR_SCONN.SCONN288_H44441004(CHIPS)':
 'DQS12P': CDS_PINID='DQS12P';
NODE_NAME     J9M1 40
 '@BASEBOARD_FAB2_LIB.BASEBOARD_FAB2(SCH_1):PAGE84_I102@MSTR_SCONN.SCONN288_H44441003(CHIPS)':
 'DQS12P': CDS_PINID='DQS12P';
NET_NAME
'M_K_DQS_DP<13>'
 '@BASEBOARD_FAB2_LIB.BASEBOARD_FAB2(SCH_1):M_K_DQS_DP'<13>:
 C_SIGNAL='@baseboard_fab2_lib.baseboard_fab2(sch_1):m_k_dqs_dp(13)';
NODE_NAME     U2D1 DW38
 '@BASEBOARD_FAB2_LIB.BASEBOARD_FAB2(SCH_1):PAGE60_I172@CHPSET_LIB.SKX_EXT_B(CHIPS)':
 'DDR3_DQS_DP'<13>: CDS_PINID='DDR3_DQS_DP(13)';
NODE_NAME     J1B1 99
 '@BASEBOARD_FAB2_LIB.BASEBOARD_FAB2(SCH_1):PAGE83_I66@MSTR_SCONN.SCONN288_H44441004(CHIPS)':
 'DQS13P': CDS_PINID='DQS13P';
NODE_NAME     J9M1 99
 '@BASEBOARD_FAB2_LIB.BASEBOARD_FAB2(SCH_1):PAGE84_I102@MSTR_SCONN.SCONN288_H44441003(CHIPS)':
 'DQS13P': CDS_PINID='DQS13P';
NET_NAME
'M_K_DQS_DP<14>'
 '@BASEBOARD_FAB2_LIB.BASEBOARD_FAB2(SCH_1):M_K_DQS_DP'<14>:
 C_SIGNAL='@baseboard_fab2_lib.baseboard_fab2(sch_1):m_k_dqs_dp(14)';
NODE_NAME     U2D1 DM35
 '@BASEBOARD_FAB2_LIB.BASEBOARD_FAB2(SCH_1):PAGE60_I172@CHPSET_LIB.SKX_EXT_B(CHIPS)':
 'DDR3_DQS_DP'<14>: CDS_PINID='DDR3_DQS_DP(14)';
NODE_NAME     J1B1 110
 '@BASEBOARD_FAB2_LIB.BASEBOARD_FAB2(SCH_1):PAGE83_I66@MSTR_SCONN.SCONN288_H44441004(CHIPS)':
 'DQS14P': CDS_PINID='DQS14P';
NODE_NAME     J9M1 110
 '@BASEBOARD_FAB2_LIB.BASEBOARD_FAB2(SCH_1):PAGE84_I102@MSTR_SCONN.SCONN288_H44441003(CHIPS)':
 'DQS14P': CDS_PINID='DQS14P';
NET_NAME
'M_K_DQS_DP<15>'
 '@BASEBOARD_FAB2_LIB.BASEBOARD_FAB2(SCH_1):M_K_DQS_DP'<15>:
 C_SIGNAL='@baseboard_fab2_lib.baseboard_fab2(sch_1):m_k_dqs_dp(15)';
NODE_NAME     U2D1 DP29
 '@BASEBOARD_FAB2_LIB.BASEBOARD_FAB2(SCH_1):PAGE60_I172@CHPSET_LIB.SKX_EXT_B(CHIPS)':
 'DDR3_DQS_DP'<15>: CDS_PINID='DDR3_DQS_DP(15)';
NODE_NAME     J1B1 121
 '@BASEBOARD_FAB2_LIB.BASEBOARD_FAB2(SCH_1):PAGE83_I66@MSTR_SCONN.SCONN288_H44441004(CHIPS)':
 'DQS15P': CDS_PINID='DQS15P';
NODE_NAME     J9M1 121
 '@BASEBOARD_FAB2_LIB.BASEBOARD_FAB2(SCH_1):PAGE84_I102@MSTR_SCONN.SCONN288_H44441003(CHIPS)':
 'DQS15P': CDS_PINID='DQS15P';
NET_NAME
'M_K_DQS_DP<16>'
 '@BASEBOARD_FAB2_LIB.BASEBOARD_FAB2(SCH_1):M_K_DQS_DP'<16>:
 C_SIGNAL='@baseboard_fab2_lib.baseboard_fab2(sch_1):m_k_dqs_dp(16)';
NODE_NAME     U2D1 DP23
 '@BASEBOARD_FAB2_LIB.BASEBOARD_FAB2(SCH_1):PAGE60_I172@CHPSET_LIB.SKX_EXT_B(CHIPS)':
 'DDR3_DQS_DP'<16>: CDS_PINID='DDR3_DQS_DP(16)';
NODE_NAME     J1B1 132
 '@BASEBOARD_FAB2_LIB.BASEBOARD_FAB2(SCH_1):PAGE83_I66@MSTR_SCONN.SCONN288_H44441004(CHIPS)':
 'DQS16P': CDS_PINID='DQS16P';
NODE_NAME     J9M1 132
 '@BASEBOARD_FAB2_LIB.BASEBOARD_FAB2(SCH_1):PAGE84_I102@MSTR_SCONN.SCONN288_H44441003(CHIPS)':
 'DQS16P': CDS_PINID='DQS16P';
NET_NAME
'M_K_DQS_DP<17>'
 '@BASEBOARD_FAB2_LIB.BASEBOARD_FAB2(SCH_1):M_K_DQS_DP'<17>:
 C_SIGNAL='@baseboard_fab2_lib.baseboard_fab2(sch_1):m_k_dqs_dp(17)';
NODE_NAME     U2D1 CY67
 '@BASEBOARD_FAB2_LIB.BASEBOARD_FAB2(SCH_1):PAGE60_I172@CHPSET_LIB.SKX_EXT_B(CHIPS)':
 'DDR3_DQS_DP'<17>: CDS_PINID='DDR3_DQS_DP(17)';
NODE_NAME     J1B1 51
 '@BASEBOARD_FAB2_LIB.BASEBOARD_FAB2(SCH_1):PAGE83_I66@MSTR_SCONN.SCONN288_H44441004(CHIPS)':
 'DQS17P': CDS_PINID='DQS17P';
NODE_NAME     J9M1 51
 '@BASEBOARD_FAB2_LIB.BASEBOARD_FAB2(SCH_1):PAGE84_I102@MSTR_SCONN.SCONN288_H44441003(CHIPS)':
 'DQS17P': CDS_PINID='DQS17P';
NET_NAME
'M_K_DQS_DP<1>'
 '@BASEBOARD_FAB2_LIB.BASEBOARD_FAB2(SCH_1):M_K_DQS_DP'<1>:
 C_SIGNAL='@baseboard_fab2_lib.baseboard_fab2(sch_1):m_k_dqs_dp(1)';
NODE_NAME     U2D1 DP85
 '@BASEBOARD_FAB2_LIB.BASEBOARD_FAB2(SCH_1):PAGE60_I172@CHPSET_LIB.SKX_EXT_B(CHIPS)':
 'DDR3_DQS_DP'<1>: CDS_PINID='DDR3_DQS_DP(1)';
NODE_NAME     J1B1 164
 '@BASEBOARD_FAB2_LIB.BASEBOARD_FAB2(SCH_1):PAGE83_I66@MSTR_SCONN.SCONN288_H44441004(CHIPS)':
 'DQS1P': CDS_PINID='DQS1P';
NODE_NAME     J9M1 164
 '@BASEBOARD_FAB2_LIB.BASEBOARD_FAB2(SCH_1):PAGE84_I102@MSTR_SCONN.SCONN288_H44441003(CHIPS)':
 'DQS1P': CDS_PINID='DQS1P';
NET_NAME
'M_K_DQS_DP<2>'
 '@BASEBOARD_FAB2_LIB.BASEBOARD_FAB2(SCH_1):M_K_DQS_DP'<2>:
 C_SIGNAL='@baseboard_fab2_lib.baseboard_fab2(sch_1):m_k_dqs_dp(2)';
NODE_NAME     U2D1 DM81
 '@BASEBOARD_FAB2_LIB.BASEBOARD_FAB2(SCH_1):PAGE60_I172@CHPSET_LIB.SKX_EXT_B(CHIPS)':
 'DDR3_DQS_DP'<2>: CDS_PINID='DDR3_DQS_DP(2)';
NODE_NAME     J1B1 175
 '@BASEBOARD_FAB2_LIB.BASEBOARD_FAB2(SCH_1):PAGE83_I66@MSTR_SCONN.SCONN288_H44441004(CHIPS)':
 'DQS2P': CDS_PINID='DQS2P';
NODE_NAME     J9M1 175
 '@BASEBOARD_FAB2_LIB.BASEBOARD_FAB2(SCH_1):PAGE84_I102@MSTR_SCONN.SCONN288_H44441003(CHIPS)':
 'DQS2P': CDS_PINID='DQS2P';
NET_NAME
'M_K_DQS_DP<3>'
 '@BASEBOARD_FAB2_LIB.BASEBOARD_FAB2(SCH_1):M_K_DQS_DP'<3>:
 C_SIGNAL='@baseboard_fab2_lib.baseboard_fab2(sch_1):m_k_dqs_dp(3)';
NODE_NAME     U2D1 DT75
 '@BASEBOARD_FAB2_LIB.BASEBOARD_FAB2(SCH_1):PAGE60_I172@CHPSET_LIB.SKX_EXT_B(CHIPS)':
 'DDR3_DQS_DP'<3>: CDS_PINID='DDR3_DQS_DP(3)';
NODE_NAME     J1B1 186
 '@BASEBOARD_FAB2_LIB.BASEBOARD_FAB2(SCH_1):PAGE83_I66@MSTR_SCONN.SCONN288_H44441004(CHIPS)':
 'DQS3P': CDS_PINID='DQS3P';
NODE_NAME     J9M1 186
 '@BASEBOARD_FAB2_LIB.BASEBOARD_FAB2(SCH_1):PAGE84_I102@MSTR_SCONN.SCONN288_H44441003(CHIPS)':
 'DQS3P': CDS_PINID='DQS3P';
NET_NAME
'M_K_DQS_DP<4>'
 '@BASEBOARD_FAB2_LIB.BASEBOARD_FAB2(SCH_1):M_K_DQS_DP'<4>:
 C_SIGNAL='@baseboard_fab2_lib.baseboard_fab2(sch_1):m_k_dqs_dp(4)';
NODE_NAME     U2D1 EC38
 '@BASEBOARD_FAB2_LIB.BASEBOARD_FAB2(SCH_1):PAGE60_I172@CHPSET_LIB.SKX_EXT_B(CHIPS)':
 'DDR3_DQS_DP'<4>: CDS_PINID='DDR3_DQS_DP(4)';
NODE_NAME     J1B1 245
 '@BASEBOARD_FAB2_LIB.BASEBOARD_FAB2(SCH_1):PAGE83_I66@MSTR_SCONN.SCONN288_H44441004(CHIPS)':
 'DQS4P': CDS_PINID='DQS4P';
NODE_NAME     J9M1 245
 '@BASEBOARD_FAB2_LIB.BASEBOARD_FAB2(SCH_1):PAGE84_I102@MSTR_SCONN.SCONN288_H44441003(CHIPS)':
 'DQS4P': CDS_PINID='DQS4P';
NET_NAME
'M_K_DQS_DP<5>'
 '@BASEBOARD_FAB2_LIB.BASEBOARD_FAB2(SCH_1):M_K_DQS_DP'<5>:
 C_SIGNAL='@baseboard_fab2_lib.baseboard_fab2(sch_1):m_k_dqs_dp(5)';
NODE_NAME     U2D1 DT35
 '@BASEBOARD_FAB2_LIB.BASEBOARD_FAB2(SCH_1):PAGE60_I172@CHPSET_LIB.SKX_EXT_B(CHIPS)':
 'DDR3_DQS_DP'<5>: CDS_PINID='DDR3_DQS_DP(5)';
NODE_NAME     J1B1 256
 '@BASEBOARD_FAB2_LIB.BASEBOARD_FAB2(SCH_1):PAGE83_I66@MSTR_SCONN.SCONN288_H44441004(CHIPS)':
 'DQS5P': CDS_PINID='DQS5P';
NODE_NAME     J9M1 256
 '@BASEBOARD_FAB2_LIB.BASEBOARD_FAB2(SCH_1):PAGE84_I102@MSTR_SCONN.SCONN288_H44441003(CHIPS)':
 'DQS5P': CDS_PINID='DQS5P';
NET_NAME
'M_K_DQS_DP<6>'
 '@BASEBOARD_FAB2_LIB.BASEBOARD_FAB2(SCH_1):M_K_DQS_DP'<6>:
 C_SIGNAL='@baseboard_fab2_lib.baseboard_fab2(sch_1):m_k_dqs_dp(6)';
NODE_NAME     U2D1 DT29
 '@BASEBOARD_FAB2_LIB.BASEBOARD_FAB2(SCH_1):PAGE60_I172@CHPSET_LIB.SKX_EXT_B(CHIPS)':
 'DDR3_DQS_DP'<6>: CDS_PINID='DDR3_DQS_DP(6)';
NODE_NAME     J1B1 267
 '@BASEBOARD_FAB2_LIB.BASEBOARD_FAB2(SCH_1):PAGE83_I66@MSTR_SCONN.SCONN288_H44441004(CHIPS)':
 'DQS6P': CDS_PINID='DQS6P';
NODE_NAME     J9M1 267
 '@BASEBOARD_FAB2_LIB.BASEBOARD_FAB2(SCH_1):PAGE84_I102@MSTR_SCONN.SCONN288_H44441003(CHIPS)':
 'DQS6P': CDS_PINID='DQS6P';
NET_NAME
'M_K_DQS_DP<7>'
 '@BASEBOARD_FAB2_LIB.BASEBOARD_FAB2(SCH_1):M_K_DQS_DP'<7>:
 C_SIGNAL='@baseboard_fab2_lib.baseboard_fab2(sch_1):m_k_dqs_dp(7)';
NODE_NAME     U2D1 DT23
 '@BASEBOARD_FAB2_LIB.BASEBOARD_FAB2(SCH_1):PAGE60_I172@CHPSET_LIB.SKX_EXT_B(CHIPS)':
 'DDR3_DQS_DP'<7>: CDS_PINID='DDR3_DQS_DP(7)';
NODE_NAME     J1B1 278
 '@BASEBOARD_FAB2_LIB.BASEBOARD_FAB2(SCH_1):PAGE83_I66@MSTR_SCONN.SCONN288_H44441004(CHIPS)':
 'DQS7P': CDS_PINID='DQS7P';
NODE_NAME     J9M1 278
 '@BASEBOARD_FAB2_LIB.BASEBOARD_FAB2(SCH_1):PAGE84_I102@MSTR_SCONN.SCONN288_H44441003(CHIPS)':
 'DQS7P': CDS_PINID='DQS7P';
NET_NAME
'M_K_DQS_DP<8>'
 '@BASEBOARD_FAB2_LIB.BASEBOARD_FAB2(SCH_1):M_K_DQS_DP'<8>:
 C_SIGNAL='@baseboard_fab2_lib.baseboard_fab2(sch_1):m_k_dqs_dp(8)';
NODE_NAME     U2D1 DD67
 '@BASEBOARD_FAB2_LIB.BASEBOARD_FAB2(SCH_1):PAGE60_I172@CHPSET_LIB.SKX_EXT_B(CHIPS)':
 'DDR3_DQS_DP'<8>: CDS_PINID='DDR3_DQS_DP(8)';
NODE_NAME     J1B1 197
 '@BASEBOARD_FAB2_LIB.BASEBOARD_FAB2(SCH_1):PAGE83_I66@MSTR_SCONN.SCONN288_H44441004(CHIPS)':
 'DQS8P': CDS_PINID='DQS8P';
NODE_NAME     J9M1 197
 '@BASEBOARD_FAB2_LIB.BASEBOARD_FAB2(SCH_1):PAGE84_I102@MSTR_SCONN.SCONN288_H44441003(CHIPS)':
 'DQS8P': CDS_PINID='DQS8P';
NET_NAME
'M_K_DQS_DP<9>'
 '@BASEBOARD_FAB2_LIB.BASEBOARD_FAB2(SCH_1):M_K_DQS_DP'<9>:
 C_SIGNAL='@baseboard_fab2_lib.baseboard_fab2(sch_1):m_k_dqs_dp(9)';
NODE_NAME     U2D1 CP85
 '@BASEBOARD_FAB2_LIB.BASEBOARD_FAB2(SCH_1):PAGE60_I172@CHPSET_LIB.SKX_EXT_B(CHIPS)':
 'DDR3_DQS_DP'<9>: CDS_PINID='DDR3_DQS_DP(9)';
NODE_NAME     J1B1 7
 '@BASEBOARD_FAB2_LIB.BASEBOARD_FAB2(SCH_1):PAGE83_I66@MSTR_SCONN.SCONN288_H44441004(CHIPS)':
 'DQS9P': CDS_PINID='DQS9P';
NODE_NAME     J9M1 7
 '@BASEBOARD_FAB2_LIB.BASEBOARD_FAB2(SCH_1):PAGE84_I102@MSTR_SCONN.SCONN288_H44441003(CHIPS)':
 'DQS9P': CDS_PINID='DQS9P';
NET_NAME
'M_K_ECC<0>'
 '@BASEBOARD_FAB2_LIB.BASEBOARD_FAB2(SCH_1):M_K_ECC'<0>:
 C_SIGNAL='@baseboard_fab2_lib.baseboard_fab2(sch_1):m_k_ecc(0)';
NODE_NAME     U2D1 DA68
 '@BASEBOARD_FAB2_LIB.BASEBOARD_FAB2(SCH_1):PAGE60_I172@CHPSET_LIB.SKX_EXT_B(CHIPS)':
 'DDR3_ECC'<0>: CDS_PINID='DDR3_ECC(0)';
NODE_NAME     J1B1 194
 '@BASEBOARD_FAB2_LIB.BASEBOARD_FAB2(SCH_1):PAGE83_I111@MSTR_SCONN.SCONN288_H44441004(CHIPS)':
 'CB'<1>: CDS_PINID='CB(1)';
NODE_NAME     J9M1 49
 '@BASEBOARD_FAB2_LIB.BASEBOARD_FAB2(SCH_1):PAGE84_I14@MSTR_SCONN.SCONN288_H44441003(CHIPS)':
 'CB'<0>: CDS_PINID='CB(0)';
NET_NAME
'M_K_ECC<1>'
 '@BASEBOARD_FAB2_LIB.BASEBOARD_FAB2(SCH_1):M_K_ECC'<1>:
 C_SIGNAL='@baseboard_fab2_lib.baseboard_fab2(sch_1):m_k_ecc(1)';
NODE_NAME     U2D1 DE68
 '@BASEBOARD_FAB2_LIB.BASEBOARD_FAB2(SCH_1):PAGE60_I172@CHPSET_LIB.SKX_EXT_B(CHIPS)':
 'DDR3_ECC'<1>: CDS_PINID='DDR3_ECC(1)';
NODE_NAME     J1B1 49
 '@BASEBOARD_FAB2_LIB.BASEBOARD_FAB2(SCH_1):PAGE83_I111@MSTR_SCONN.SCONN288_H44441004(CHIPS)':
 'CB'<0>: CDS_PINID='CB(0)';
NODE_NAME     J9M1 194
 '@BASEBOARD_FAB2_LIB.BASEBOARD_FAB2(SCH_1):PAGE84_I14@MSTR_SCONN.SCONN288_H44441003(CHIPS)':
 'CB'<1>: CDS_PINID='CB(1)';
NET_NAME
'M_K_ECC<2>'
 '@BASEBOARD_FAB2_LIB.BASEBOARD_FAB2(SCH_1):M_K_ECC'<2>:
 C_SIGNAL='@baseboard_fab2_lib.baseboard_fab2(sch_1):m_k_ecc(2)';
NODE_NAME     U2D1 DB65
 '@BASEBOARD_FAB2_LIB.BASEBOARD_FAB2(SCH_1):PAGE60_I172@CHPSET_LIB.SKX_EXT_B(CHIPS)':
 'DDR3_ECC'<2>: CDS_PINID='DDR3_ECC(2)';
NODE_NAME     J1B1 201
 '@BASEBOARD_FAB2_LIB.BASEBOARD_FAB2(SCH_1):PAGE83_I111@MSTR_SCONN.SCONN288_H44441004(CHIPS)':
 'CB'<3>: CDS_PINID='CB(3)';
NODE_NAME     J9M1 56
 '@BASEBOARD_FAB2_LIB.BASEBOARD_FAB2(SCH_1):PAGE84_I14@MSTR_SCONN.SCONN288_H44441003(CHIPS)':
 'CB'<2>: CDS_PINID='CB(2)';
NET_NAME
'M_K_ECC<3>'
 '@BASEBOARD_FAB2_LIB.BASEBOARD_FAB2(SCH_1):M_K_ECC'<3>:
 C_SIGNAL='@baseboard_fab2_lib.baseboard_fab2(sch_1):m_k_ecc(3)';
NODE_NAME     U2D1 DD65
 '@BASEBOARD_FAB2_LIB.BASEBOARD_FAB2(SCH_1):PAGE60_I172@CHPSET_LIB.SKX_EXT_B(CHIPS)':
 'DDR3_ECC'<3>: CDS_PINID='DDR3_ECC(3)';
NODE_NAME     J1B1 56
 '@BASEBOARD_FAB2_LIB.BASEBOARD_FAB2(SCH_1):PAGE83_I111@MSTR_SCONN.SCONN288_H44441004(CHIPS)':
 'CB'<2>: CDS_PINID='CB(2)';
NODE_NAME     J9M1 201
 '@BASEBOARD_FAB2_LIB.BASEBOARD_FAB2(SCH_1):PAGE84_I14@MSTR_SCONN.SCONN288_H44441003(CHIPS)':
 'CB'<3>: CDS_PINID='CB(3)';
NET_NAME
'M_K_ECC<4>'
 '@BASEBOARD_FAB2_LIB.BASEBOARD_FAB2(SCH_1):M_K_ECC'<4>:
 C_SIGNAL='@baseboard_fab2_lib.baseboard_fab2(sch_1):m_k_ecc(4)';
NODE_NAME     U2D1 DB69
 '@BASEBOARD_FAB2_LIB.BASEBOARD_FAB2(SCH_1):PAGE60_I172@CHPSET_LIB.SKX_EXT_B(CHIPS)':
 'DDR3_ECC'<4>: CDS_PINID='DDR3_ECC(4)';
NODE_NAME     J1B1 192
 '@BASEBOARD_FAB2_LIB.BASEBOARD_FAB2(SCH_1):PAGE83_I111@MSTR_SCONN.SCONN288_H44441004(CHIPS)':
 'CB'<5>: CDS_PINID='CB(5)';
NODE_NAME     J9M1 47
 '@BASEBOARD_FAB2_LIB.BASEBOARD_FAB2(SCH_1):PAGE84_I14@MSTR_SCONN.SCONN288_H44441003(CHIPS)':
 'CB'<4>: CDS_PINID='CB(4)';
NET_NAME
'M_K_ECC<5>'
 '@BASEBOARD_FAB2_LIB.BASEBOARD_FAB2(SCH_1):M_K_ECC'<5>:
 C_SIGNAL='@baseboard_fab2_lib.baseboard_fab2(sch_1):m_k_ecc(5)';
NODE_NAME     U2D1 DD69
 '@BASEBOARD_FAB2_LIB.BASEBOARD_FAB2(SCH_1):PAGE60_I172@CHPSET_LIB.SKX_EXT_B(CHIPS)':
 'DDR3_ECC'<5>: CDS_PINID='DDR3_ECC(5)';
NODE_NAME     J1B1 47
 '@BASEBOARD_FAB2_LIB.BASEBOARD_FAB2(SCH_1):PAGE83_I111@MSTR_SCONN.SCONN288_H44441004(CHIPS)':
 'CB'<4>: CDS_PINID='CB(4)';
NODE_NAME     J9M1 192
 '@BASEBOARD_FAB2_LIB.BASEBOARD_FAB2(SCH_1):PAGE84_I14@MSTR_SCONN.SCONN288_H44441003(CHIPS)':
 'CB'<5>: CDS_PINID='CB(5)';
NET_NAME
'M_K_ECC<6>'
 '@BASEBOARD_FAB2_LIB.BASEBOARD_FAB2(SCH_1):M_K_ECC'<6>:
 C_SIGNAL='@baseboard_fab2_lib.baseboard_fab2(sch_1):m_k_ecc(6)';
NODE_NAME     U2D1 DA66
 '@BASEBOARD_FAB2_LIB.BASEBOARD_FAB2(SCH_1):PAGE60_I172@CHPSET_LIB.SKX_EXT_B(CHIPS)':
 'DDR3_ECC'<6>: CDS_PINID='DDR3_ECC(6)';
NODE_NAME     J1B1 199
 '@BASEBOARD_FAB2_LIB.BASEBOARD_FAB2(SCH_1):PAGE83_I111@MSTR_SCONN.SCONN288_H44441004(CHIPS)':
 'CB'<7>: CDS_PINID='CB(7)';
NODE_NAME     J9M1 54
 '@BASEBOARD_FAB2_LIB.BASEBOARD_FAB2(SCH_1):PAGE84_I14@MSTR_SCONN.SCONN288_H44441003(CHIPS)':
 'CB'<6>: CDS_PINID='CB(6)';
NET_NAME
'M_K_ECC<7>'
 '@BASEBOARD_FAB2_LIB.BASEBOARD_FAB2(SCH_1):M_K_ECC'<7>:
 C_SIGNAL='@baseboard_fab2_lib.baseboard_fab2(sch_1):m_k_ecc(7)';
NODE_NAME     U2D1 DE66
 '@BASEBOARD_FAB2_LIB.BASEBOARD_FAB2(SCH_1):PAGE60_I172@CHPSET_LIB.SKX_EXT_B(CHIPS)':
 'DDR3_ECC'<7>: CDS_PINID='DDR3_ECC(7)';
NODE_NAME     J1B1 54
 '@BASEBOARD_FAB2_LIB.BASEBOARD_FAB2(SCH_1):PAGE83_I111@MSTR_SCONN.SCONN288_H44441004(CHIPS)':
 'CB'<6>: CDS_PINID='CB(6)';
NODE_NAME     J9M1 199
 '@BASEBOARD_FAB2_LIB.BASEBOARD_FAB2(SCH_1):PAGE84_I14@MSTR_SCONN.SCONN288_H44441003(CHIPS)':
 'CB'<7>: CDS_PINID='CB(7)';
NET_NAME
'M_K_MA<0>'
 '@BASEBOARD_FAB2_LIB.BASEBOARD_FAB2(SCH_1):M_K_MA'<0>:
 C_SIGNAL='@baseboard_fab2_lib.baseboard_fab2(sch_1):m_k_ma(0)';
NODE_NAME     U2D1 EB53
 '@BASEBOARD_FAB2_LIB.BASEBOARD_FAB2(SCH_1):PAGE60_I172@CHPSET_LIB.SKX_EXT_B(CHIPS)':
 'DDR3_MA'<0>: CDS_PINID='DDR3_MA(0)';
NODE_NAME     J1B1 79
 '@BASEBOARD_FAB2_LIB.BASEBOARD_FAB2(SCH_1):PAGE83_I111@MSTR_SCONN.SCONN288_H44441004(CHIPS)':
 'A0': CDS_PINID='A0';
NODE_NAME     J9M1 79
 '@BASEBOARD_FAB2_LIB.BASEBOARD_FAB2(SCH_1):PAGE84_I14@MSTR_SCONN.SCONN288_H44441003(CHIPS)':
 'A0': CDS_PINID='A0';
NET_NAME
'M_K_MA<10>'
 '@BASEBOARD_FAB2_LIB.BASEBOARD_FAB2(SCH_1):M_K_MA'<10>:
 C_SIGNAL='@baseboard_fab2_lib.baseboard_fab2(sch_1):m_k_ma(10)';
NODE_NAME     U2D1 DW54
 '@BASEBOARD_FAB2_LIB.BASEBOARD_FAB2(SCH_1):PAGE60_I172@CHPSET_LIB.SKX_EXT_B(CHIPS)':
 'DDR3_MA'<10>: CDS_PINID='DDR3_MA(10)';
NODE_NAME     J1B1 225
 '@BASEBOARD_FAB2_LIB.BASEBOARD_FAB2(SCH_1):PAGE83_I111@MSTR_SCONN.SCONN288_H44441004(CHIPS)':
 'A10': CDS_PINID='A10';
NODE_NAME     J9M1 225
 '@BASEBOARD_FAB2_LIB.BASEBOARD_FAB2(SCH_1):PAGE84_I14@MSTR_SCONN.SCONN288_H44441003(CHIPS)':
 'A10': CDS_PINID='A10';
NET_NAME
'M_K_MA<11>'
 '@BASEBOARD_FAB2_LIB.BASEBOARD_FAB2(SCH_1):M_K_MA'<11>:
 C_SIGNAL='@baseboard_fab2_lib.baseboard_fab2(sch_1):m_k_ma(11)';
NODE_NAME     U2D1 EB61
 '@BASEBOARD_FAB2_LIB.BASEBOARD_FAB2(SCH_1):PAGE60_I172@CHPSET_LIB.SKX_EXT_B(CHIPS)':
 'DDR3_MA'<11>: CDS_PINID='DDR3_MA(11)';
NODE_NAME     J1B1 210
 '@BASEBOARD_FAB2_LIB.BASEBOARD_FAB2(SCH_1):PAGE83_I111@MSTR_SCONN.SCONN288_H44441004(CHIPS)':
 'A11': CDS_PINID='A11';
NODE_NAME     J9M1 210
 '@BASEBOARD_FAB2_LIB.BASEBOARD_FAB2(SCH_1):PAGE84_I14@MSTR_SCONN.SCONN288_H44441003(CHIPS)':
 'A11': CDS_PINID='A11';
NET_NAME
'M_K_MA<12>'
 '@BASEBOARD_FAB2_LIB.BASEBOARD_FAB2(SCH_1):M_K_MA'<12>:
 C_SIGNAL='@baseboard_fab2_lib.baseboard_fab2(sch_1):m_k_ma(12)';
NODE_NAME     U2D1 DT63
 '@BASEBOARD_FAB2_LIB.BASEBOARD_FAB2(SCH_1):PAGE60_I172@CHPSET_LIB.SKX_EXT_B(CHIPS)':
 'DDR3_MA'<12>: CDS_PINID='DDR3_MA(12)';
NODE_NAME     J1B1 65
 '@BASEBOARD_FAB2_LIB.BASEBOARD_FAB2(SCH_1):PAGE83_I111@MSTR_SCONN.SCONN288_H44441004(CHIPS)':
 'A12': CDS_PINID='A12';
NODE_NAME     J9M1 65
 '@BASEBOARD_FAB2_LIB.BASEBOARD_FAB2(SCH_1):PAGE84_I14@MSTR_SCONN.SCONN288_H44441003(CHIPS)':
 'A12': CDS_PINID='A12';
NET_NAME
'M_K_MA<13>'
 '@BASEBOARD_FAB2_LIB.BASEBOARD_FAB2(SCH_1):M_K_MA'<13>:
 C_SIGNAL='@baseboard_fab2_lib.baseboard_fab2(sch_1):m_k_ma(13)';
NODE_NAME     U2D1 DW48
 '@BASEBOARD_FAB2_LIB.BASEBOARD_FAB2(SCH_1):PAGE60_I172@CHPSET_LIB.SKX_EXT_B(CHIPS)':
 'DDR3_MA'<13>: CDS_PINID='DDR3_MA(13)';
NODE_NAME     J1B1 232
 '@BASEBOARD_FAB2_LIB.BASEBOARD_FAB2(SCH_1):PAGE83_I111@MSTR_SCONN.SCONN288_H44441004(CHIPS)':
 'A13': CDS_PINID='A13';
NODE_NAME     J9M1 232
 '@BASEBOARD_FAB2_LIB.BASEBOARD_FAB2(SCH_1):PAGE84_I14@MSTR_SCONN.SCONN288_H44441003(CHIPS)':
 'A13': CDS_PINID='A13';
NET_NAME
'M_K_MA<14>'
 '@BASEBOARD_FAB2_LIB.BASEBOARD_FAB2(SCH_1):M_K_MA'<14>:
 C_SIGNAL='@baseboard_fab2_lib.baseboard_fab2(sch_1):m_k_ma(14)';
NODE_NAME     U2D1 ED51
 '@BASEBOARD_FAB2_LIB.BASEBOARD_FAB2(SCH_1):PAGE60_I172@CHPSET_LIB.SKX_EXT_B(CHIPS)':
 'DDR3_MA'<14>: CDS_PINID='DDR3_MA(14)';
NODE_NAME     J1B1 228
 '@BASEBOARD_FAB2_LIB.BASEBOARD_FAB2(SCH_1):PAGE83_I111@MSTR_SCONN.SCONN288_H44441004(CHIPS)':
 'A14_WE_N': CDS_PINID='A14_WE_N';
NODE_NAME     J9M1 228
 '@BASEBOARD_FAB2_LIB.BASEBOARD_FAB2(SCH_1):PAGE84_I14@MSTR_SCONN.SCONN288_H44441003(CHIPS)':
 'A14_WE_N': CDS_PINID='A14_WE_N';
NET_NAME
'M_K_MA<15>'
 '@BASEBOARD_FAB2_LIB.BASEBOARD_FAB2(SCH_1):M_K_MA'<15>:
 C_SIGNAL='@baseboard_fab2_lib.baseboard_fab2(sch_1):m_k_ma(15)';
NODE_NAME     U2D1 DV49
 '@BASEBOARD_FAB2_LIB.BASEBOARD_FAB2(SCH_1):PAGE60_I172@CHPSET_LIB.SKX_EXT_B(CHIPS)':
 'DDR3_MA'<15>: CDS_PINID='DDR3_MA(15)';
NODE_NAME     J1B1 86
 '@BASEBOARD_FAB2_LIB.BASEBOARD_FAB2(SCH_1):PAGE83_I111@MSTR_SCONN.SCONN288_H44441004(CHIPS)':
 'A15_CAS_N': CDS_PINID='A15_CAS_N';
NODE_NAME     J9M1 86
 '@BASEBOARD_FAB2_LIB.BASEBOARD_FAB2(SCH_1):PAGE84_I14@MSTR_SCONN.SCONN288_H44441003(CHIPS)':
 'A15_CAS_N': CDS_PINID='A15_CAS_N';
NET_NAME
'M_K_MA<16>'
 '@BASEBOARD_FAB2_LIB.BASEBOARD_FAB2(SCH_1):M_K_MA'<16>:
 C_SIGNAL='@baseboard_fab2_lib.baseboard_fab2(sch_1):m_k_ma(16)';
NODE_NAME     U2D1 EA52
 '@BASEBOARD_FAB2_LIB.BASEBOARD_FAB2(SCH_1):PAGE60_I172@CHPSET_LIB.SKX_EXT_B(CHIPS)':
 'DDR3_MA'<16>: CDS_PINID='DDR3_MA(16)';
NODE_NAME     J1B1 82
 '@BASEBOARD_FAB2_LIB.BASEBOARD_FAB2(SCH_1):PAGE83_I111@MSTR_SCONN.SCONN288_H44441004(CHIPS)':
 'A16_RAS_N': CDS_PINID='A16_RAS_N';
NODE_NAME     J9M1 82
 '@BASEBOARD_FAB2_LIB.BASEBOARD_FAB2(SCH_1):PAGE84_I14@MSTR_SCONN.SCONN288_H44441003(CHIPS)':
 'A16_RAS_N': CDS_PINID='A16_RAS_N';
NET_NAME
'M_K_MA<17>'
 '@BASEBOARD_FAB2_LIB.BASEBOARD_FAB2(SCH_1):M_K_MA'<17>:
 C_SIGNAL='@baseboard_fab2_lib.baseboard_fab2(sch_1):m_k_ma(17)';
NODE_NAME     U2D1 EA46
 '@BASEBOARD_FAB2_LIB.BASEBOARD_FAB2(SCH_1):PAGE60_I172@CHPSET_LIB.SKX_EXT_B(CHIPS)':
 'DDR3_MA'<17>: CDS_PINID='DDR3_MA(17)';
NODE_NAME     J1B1 234
 '@BASEBOARD_FAB2_LIB.BASEBOARD_FAB2(SCH_1):PAGE83_I111@MSTR_SCONN.SCONN288_H44441004(CHIPS)':
 'A17': CDS_PINID='A17';
NODE_NAME     J9M1 234
 '@BASEBOARD_FAB2_LIB.BASEBOARD_FAB2(SCH_1):PAGE84_I14@MSTR_SCONN.SCONN288_H44441003(CHIPS)':
 'A17': CDS_PINID='A17';
NET_NAME
'M_K_MA<1>'
 '@BASEBOARD_FAB2_LIB.BASEBOARD_FAB2(SCH_1):M_K_MA'<1>:
 C_SIGNAL='@baseboard_fab2_lib.baseboard_fab2(sch_1):m_k_ma(1)';
NODE_NAME     U2D1 ED57
 '@BASEBOARD_FAB2_LIB.BASEBOARD_FAB2(SCH_1):PAGE60_I172@CHPSET_LIB.SKX_EXT_B(CHIPS)':
 'DDR3_MA'<1>: CDS_PINID='DDR3_MA(1)';
NODE_NAME     J1B1 72
 '@BASEBOARD_FAB2_LIB.BASEBOARD_FAB2(SCH_1):PAGE83_I111@MSTR_SCONN.SCONN288_H44441004(CHIPS)':
 'A1': CDS_PINID='A1';
NODE_NAME     J9M1 72
 '@BASEBOARD_FAB2_LIB.BASEBOARD_FAB2(SCH_1):PAGE84_I14@MSTR_SCONN.SCONN288_H44441003(CHIPS)':
 'A1': CDS_PINID='A1';
NET_NAME
'M_K_MA<2>'
 '@BASEBOARD_FAB2_LIB.BASEBOARD_FAB2(SCH_1):M_K_MA'<2>:
 C_SIGNAL='@baseboard_fab2_lib.baseboard_fab2(sch_1):m_k_ma(2)';
NODE_NAME     U2D1 EE58
 '@BASEBOARD_FAB2_LIB.BASEBOARD_FAB2(SCH_1):PAGE60_I172@CHPSET_LIB.SKX_EXT_B(CHIPS)':
 'DDR3_MA'<2>: CDS_PINID='DDR3_MA(2)';
NODE_NAME     J1B1 216
 '@BASEBOARD_FAB2_LIB.BASEBOARD_FAB2(SCH_1):PAGE83_I111@MSTR_SCONN.SCONN288_H44441004(CHIPS)':
 'A2': CDS_PINID='A2';
NODE_NAME     J9M1 216
 '@BASEBOARD_FAB2_LIB.BASEBOARD_FAB2(SCH_1):PAGE84_I14@MSTR_SCONN.SCONN288_H44441003(CHIPS)':
 'A2': CDS_PINID='A2';
NET_NAME
'M_K_MA<3>'
 '@BASEBOARD_FAB2_LIB.BASEBOARD_FAB2(SCH_1):M_K_MA'<3>:
 C_SIGNAL='@baseboard_fab2_lib.baseboard_fab2(sch_1):m_k_ma(3)';
NODE_NAME     U2D1 EB57
 '@BASEBOARD_FAB2_LIB.BASEBOARD_FAB2(SCH_1):PAGE60_I172@CHPSET_LIB.SKX_EXT_B(CHIPS)':
 'DDR3_MA'<3>: CDS_PINID='DDR3_MA(3)';
NODE_NAME     J1B1 71
 '@BASEBOARD_FAB2_LIB.BASEBOARD_FAB2(SCH_1):PAGE83_I111@MSTR_SCONN.SCONN288_H44441004(CHIPS)':
 'A3': CDS_PINID='A3';
NODE_NAME     J9M1 71
 '@BASEBOARD_FAB2_LIB.BASEBOARD_FAB2(SCH_1):PAGE84_I14@MSTR_SCONN.SCONN288_H44441003(CHIPS)':
 'A3': CDS_PINID='A3';
NET_NAME
'M_K_MA<4>'
 '@BASEBOARD_FAB2_LIB.BASEBOARD_FAB2(SCH_1):M_K_MA'<4>:
 C_SIGNAL='@baseboard_fab2_lib.baseboard_fab2(sch_1):m_k_ma(4)';
NODE_NAME     U2D1 ED59
 '@BASEBOARD_FAB2_LIB.BASEBOARD_FAB2(SCH_1):PAGE60_I172@CHPSET_LIB.SKX_EXT_B(CHIPS)':
 'DDR3_MA'<4>: CDS_PINID='DDR3_MA(4)';
NODE_NAME     J1B1 214
 '@BASEBOARD_FAB2_LIB.BASEBOARD_FAB2(SCH_1):PAGE83_I111@MSTR_SCONN.SCONN288_H44441004(CHIPS)':
 'A4': CDS_PINID='A4';
NODE_NAME     J9M1 214
 '@BASEBOARD_FAB2_LIB.BASEBOARD_FAB2(SCH_1):PAGE84_I14@MSTR_SCONN.SCONN288_H44441003(CHIPS)':
 'A4': CDS_PINID='A4';
NET_NAME
'M_K_MA<5>'
 '@BASEBOARD_FAB2_LIB.BASEBOARD_FAB2(SCH_1):M_K_MA'<5>:
 C_SIGNAL='@baseboard_fab2_lib.baseboard_fab2(sch_1):m_k_ma(5)';
NODE_NAME     U2D1 EA58
 '@BASEBOARD_FAB2_LIB.BASEBOARD_FAB2(SCH_1):PAGE60_I172@CHPSET_LIB.SKX_EXT_B(CHIPS)':
 'DDR3_MA'<5>: CDS_PINID='DDR3_MA(5)';
NODE_NAME     J1B1 213
 '@BASEBOARD_FAB2_LIB.BASEBOARD_FAB2(SCH_1):PAGE83_I111@MSTR_SCONN.SCONN288_H44441004(CHIPS)':
 'A5': CDS_PINID='A5';
NODE_NAME     J9M1 213
 '@BASEBOARD_FAB2_LIB.BASEBOARD_FAB2(SCH_1):PAGE84_I14@MSTR_SCONN.SCONN288_H44441003(CHIPS)':
 'A5': CDS_PINID='A5';
NET_NAME
'M_K_MA<6>'
 '@BASEBOARD_FAB2_LIB.BASEBOARD_FAB2(SCH_1):M_K_MA'<6>:
 C_SIGNAL='@baseboard_fab2_lib.baseboard_fab2(sch_1):m_k_ma(6)';
NODE_NAME     U2D1 EE60
 '@BASEBOARD_FAB2_LIB.BASEBOARD_FAB2(SCH_1):PAGE60_I172@CHPSET_LIB.SKX_EXT_B(CHIPS)':
 'DDR3_MA'<6>: CDS_PINID='DDR3_MA(6)';
NODE_NAME     J1B1 69
 '@BASEBOARD_FAB2_LIB.BASEBOARD_FAB2(SCH_1):PAGE83_I111@MSTR_SCONN.SCONN288_H44441004(CHIPS)':
 'A6': CDS_PINID='A6';
NODE_NAME     J9M1 69
 '@BASEBOARD_FAB2_LIB.BASEBOARD_FAB2(SCH_1):PAGE84_I14@MSTR_SCONN.SCONN288_H44441003(CHIPS)':
 'A6': CDS_PINID='A6';
NET_NAME
'M_K_MA<7>'
 '@BASEBOARD_FAB2_LIB.BASEBOARD_FAB2(SCH_1):M_K_MA'<7>:
 C_SIGNAL='@baseboard_fab2_lib.baseboard_fab2(sch_1):m_k_ma(7)';
NODE_NAME     U2D1 EA60
 '@BASEBOARD_FAB2_LIB.BASEBOARD_FAB2(SCH_1):PAGE60_I172@CHPSET_LIB.SKX_EXT_B(CHIPS)':
 'DDR3_MA'<7>: CDS_PINID='DDR3_MA(7)';
NODE_NAME     J1B1 211
 '@BASEBOARD_FAB2_LIB.BASEBOARD_FAB2(SCH_1):PAGE83_I111@MSTR_SCONN.SCONN288_H44441004(CHIPS)':
 'A7': CDS_PINID='A7';
NODE_NAME     J9M1 211
 '@BASEBOARD_FAB2_LIB.BASEBOARD_FAB2(SCH_1):PAGE84_I14@MSTR_SCONN.SCONN288_H44441003(CHIPS)':
 'A7': CDS_PINID='A7';
NET_NAME
'M_K_MA<8>'
 '@BASEBOARD_FAB2_LIB.BASEBOARD_FAB2(SCH_1):M_K_MA'<8>:
 C_SIGNAL='@baseboard_fab2_lib.baseboard_fab2(sch_1):m_k_ma(8)';
NODE_NAME     U2D1 EB59
 '@BASEBOARD_FAB2_LIB.BASEBOARD_FAB2(SCH_1):PAGE60_I172@CHPSET_LIB.SKX_EXT_B(CHIPS)':
 'DDR3_MA'<8>: CDS_PINID='DDR3_MA(8)';
NODE_NAME     J1B1 68
 '@BASEBOARD_FAB2_LIB.BASEBOARD_FAB2(SCH_1):PAGE83_I111@MSTR_SCONN.SCONN288_H44441004(CHIPS)':
 'A8': CDS_PINID='A8';
NODE_NAME     J9M1 68
 '@BASEBOARD_FAB2_LIB.BASEBOARD_FAB2(SCH_1):PAGE84_I14@MSTR_SCONN.SCONN288_H44441003(CHIPS)':
 'A8': CDS_PINID='A8';
NET_NAME
'M_K_MA<9>'
 '@BASEBOARD_FAB2_LIB.BASEBOARD_FAB2(SCH_1):M_K_MA'<9>:
 C_SIGNAL='@baseboard_fab2_lib.baseboard_fab2(sch_1):m_k_ma(9)';
NODE_NAME     U2D1 EF61
 '@BASEBOARD_FAB2_LIB.BASEBOARD_FAB2(SCH_1):PAGE60_I172@CHPSET_LIB.SKX_EXT_B(CHIPS)':
 'DDR3_MA'<9>: CDS_PINID='DDR3_MA(9)';
NODE_NAME     J1B1 66
 '@BASEBOARD_FAB2_LIB.BASEBOARD_FAB2(SCH_1):PAGE83_I111@MSTR_SCONN.SCONN288_H44441004(CHIPS)':
 'A9': CDS_PINID='A9';
NODE_NAME     J9M1 66
 '@BASEBOARD_FAB2_LIB.BASEBOARD_FAB2(SCH_1):PAGE84_I14@MSTR_SCONN.SCONN288_H44441003(CHIPS)':
 'A9': CDS_PINID='A9';
NET_NAME
'M_K_ODT<0>'
 '@BASEBOARD_FAB2_LIB.BASEBOARD_FAB2(SCH_1):M_K_ODT'<0>:
 C_SIGNAL='@baseboard_fab2_lib.baseboard_fab2(sch_1):m_k_odt(0)';
NODE_NAME     U2D1 EE50
 '@BASEBOARD_FAB2_LIB.BASEBOARD_FAB2(SCH_1):PAGE60_I172@CHPSET_LIB.SKX_EXT_B(CHIPS)':
 'DDR3_ODT'<0>: CDS_PINID='DDR3_ODT(0)';
NODE_NAME     J1B1 87
 '@BASEBOARD_FAB2_LIB.BASEBOARD_FAB2(SCH_1):PAGE83_I111@MSTR_SCONN.SCONN288_H44441004(CHIPS)':
 'ODT'<0>: CDS_PINID='ODT(0)';
NET_NAME
'M_K_ODT<1>'
 '@BASEBOARD_FAB2_LIB.BASEBOARD_FAB2(SCH_1):M_K_ODT'<1>:
 C_SIGNAL='@baseboard_fab2_lib.baseboard_fab2(sch_1):m_k_odt(1)';
NODE_NAME     U2D1 EE48
 '@BASEBOARD_FAB2_LIB.BASEBOARD_FAB2(SCH_1):PAGE60_I172@CHPSET_LIB.SKX_EXT_B(CHIPS)':
 'DDR3_ODT'<1>: CDS_PINID='DDR3_ODT(1)';
NODE_NAME     J1B1 91
 '@BASEBOARD_FAB2_LIB.BASEBOARD_FAB2(SCH_1):PAGE83_I111@MSTR_SCONN.SCONN288_H44441004(CHIPS)':
 'ODT'<1>: CDS_PINID='ODT(1)';
NET_NAME
'M_K_ODT<2>'
 '@BASEBOARD_FAB2_LIB.BASEBOARD_FAB2(SCH_1):M_K_ODT'<2>:
 C_SIGNAL='@baseboard_fab2_lib.baseboard_fab2(sch_1):m_k_odt(2)';
NODE_NAME     U2D1 EA50
 '@BASEBOARD_FAB2_LIB.BASEBOARD_FAB2(SCH_1):PAGE60_I172@CHPSET_LIB.SKX_EXT_B(CHIPS)':
 'DDR3_ODT'<2>: CDS_PINID='DDR3_ODT(2)';
NODE_NAME     J9M1 87
 '@BASEBOARD_FAB2_LIB.BASEBOARD_FAB2(SCH_1):PAGE84_I14@MSTR_SCONN.SCONN288_H44441003(CHIPS)':
 'ODT'<0>: CDS_PINID='ODT(0)';
NET_NAME
'M_K_ODT<3>'
 '@BASEBOARD_FAB2_LIB.BASEBOARD_FAB2(SCH_1):M_K_ODT'<3>:
 C_SIGNAL='@baseboard_fab2_lib.baseboard_fab2(sch_1):m_k_odt(3)';
NODE_NAME     U2D1 EA48
 '@BASEBOARD_FAB2_LIB.BASEBOARD_FAB2(SCH_1):PAGE60_I172@CHPSET_LIB.SKX_EXT_B(CHIPS)':
 'DDR3_ODT'<3>: CDS_PINID='DDR3_ODT(3)';
NODE_NAME     J9M1 91
 '@BASEBOARD_FAB2_LIB.BASEBOARD_FAB2(SCH_1):PAGE84_I14@MSTR_SCONN.SCONN288_H44441003(CHIPS)':
 'ODT'<1>: CDS_PINID='ODT(1)';
NET_NAME
'M_K_PAR'
 '@BASEBOARD_FAB2_LIB.BASEBOARD_FAB2(SCH_1):M_K_PAR':
 C_SIGNAL='@baseboard_fab2_lib.baseboard_fab2(sch_1):m_k_par';
NODE_NAME     U2D1 ED53
 '@BASEBOARD_FAB2_LIB.BASEBOARD_FAB2(SCH_1):PAGE60_I172@CHPSET_LIB.SKX_EXT_B(CHIPS)':
 'DDR3_PAR': CDS_PINID='DDR3_PAR';
NODE_NAME     J1B1 222
 '@BASEBOARD_FAB2_LIB.BASEBOARD_FAB2(SCH_1):PAGE83_I111@MSTR_SCONN.SCONN288_H44441004(CHIPS)':
 'PAR': CDS_PINID='PAR';
NODE_NAME     J9M1 222
 '@BASEBOARD_FAB2_LIB.BASEBOARD_FAB2(SCH_1):PAGE84_I14@MSTR_SCONN.SCONN288_H44441003(CHIPS)':
 'PAR': CDS_PINID='PAR';
NET_NAME
'M_K_VREF'
 '@BASEBOARD_FAB2_LIB.BASEBOARD_FAB2(SCH_1):M_K_VREF':
 C_SIGNAL='@baseboard_fab2_lib.baseboard_fab2(sch_1):m_k_vref';
NODE_NAME     J1B1 146
 '@BASEBOARD_FAB2_LIB.BASEBOARD_FAB2(SCH_1):PAGE83_I111@MSTR_SCONN.SCONN288_H44441004(CHIPS)':
 'VREFCA': CDS_PINID='VREFCA';
NODE_NAME     C1B9 1
 '@BASEBOARD_FAB2_LIB.BASEBOARD_FAB2(SCH_1):PAGE83_I176@DEV_DISCRETE.CAP_A(CHIPS)':
 'A': CDS_PINID='A';
NODE_NAME     C9M1 1
 '@BASEBOARD_FAB2_LIB.BASEBOARD_FAB2(SCH_1):PAGE84_I4@DEV_DISCRETE.CAP_A(CHIPS)':
 'A': CDS_PINID='A';
NODE_NAME     J9M1 146
 '@BASEBOARD_FAB2_LIB.BASEBOARD_FAB2(SCH_1):PAGE84_I14@MSTR_SCONN.SCONN288_H44441003(CHIPS)':
 'VREFCA': CDS_PINID='VREFCA';
NODE_NAME     R9L11 1
 '@BASEBOARD_FAB2_LIB.BASEBOARD_FAB2(SCH_1):PAGE100_I4@MSTR_DISCRETE.RES(CHIPS)':
 'A': CDS_PINID='A';
NODE_NAME     R9M1 2
 '@BASEBOARD_FAB2_LIB.BASEBOARD_FAB2(SCH_1):PAGE100_I11@MSTR_DISCRETE.RES(CHIPS)':
 'B': CDS_PINID='B';
NODE_NAME     R9M2 2
 '@BASEBOARD_FAB2_LIB.BASEBOARD_FAB2(SCH_1):PAGE100_I13@MSTR_DISCRETE.RES(CHIPS)':
 'B': CDS_PINID='B';
NET_NAME
'M_L_ACT_N'
 '@BASEBOARD_FAB2_LIB.BASEBOARD_FAB2(SCH_1):M_L_ACT_N':
 C_SIGNAL='@baseboard_fab2_lib.baseboard_fab2(sch_1):m_l_act_n';
NODE_NAME     U2D1 DR62
 '@BASEBOARD_FAB2_LIB.BASEBOARD_FAB2(SCH_1):PAGE61_I172@CHPSET_LIB.SKX_EXT_B(CHIPS)':
 'DDR4_ACT_N': CDS_PINID='DDR4_ACT_N';
NODE_NAME     J1A2 62
 '@BASEBOARD_FAB2_LIB.BASEBOARD_FAB2(SCH_1):PAGE85_I111@MSTR_SCONN.SCONN288_H44441004(CHIPS)':
 'ACT_N': CDS_PINID='ACT_N';
NODE_NAME     J9L2 62
 '@BASEBOARD_FAB2_LIB.BASEBOARD_FAB2(SCH_1):PAGE86_I12@MSTR_SCONN.SCONN288_H44441003(CHIPS)':
 'ACT_N': CDS_PINID='ACT_N';
NET_NAME
'M_L_ALERT_N'
 '@BASEBOARD_FAB2_LIB.BASEBOARD_FAB2(SCH_1):M_L_ALERT_N':
 C_SIGNAL='@baseboard_fab2_lib.baseboard_fab2(sch_1):m_l_alert_n';
NODE_NAME     U2D1 DT61
 '@BASEBOARD_FAB2_LIB.BASEBOARD_FAB2(SCH_1):PAGE61_I172@CHPSET_LIB.SKX_EXT_B(CHIPS)':
 'DDR4_ALERT_N': CDS_PINID='DDR4_ALERT_N';
NODE_NAME     J1A2 208
 '@BASEBOARD_FAB2_LIB.BASEBOARD_FAB2(SCH_1):PAGE85_I111@MSTR_SCONN.SCONN288_H44441004(CHIPS)':
 'ALERT_N': CDS_PINID='ALERT_N';
NODE_NAME     J9L2 208
 '@BASEBOARD_FAB2_LIB.BASEBOARD_FAB2(SCH_1):PAGE86_I12@MSTR_SCONN.SCONN288_H44441003(CHIPS)':
 'ALERT_N': CDS_PINID='ALERT_N';
NET_NAME
'M_L_BA<0>'
 '@BASEBOARD_FAB2_LIB.BASEBOARD_FAB2(SCH_1):M_L_BA'<0>:
 C_SIGNAL='@baseboard_fab2_lib.baseboard_fab2(sch_1):m_l_ba(0)';
NODE_NAME     U2D1 DM53
 '@BASEBOARD_FAB2_LIB.BASEBOARD_FAB2(SCH_1):PAGE61_I172@CHPSET_LIB.SKX_EXT_B(CHIPS)':
 'DDR4_BA'<0>: CDS_PINID='DDR4_BA(0)';
NODE_NAME     J1A2 81
 '@BASEBOARD_FAB2_LIB.BASEBOARD_FAB2(SCH_1):PAGE85_I111@MSTR_SCONN.SCONN288_H44441004(CHIPS)':
 'BA'<0>: CDS_PINID='BA(0)';
NODE_NAME     J9L2 81
 '@BASEBOARD_FAB2_LIB.BASEBOARD_FAB2(SCH_1):PAGE86_I12@MSTR_SCONN.SCONN288_H44441003(CHIPS)':
 'BA'<0>: CDS_PINID='BA(0)';
NET_NAME
'M_L_BA<1>'
 '@BASEBOARD_FAB2_LIB.BASEBOARD_FAB2(SCH_1):M_L_BA'<1>:
 C_SIGNAL='@baseboard_fab2_lib.baseboard_fab2(sch_1):m_l_ba(1)';
NODE_NAME     U2D1 DV55
 '@BASEBOARD_FAB2_LIB.BASEBOARD_FAB2(SCH_1):PAGE61_I172@CHPSET_LIB.SKX_EXT_B(CHIPS)':
 'DDR4_BA'<1>: CDS_PINID='DDR4_BA(1)';
NODE_NAME     J1A2 224
 '@BASEBOARD_FAB2_LIB.BASEBOARD_FAB2(SCH_1):PAGE85_I111@MSTR_SCONN.SCONN288_H44441004(CHIPS)':
 'BA'<1>: CDS_PINID='BA(1)';
NODE_NAME     J9L2 224
 '@BASEBOARD_FAB2_LIB.BASEBOARD_FAB2(SCH_1):PAGE86_I12@MSTR_SCONN.SCONN288_H44441003(CHIPS)':
 'BA'<1>: CDS_PINID='BA(1)';
NET_NAME
'M_L_BG<0>'
 '@BASEBOARD_FAB2_LIB.BASEBOARD_FAB2(SCH_1):M_L_BG'<0>:
 C_SIGNAL='@baseboard_fab2_lib.baseboard_fab2(sch_1):m_l_bg(0)';
NODE_NAME     U2D1 DJ62
 '@BASEBOARD_FAB2_LIB.BASEBOARD_FAB2(SCH_1):PAGE61_I172@CHPSET_LIB.SKX_EXT_B(CHIPS)':
 'DDR4_BG'<0>: CDS_PINID='DDR4_BG(0)';
NODE_NAME     J1A2 63
 '@BASEBOARD_FAB2_LIB.BASEBOARD_FAB2(SCH_1):PAGE85_I111@MSTR_SCONN.SCONN288_H44441004(CHIPS)':
 'BG'<0>: CDS_PINID='BG(0)';
NODE_NAME     J9L2 63
 '@BASEBOARD_FAB2_LIB.BASEBOARD_FAB2(SCH_1):PAGE86_I12@MSTR_SCONN.SCONN288_H44441003(CHIPS)':
 'BG'<0>: CDS_PINID='BG(0)';
NET_NAME
'M_L_BG<1>'
 '@BASEBOARD_FAB2_LIB.BASEBOARD_FAB2(SCH_1):M_L_BG'<1>:
 C_SIGNAL='@baseboard_fab2_lib.baseboard_fab2(sch_1):m_l_bg(1)';
NODE_NAME     U2D1 DM61
 '@BASEBOARD_FAB2_LIB.BASEBOARD_FAB2(SCH_1):PAGE61_I172@CHPSET_LIB.SKX_EXT_B(CHIPS)':
 'DDR4_BG'<1>: CDS_PINID='DDR4_BG(1)';
NODE_NAME     J1A2 207
 '@BASEBOARD_FAB2_LIB.BASEBOARD_FAB2(SCH_1):PAGE85_I111@MSTR_SCONN.SCONN288_H44441004(CHIPS)':
 'BG'<1>: CDS_PINID='BG(1)';
NODE_NAME     J9L2 207
 '@BASEBOARD_FAB2_LIB.BASEBOARD_FAB2(SCH_1):PAGE86_I12@MSTR_SCONN.SCONN288_H44441003(CHIPS)':
 'BG'<1>: CDS_PINID='BG(1)';
NET_NAME
'M_L_C<2>'
 '@BASEBOARD_FAB2_LIB.BASEBOARD_FAB2(SCH_1):M_L_C'<2>:
 C_SIGNAL='@baseboard_fab2_lib.baseboard_fab2(sch_1):m_l_c(2)';
NODE_NAME     U2D1 DT47
 '@BASEBOARD_FAB2_LIB.BASEBOARD_FAB2(SCH_1):PAGE61_I172@CHPSET_LIB.SKX_EXT_B(CHIPS)':
 'DDR4_CID'<2>: CDS_PINID='DDR4_CID(2)';
NODE_NAME     J1A2 235
 '@BASEBOARD_FAB2_LIB.BASEBOARD_FAB2(SCH_1):PAGE85_I111@MSTR_SCONN.SCONN288_H44441004(CHIPS)':
 'C'<2>: CDS_PINID='C(2)';
NODE_NAME     J9L2 235
 '@BASEBOARD_FAB2_LIB.BASEBOARD_FAB2(SCH_1):PAGE86_I12@MSTR_SCONN.SCONN288_H44441003(CHIPS)':
 'C'<2>: CDS_PINID='C(2)';
NET_NAME
'M_L_CKE<0>'
 '@BASEBOARD_FAB2_LIB.BASEBOARD_FAB2(SCH_1):M_L_CKE'<0>:
 C_SIGNAL='@baseboard_fab2_lib.baseboard_fab2(sch_1):m_l_cke(0)';
NODE_NAME     U2D1 DM63
 '@BASEBOARD_FAB2_LIB.BASEBOARD_FAB2(SCH_1):PAGE61_I172@CHPSET_LIB.SKX_EXT_B(CHIPS)':
 'DDR4_CKE'<0>: CDS_PINID='DDR4_CKE(0)';
NODE_NAME     J1A2 60
 '@BASEBOARD_FAB2_LIB.BASEBOARD_FAB2(SCH_1):PAGE85_I111@MSTR_SCONN.SCONN288_H44441004(CHIPS)':
 'CKE'<0>: CDS_PINID='CKE(0)';
NET_NAME
'M_L_CKE<1>'
 '@BASEBOARD_FAB2_LIB.BASEBOARD_FAB2(SCH_1):M_L_CKE'<1>:
 C_SIGNAL='@baseboard_fab2_lib.baseboard_fab2(sch_1):m_l_cke(1)';
NODE_NAME     U2D1 DN64
 '@BASEBOARD_FAB2_LIB.BASEBOARD_FAB2(SCH_1):PAGE61_I172@CHPSET_LIB.SKX_EXT_B(CHIPS)':
 'DDR4_CKE'<1>: CDS_PINID='DDR4_CKE(1)';
NODE_NAME     J1A2 203
 '@BASEBOARD_FAB2_LIB.BASEBOARD_FAB2(SCH_1):PAGE85_I111@MSTR_SCONN.SCONN288_H44441004(CHIPS)':
 'CKE'<1>: CDS_PINID='CKE(1)';
NET_NAME
'M_L_CKE<2>'
 '@BASEBOARD_FAB2_LIB.BASEBOARD_FAB2(SCH_1):M_L_CKE'<2>:
 C_SIGNAL='@baseboard_fab2_lib.baseboard_fab2(sch_1):m_l_cke(2)';
NODE_NAME     U2D1 DL64
 '@BASEBOARD_FAB2_LIB.BASEBOARD_FAB2(SCH_1):PAGE61_I172@CHPSET_LIB.SKX_EXT_B(CHIPS)':
 'DDR4_CKE'<2>: CDS_PINID='DDR4_CKE(2)';
NODE_NAME     J9L2 60
 '@BASEBOARD_FAB2_LIB.BASEBOARD_FAB2(SCH_1):PAGE86_I12@MSTR_SCONN.SCONN288_H44441003(CHIPS)':
 'CKE'<0>: CDS_PINID='CKE(0)';
NET_NAME
'M_L_CKE<3>'
 '@BASEBOARD_FAB2_LIB.BASEBOARD_FAB2(SCH_1):M_L_CKE'<3>:
 C_SIGNAL='@baseboard_fab2_lib.baseboard_fab2(sch_1):m_l_cke(3)';
NODE_NAME     U2D1 DR64
 '@BASEBOARD_FAB2_LIB.BASEBOARD_FAB2(SCH_1):PAGE61_I172@CHPSET_LIB.SKX_EXT_B(CHIPS)':
 'DDR4_CKE'<3>: CDS_PINID='DDR4_CKE(3)';
NODE_NAME     J9L2 203
 '@BASEBOARD_FAB2_LIB.BASEBOARD_FAB2(SCH_1):PAGE86_I12@MSTR_SCONN.SCONN288_H44441003(CHIPS)':
 'CKE'<1>: CDS_PINID='CKE(1)';
NET_NAME
'M_L_CLK_DN<0>'
 '@BASEBOARD_FAB2_LIB.BASEBOARD_FAB2(SCH_1):M_L_CLK_DN'<0>:
 C_SIGNAL='@baseboard_fab2_lib.baseboard_fab2(sch_1):m_l_clk_dn(0)';
NODE_NAME     U2D1 DM55
 '@BASEBOARD_FAB2_LIB.BASEBOARD_FAB2(SCH_1):PAGE61_I172@CHPSET_LIB.SKX_EXT_B(CHIPS)':
 'DDR4_CLK_DN'<0>: CDS_PINID='DDR4_CLK_DN(0)';
NODE_NAME     J1A2 75
 '@BASEBOARD_FAB2_LIB.BASEBOARD_FAB2(SCH_1):PAGE85_I111@MSTR_SCONN.SCONN288_H44441004(CHIPS)':
 'CK0N': CDS_PINID='CK0N';
NET_NAME
'M_L_CLK_DN<1>'
 '@BASEBOARD_FAB2_LIB.BASEBOARD_FAB2(SCH_1):M_L_CLK_DN'<1>:
 C_SIGNAL='@baseboard_fab2_lib.baseboard_fab2(sch_1):m_l_clk_dn(1)';
NODE_NAME     U2D1 DR54
 '@BASEBOARD_FAB2_LIB.BASEBOARD_FAB2(SCH_1):PAGE61_I172@CHPSET_LIB.SKX_EXT_B(CHIPS)':
 'DDR4_CLK_DN'<1>: CDS_PINID='DDR4_CLK_DN(1)';
NODE_NAME     J1A2 219
 '@BASEBOARD_FAB2_LIB.BASEBOARD_FAB2(SCH_1):PAGE85_I111@MSTR_SCONN.SCONN288_H44441004(CHIPS)':
 'CK1N': CDS_PINID='CK1N';
NET_NAME
'M_L_CLK_DN<2>'
 '@BASEBOARD_FAB2_LIB.BASEBOARD_FAB2(SCH_1):M_L_CLK_DN'<2>:
 C_SIGNAL='@baseboard_fab2_lib.baseboard_fab2(sch_1):m_l_clk_dn(2)';
NODE_NAME     U2D1 DM57
 '@BASEBOARD_FAB2_LIB.BASEBOARD_FAB2(SCH_1):PAGE61_I172@CHPSET_LIB.SKX_EXT_B(CHIPS)':
 'DDR4_CLK_DN'<2>: CDS_PINID='DDR4_CLK_DN(2)';
NODE_NAME     J9L2 75
 '@BASEBOARD_FAB2_LIB.BASEBOARD_FAB2(SCH_1):PAGE86_I12@MSTR_SCONN.SCONN288_H44441003(CHIPS)':
 'CK0N': CDS_PINID='CK0N';
NET_NAME
'M_L_CLK_DN<3>'
 '@BASEBOARD_FAB2_LIB.BASEBOARD_FAB2(SCH_1):M_L_CLK_DN'<3>:
 C_SIGNAL='@baseboard_fab2_lib.baseboard_fab2(sch_1):m_l_clk_dn(3)';
NODE_NAME     U2D1 DT57
 '@BASEBOARD_FAB2_LIB.BASEBOARD_FAB2(SCH_1):PAGE61_I172@CHPSET_LIB.SKX_EXT_B(CHIPS)':
 'DDR4_CLK_DN'<3>: CDS_PINID='DDR4_CLK_DN(3)';
NODE_NAME     J9L2 219
 '@BASEBOARD_FAB2_LIB.BASEBOARD_FAB2(SCH_1):PAGE86_I12@MSTR_SCONN.SCONN288_H44441003(CHIPS)':
 'CK1N': CDS_PINID='CK1N';
NET_NAME
'M_L_CLK_DP<0>'
 '@BASEBOARD_FAB2_LIB.BASEBOARD_FAB2(SCH_1):M_L_CLK_DP'<0>:
 C_SIGNAL='@baseboard_fab2_lib.baseboard_fab2(sch_1):m_l_clk_dp(0)';
NODE_NAME     U2D1 DN54
 '@BASEBOARD_FAB2_LIB.BASEBOARD_FAB2(SCH_1):PAGE61_I172@CHPSET_LIB.SKX_EXT_B(CHIPS)':
 'DDR4_CLK_DP'<0>: CDS_PINID='DDR4_CLK_DP(0)';
NODE_NAME     J1A2 74
 '@BASEBOARD_FAB2_LIB.BASEBOARD_FAB2(SCH_1):PAGE85_I111@MSTR_SCONN.SCONN288_H44441004(CHIPS)':
 'CK0P': CDS_PINID='CK0P';
NET_NAME
'M_L_CLK_DP<1>'
 '@BASEBOARD_FAB2_LIB.BASEBOARD_FAB2(SCH_1):M_L_CLK_DP'<1>:
 C_SIGNAL='@baseboard_fab2_lib.baseboard_fab2(sch_1):m_l_clk_dp(1)';
NODE_NAME     U2D1 DT53
 '@BASEBOARD_FAB2_LIB.BASEBOARD_FAB2(SCH_1):PAGE61_I172@CHPSET_LIB.SKX_EXT_B(CHIPS)':
 'DDR4_CLK_DP'<1>: CDS_PINID='DDR4_CLK_DP(1)';
NODE_NAME     J1A2 218
 '@BASEBOARD_FAB2_LIB.BASEBOARD_FAB2(SCH_1):PAGE85_I111@MSTR_SCONN.SCONN288_H44441004(CHIPS)':
 'CK1P': CDS_PINID='CK1P';
NET_NAME
'M_L_CLK_DP<2>'
 '@BASEBOARD_FAB2_LIB.BASEBOARD_FAB2(SCH_1):M_L_CLK_DP'<2>:
 C_SIGNAL='@baseboard_fab2_lib.baseboard_fab2(sch_1):m_l_clk_dp(2)';
NODE_NAME     U2D1 DN56
 '@BASEBOARD_FAB2_LIB.BASEBOARD_FAB2(SCH_1):PAGE61_I172@CHPSET_LIB.SKX_EXT_B(CHIPS)':
 'DDR4_CLK_DP'<2>: CDS_PINID='DDR4_CLK_DP(2)';
NODE_NAME     J9L2 74
 '@BASEBOARD_FAB2_LIB.BASEBOARD_FAB2(SCH_1):PAGE86_I12@MSTR_SCONN.SCONN288_H44441003(CHIPS)':
 'CK0P': CDS_PINID='CK0P';
NET_NAME
'M_L_CLK_DP<3>'
 '@BASEBOARD_FAB2_LIB.BASEBOARD_FAB2(SCH_1):M_L_CLK_DP'<3>:
 C_SIGNAL='@baseboard_fab2_lib.baseboard_fab2(sch_1):m_l_clk_dp(3)';
NODE_NAME     U2D1 DR56
 '@BASEBOARD_FAB2_LIB.BASEBOARD_FAB2(SCH_1):PAGE61_I172@CHPSET_LIB.SKX_EXT_B(CHIPS)':
 'DDR4_CLK_DP'<3>: CDS_PINID='DDR4_CLK_DP(3)';
NODE_NAME     J9L2 218
 '@BASEBOARD_FAB2_LIB.BASEBOARD_FAB2(SCH_1):PAGE86_I12@MSTR_SCONN.SCONN288_H44441003(CHIPS)':
 'CK1P': CDS_PINID='CK1P';
NET_NAME
'M_L_CPU_VREF'
 '@BASEBOARD_FAB2_LIB.BASEBOARD_FAB2(SCH_1):M_L_CPU_VREF':
 C_SIGNAL='@baseboard_fab2_lib.baseboard_fab2(sch_1):m_l_cpu_vref';
NODE_NAME     U2D1 CT61
 '@BASEBOARD_FAB2_LIB.BASEBOARD_FAB2(SCH_1):PAGE55_I172@CHPSET_LIB.SKX_EXT_B(CHIPS)':
 'DDR4_CAVREF': CDS_PINID='DDR4_CAVREF';
NODE_NAME     R9L8 1
 '@BASEBOARD_FAB2_LIB.BASEBOARD_FAB2(SCH_1):PAGE100_I29@MSTR_DISCRETE.RES(CHIPS)':
 'A': CDS_PINID='A';
NODE_NAME     C9L8 1
 '@BASEBOARD_FAB2_LIB.BASEBOARD_FAB2(SCH_1):PAGE100_I30@DEV_DISCRETE.CAP_A(CHIPS)':
 'A': CDS_PINID='A';
NET_NAME
'M_L_CS_N<0>'
 '@BASEBOARD_FAB2_LIB.BASEBOARD_FAB2(SCH_1):M_L_CS_N'<0>:
 C_SIGNAL='@baseboard_fab2_lib.baseboard_fab2(sch_1):m_l_cs_n(0)';
NODE_NAME     U2D1 DV51
 '@BASEBOARD_FAB2_LIB.BASEBOARD_FAB2(SCH_1):PAGE61_I172@CHPSET_LIB.SKX_EXT_B(CHIPS)':
 'DDR4_CS_N'<0>: CDS_PINID='DDR4_CS_N(0)';
NODE_NAME     J1A2 84
 '@BASEBOARD_FAB2_LIB.BASEBOARD_FAB2(SCH_1):PAGE85_I111@MSTR_SCONN.SCONN288_H44441004(CHIPS)':
 'S0_N': CDS_PINID='S0_N';
NET_NAME
'M_L_CS_N<1>'
 '@BASEBOARD_FAB2_LIB.BASEBOARD_FAB2(SCH_1):M_L_CS_N'<1>:
 C_SIGNAL='@baseboard_fab2_lib.baseboard_fab2(sch_1):m_l_cs_n(1)';
NODE_NAME     U2D1 DN50
 '@BASEBOARD_FAB2_LIB.BASEBOARD_FAB2(SCH_1):PAGE61_I172@CHPSET_LIB.SKX_EXT_B(CHIPS)':
 'DDR4_CS_N'<1>: CDS_PINID='DDR4_CS_N(1)';
NODE_NAME     J1A2 89
 '@BASEBOARD_FAB2_LIB.BASEBOARD_FAB2(SCH_1):PAGE85_I111@MSTR_SCONN.SCONN288_H44441004(CHIPS)':
 'S1_N': CDS_PINID='S1_N';
NET_NAME
'M_L_CS_N<2>'
 '@BASEBOARD_FAB2_LIB.BASEBOARD_FAB2(SCH_1):M_L_CS_N'<2>:
 C_SIGNAL='@baseboard_fab2_lib.baseboard_fab2(sch_1):m_l_cs_n(2)';
NODE_NAME     U2D1 DR46
 '@BASEBOARD_FAB2_LIB.BASEBOARD_FAB2(SCH_1):PAGE61_I172@CHPSET_LIB.SKX_EXT_B(CHIPS)':
 'DDR4_CS_N'<2>: CDS_PINID='DDR4_CS_N(2)';
NODE_NAME     J1A2 93
 '@BASEBOARD_FAB2_LIB.BASEBOARD_FAB2(SCH_1):PAGE85_I111@MSTR_SCONN.SCONN288_H44441004(CHIPS)':
 'S2_N_C'<0>: CDS_PINID='S2_N_C(0)';
NET_NAME
'M_L_CS_N<3>'
 '@BASEBOARD_FAB2_LIB.BASEBOARD_FAB2(SCH_1):M_L_CS_N'<3>:
 C_SIGNAL='@baseboard_fab2_lib.baseboard_fab2(sch_1):m_l_cs_n(3)';
NODE_NAME     U2D1 DK47
 '@BASEBOARD_FAB2_LIB.BASEBOARD_FAB2(SCH_1):PAGE61_I172@CHPSET_LIB.SKX_EXT_B(CHIPS)':
 'DDR4_CS_N'<3>: CDS_PINID='DDR4_CS_N(3)';
NODE_NAME     J1A2 237
 '@BASEBOARD_FAB2_LIB.BASEBOARD_FAB2(SCH_1):PAGE85_I111@MSTR_SCONN.SCONN288_H44441004(CHIPS)':
 'S3_N_C'<1>: CDS_PINID='S3_N_C(1)';
NET_NAME
'M_L_CS_N<4>'
 '@BASEBOARD_FAB2_LIB.BASEBOARD_FAB2(SCH_1):M_L_CS_N'<4>:
 C_SIGNAL='@baseboard_fab2_lib.baseboard_fab2(sch_1):m_l_cs_n(4)';
NODE_NAME     U2D1 DW50
 '@BASEBOARD_FAB2_LIB.BASEBOARD_FAB2(SCH_1):PAGE61_I172@CHPSET_LIB.SKX_EXT_B(CHIPS)':
 'DDR4_CS_N'<4>: CDS_PINID='DDR4_CS_N(4)';
NODE_NAME     J9L2 84
 '@BASEBOARD_FAB2_LIB.BASEBOARD_FAB2(SCH_1):PAGE86_I12@MSTR_SCONN.SCONN288_H44441003(CHIPS)':
 'S0_N': CDS_PINID='S0_N';
NET_NAME
'M_L_CS_N<5>'
 '@BASEBOARD_FAB2_LIB.BASEBOARD_FAB2(SCH_1):M_L_CS_N'<5>:
 C_SIGNAL='@baseboard_fab2_lib.baseboard_fab2(sch_1):m_l_cs_n(5)';
NODE_NAME     U2D1 DM49
 '@BASEBOARD_FAB2_LIB.BASEBOARD_FAB2(SCH_1):PAGE61_I172@CHPSET_LIB.SKX_EXT_B(CHIPS)':
 'DDR4_CS_N'<5>: CDS_PINID='DDR4_CS_N(5)';
NODE_NAME     J9L2 89
 '@BASEBOARD_FAB2_LIB.BASEBOARD_FAB2(SCH_1):PAGE86_I12@MSTR_SCONN.SCONN288_H44441003(CHIPS)':
 'S1_N': CDS_PINID='S1_N';
NET_NAME
'M_L_CS_N<6>'
 '@BASEBOARD_FAB2_LIB.BASEBOARD_FAB2(SCH_1):M_L_CS_N'<6>:
 C_SIGNAL='@baseboard_fab2_lib.baseboard_fab2(sch_1):m_l_cs_n(6)';
NODE_NAME     U2D1 DT45
 '@BASEBOARD_FAB2_LIB.BASEBOARD_FAB2(SCH_1):PAGE61_I172@CHPSET_LIB.SKX_EXT_B(CHIPS)':
 'DDR4_CS_N'<6>: CDS_PINID='DDR4_CS_N(6)';
NODE_NAME     J9L2 93
 '@BASEBOARD_FAB2_LIB.BASEBOARD_FAB2(SCH_1):PAGE86_I12@MSTR_SCONN.SCONN288_H44441003(CHIPS)':
 'S2_N_C'<0>: CDS_PINID='S2_N_C(0)';
NET_NAME
'M_L_CS_N<7>'
 '@BASEBOARD_FAB2_LIB.BASEBOARD_FAB2(SCH_1):M_L_CS_N'<7>:
 C_SIGNAL='@baseboard_fab2_lib.baseboard_fab2(sch_1):m_l_cs_n(7)';
NODE_NAME     U2D1 DN46
 '@BASEBOARD_FAB2_LIB.BASEBOARD_FAB2(SCH_1):PAGE61_I172@CHPSET_LIB.SKX_EXT_B(CHIPS)':
 'DDR4_CS_N'<7>: CDS_PINID='DDR4_CS_N(7)';
NODE_NAME     J9L2 237
 '@BASEBOARD_FAB2_LIB.BASEBOARD_FAB2(SCH_1):PAGE86_I12@MSTR_SCONN.SCONN288_H44441003(CHIPS)':
 'S3_N_C'<1>: CDS_PINID='S3_N_C(1)';
NET_NAME
'M_L_DQ<0>'
 '@BASEBOARD_FAB2_LIB.BASEBOARD_FAB2(SCH_1):M_L_DQ'<0>:
 C_SIGNAL='@baseboard_fab2_lib.baseboard_fab2(sch_1):m_l_dq(0)';
NODE_NAME     U2D1 CM79
 '@BASEBOARD_FAB2_LIB.BASEBOARD_FAB2(SCH_1):PAGE61_I172@CHPSET_LIB.SKX_EXT_B(CHIPS)':
 'DDR4_DQ'<0>: CDS_PINID='DDR4_DQ(0)';
NODE_NAME     J1A2 150
 '@BASEBOARD_FAB2_LIB.BASEBOARD_FAB2(SCH_1):PAGE85_I111@MSTR_SCONN.SCONN288_H44441004(CHIPS)':
 'DQ'<1>: CDS_PINID='DQ(1)';
NODE_NAME     J9L2 5
 '@BASEBOARD_FAB2_LIB.BASEBOARD_FAB2(SCH_1):PAGE86_I12@MSTR_SCONN.SCONN288_H44441003(CHIPS)':
 'DQ'<0>: CDS_PINID='DQ(0)';
NET_NAME
'M_L_DQ<10>'
 '@BASEBOARD_FAB2_LIB.BASEBOARD_FAB2(SCH_1):M_L_DQ'<10>:
 C_SIGNAL='@baseboard_fab2_lib.baseboard_fab2(sch_1):m_l_dq(10)';
NODE_NAME     U2D1 DE80
 '@BASEBOARD_FAB2_LIB.BASEBOARD_FAB2(SCH_1):PAGE61_I172@CHPSET_LIB.SKX_EXT_B(CHIPS)':
 'DDR4_DQ'<10>: CDS_PINID='DDR4_DQ(10)';
NODE_NAME     J1A2 168
 '@BASEBOARD_FAB2_LIB.BASEBOARD_FAB2(SCH_1):PAGE85_I111@MSTR_SCONN.SCONN288_H44441004(CHIPS)':
 'DQ'<11>: CDS_PINID='DQ(11)';
NODE_NAME     J9L2 23
 '@BASEBOARD_FAB2_LIB.BASEBOARD_FAB2(SCH_1):PAGE86_I12@MSTR_SCONN.SCONN288_H44441003(CHIPS)':
 'DQ'<10>: CDS_PINID='DQ(10)';
NET_NAME
'M_L_DQ<11>'
 '@BASEBOARD_FAB2_LIB.BASEBOARD_FAB2(SCH_1):M_L_DQ'<11>:
 C_SIGNAL='@baseboard_fab2_lib.baseboard_fab2(sch_1):m_l_dq(11)';
NODE_NAME     U2D1 DF81
 '@BASEBOARD_FAB2_LIB.BASEBOARD_FAB2(SCH_1):PAGE61_I172@CHPSET_LIB.SKX_EXT_B(CHIPS)':
 'DDR4_DQ'<11>: CDS_PINID='DDR4_DQ(11)';
NODE_NAME     J1A2 23
 '@BASEBOARD_FAB2_LIB.BASEBOARD_FAB2(SCH_1):PAGE85_I111@MSTR_SCONN.SCONN288_H44441004(CHIPS)':
 'DQ'<10>: CDS_PINID='DQ(10)';
NODE_NAME     J9L2 168
 '@BASEBOARD_FAB2_LIB.BASEBOARD_FAB2(SCH_1):PAGE86_I12@MSTR_SCONN.SCONN288_H44441003(CHIPS)':
 'DQ'<11>: CDS_PINID='DQ(11)';
NET_NAME
'M_L_DQ<12>'
 '@BASEBOARD_FAB2_LIB.BASEBOARD_FAB2(SCH_1):M_L_DQ'<12>:
 C_SIGNAL='@baseboard_fab2_lib.baseboard_fab2(sch_1):m_l_dq(12)';
NODE_NAME     U2D1 CY79
 '@BASEBOARD_FAB2_LIB.BASEBOARD_FAB2(SCH_1):PAGE61_I172@CHPSET_LIB.SKX_EXT_B(CHIPS)':
 'DDR4_DQ'<12>: CDS_PINID='DDR4_DQ(12)';
NODE_NAME     J1A2 159
 '@BASEBOARD_FAB2_LIB.BASEBOARD_FAB2(SCH_1):PAGE85_I111@MSTR_SCONN.SCONN288_H44441004(CHIPS)':
 'DQ'<13>: CDS_PINID='DQ(13)';
NODE_NAME     J9L2 14
 '@BASEBOARD_FAB2_LIB.BASEBOARD_FAB2(SCH_1):PAGE86_I12@MSTR_SCONN.SCONN288_H44441003(CHIPS)':
 'DQ'<12>: CDS_PINID='DQ(12)';
NET_NAME
'M_L_DQ<13>'
 '@BASEBOARD_FAB2_LIB.BASEBOARD_FAB2(SCH_1):M_L_DQ'<13>:
 C_SIGNAL='@baseboard_fab2_lib.baseboard_fab2(sch_1):m_l_dq(13)';
NODE_NAME     U2D1 CW80
 '@BASEBOARD_FAB2_LIB.BASEBOARD_FAB2(SCH_1):PAGE61_I172@CHPSET_LIB.SKX_EXT_B(CHIPS)':
 'DDR4_DQ'<13>: CDS_PINID='DDR4_DQ(13)';
NODE_NAME     J1A2 14
 '@BASEBOARD_FAB2_LIB.BASEBOARD_FAB2(SCH_1):PAGE85_I111@MSTR_SCONN.SCONN288_H44441004(CHIPS)':
 'DQ'<12>: CDS_PINID='DQ(12)';
NODE_NAME     J9L2 159
 '@BASEBOARD_FAB2_LIB.BASEBOARD_FAB2(SCH_1):PAGE86_I12@MSTR_SCONN.SCONN288_H44441003(CHIPS)':
 'DQ'<13>: CDS_PINID='DQ(13)';
NET_NAME
'M_L_DQ<14>'
 '@BASEBOARD_FAB2_LIB.BASEBOARD_FAB2(SCH_1):M_L_DQ'<14>:
 C_SIGNAL='@baseboard_fab2_lib.baseboard_fab2(sch_1):m_l_dq(14)';
NODE_NAME     U2D1 DC82
 '@BASEBOARD_FAB2_LIB.BASEBOARD_FAB2(SCH_1):PAGE61_I172@CHPSET_LIB.SKX_EXT_B(CHIPS)':
 'DDR4_DQ'<14>: CDS_PINID='DDR4_DQ(14)';
NODE_NAME     J1A2 166
 '@BASEBOARD_FAB2_LIB.BASEBOARD_FAB2(SCH_1):PAGE85_I111@MSTR_SCONN.SCONN288_H44441004(CHIPS)':
 'DQ'<15>: CDS_PINID='DQ(15)';
NODE_NAME     J9L2 21
 '@BASEBOARD_FAB2_LIB.BASEBOARD_FAB2(SCH_1):PAGE86_I12@MSTR_SCONN.SCONN288_H44441003(CHIPS)':
 'DQ'<14>: CDS_PINID='DQ(14)';
NET_NAME
'M_L_DQ<15>'
 '@BASEBOARD_FAB2_LIB.BASEBOARD_FAB2(SCH_1):M_L_DQ'<15>:
 C_SIGNAL='@baseboard_fab2_lib.baseboard_fab2(sch_1):m_l_dq(15)';
NODE_NAME     U2D1 DE82
 '@BASEBOARD_FAB2_LIB.BASEBOARD_FAB2(SCH_1):PAGE61_I172@CHPSET_LIB.SKX_EXT_B(CHIPS)':
 'DDR4_DQ'<15>: CDS_PINID='DDR4_DQ(15)';
NODE_NAME     J1A2 21
 '@BASEBOARD_FAB2_LIB.BASEBOARD_FAB2(SCH_1):PAGE85_I111@MSTR_SCONN.SCONN288_H44441004(CHIPS)':
 'DQ'<14>: CDS_PINID='DQ(14)';
NODE_NAME     J9L2 166
 '@BASEBOARD_FAB2_LIB.BASEBOARD_FAB2(SCH_1):PAGE86_I12@MSTR_SCONN.SCONN288_H44441003(CHIPS)':
 'DQ'<15>: CDS_PINID='DQ(15)';
NET_NAME
'M_L_DQ<16>'
 '@BASEBOARD_FAB2_LIB.BASEBOARD_FAB2(SCH_1):M_L_DQ'<16>:
 C_SIGNAL='@baseboard_fab2_lib.baseboard_fab2(sch_1):m_l_dq(16)';
NODE_NAME     U2D1 DW80
 '@BASEBOARD_FAB2_LIB.BASEBOARD_FAB2(SCH_1):PAGE61_I172@CHPSET_LIB.SKX_EXT_B(CHIPS)':
 'DDR4_DQ'<16>: CDS_PINID='DDR4_DQ(16)';
NODE_NAME     J1A2 172
 '@BASEBOARD_FAB2_LIB.BASEBOARD_FAB2(SCH_1):PAGE85_I111@MSTR_SCONN.SCONN288_H44441004(CHIPS)':
 'DQ'<17>: CDS_PINID='DQ(17)';
NODE_NAME     J9L2 27
 '@BASEBOARD_FAB2_LIB.BASEBOARD_FAB2(SCH_1):PAGE86_I12@MSTR_SCONN.SCONN288_H44441003(CHIPS)':
 'DQ'<16>: CDS_PINID='DQ(16)';
NET_NAME
'M_L_DQ<17>'
 '@BASEBOARD_FAB2_LIB.BASEBOARD_FAB2(SCH_1):M_L_DQ'<17>:
 C_SIGNAL='@baseboard_fab2_lib.baseboard_fab2(sch_1):m_l_dq(17)';
NODE_NAME     U2D1 EC80
 '@BASEBOARD_FAB2_LIB.BASEBOARD_FAB2(SCH_1):PAGE61_I172@CHPSET_LIB.SKX_EXT_B(CHIPS)':
 'DDR4_DQ'<17>: CDS_PINID='DDR4_DQ(17)';
NODE_NAME     J1A2 27
 '@BASEBOARD_FAB2_LIB.BASEBOARD_FAB2(SCH_1):PAGE85_I111@MSTR_SCONN.SCONN288_H44441004(CHIPS)':
 'DQ'<16>: CDS_PINID='DQ(16)';
NODE_NAME     J9L2 172
 '@BASEBOARD_FAB2_LIB.BASEBOARD_FAB2(SCH_1):PAGE86_I12@MSTR_SCONN.SCONN288_H44441003(CHIPS)':
 'DQ'<17>: CDS_PINID='DQ(17)';
NET_NAME
'M_L_DQ<18>'
 '@BASEBOARD_FAB2_LIB.BASEBOARD_FAB2(SCH_1):M_L_DQ'<18>:
 C_SIGNAL='@baseboard_fab2_lib.baseboard_fab2(sch_1):m_l_dq(18)';
NODE_NAME     U2D1 DY77
 '@BASEBOARD_FAB2_LIB.BASEBOARD_FAB2(SCH_1):PAGE61_I172@CHPSET_LIB.SKX_EXT_B(CHIPS)':
 'DDR4_DQ'<18>: CDS_PINID='DDR4_DQ(18)';
NODE_NAME     J1A2 179
 '@BASEBOARD_FAB2_LIB.BASEBOARD_FAB2(SCH_1):PAGE85_I111@MSTR_SCONN.SCONN288_H44441004(CHIPS)':
 'DQ'<19>: CDS_PINID='DQ(19)';
NODE_NAME     J9L2 34
 '@BASEBOARD_FAB2_LIB.BASEBOARD_FAB2(SCH_1):PAGE86_I12@MSTR_SCONN.SCONN288_H44441003(CHIPS)':
 'DQ'<18>: CDS_PINID='DQ(18)';
NET_NAME
'M_L_DQ<19>'
 '@BASEBOARD_FAB2_LIB.BASEBOARD_FAB2(SCH_1):M_L_DQ'<19>:
 C_SIGNAL='@baseboard_fab2_lib.baseboard_fab2(sch_1):m_l_dq(19)';
NODE_NAME     U2D1 EB77
 '@BASEBOARD_FAB2_LIB.BASEBOARD_FAB2(SCH_1):PAGE61_I172@CHPSET_LIB.SKX_EXT_B(CHIPS)':
 'DDR4_DQ'<19>: CDS_PINID='DDR4_DQ(19)';
NODE_NAME     J1A2 34
 '@BASEBOARD_FAB2_LIB.BASEBOARD_FAB2(SCH_1):PAGE85_I111@MSTR_SCONN.SCONN288_H44441004(CHIPS)':
 'DQ'<18>: CDS_PINID='DQ(18)';
NODE_NAME     J9L2 179
 '@BASEBOARD_FAB2_LIB.BASEBOARD_FAB2(SCH_1):PAGE86_I12@MSTR_SCONN.SCONN288_H44441003(CHIPS)':
 'DQ'<19>: CDS_PINID='DQ(19)';
NET_NAME
'M_L_DQ<1>'
 '@BASEBOARD_FAB2_LIB.BASEBOARD_FAB2(SCH_1):M_L_DQ'<1>:
 C_SIGNAL='@baseboard_fab2_lib.baseboard_fab2(sch_1):m_l_dq(1)';
NODE_NAME     U2D1 CK81
 '@BASEBOARD_FAB2_LIB.BASEBOARD_FAB2(SCH_1):PAGE61_I172@CHPSET_LIB.SKX_EXT_B(CHIPS)':
 'DDR4_DQ'<1>: CDS_PINID='DDR4_DQ(1)';
NODE_NAME     J1A2 5
 '@BASEBOARD_FAB2_LIB.BASEBOARD_FAB2(SCH_1):PAGE85_I111@MSTR_SCONN.SCONN288_H44441004(CHIPS)':
 'DQ'<0>: CDS_PINID='DQ(0)';
NODE_NAME     J9L2 150
 '@BASEBOARD_FAB2_LIB.BASEBOARD_FAB2(SCH_1):PAGE86_I12@MSTR_SCONN.SCONN288_H44441003(CHIPS)':
 'DQ'<1>: CDS_PINID='DQ(1)';
NET_NAME
'M_L_DQ<20>'
 '@BASEBOARD_FAB2_LIB.BASEBOARD_FAB2(SCH_1):M_L_DQ'<20>:
 C_SIGNAL='@baseboard_fab2_lib.baseboard_fab2(sch_1):m_l_dq(20)';
NODE_NAME     U2D1 DY81
 '@BASEBOARD_FAB2_LIB.BASEBOARD_FAB2(SCH_1):PAGE61_I172@CHPSET_LIB.SKX_EXT_B(CHIPS)':
 'DDR4_DQ'<20>: CDS_PINID='DDR4_DQ(20)';
NODE_NAME     J1A2 170
 '@BASEBOARD_FAB2_LIB.BASEBOARD_FAB2(SCH_1):PAGE85_I111@MSTR_SCONN.SCONN288_H44441004(CHIPS)':
 'DQ'<21>: CDS_PINID='DQ(21)';
NODE_NAME     J9L2 25
 '@BASEBOARD_FAB2_LIB.BASEBOARD_FAB2(SCH_1):PAGE86_I12@MSTR_SCONN.SCONN288_H44441003(CHIPS)':
 'DQ'<20>: CDS_PINID='DQ(20)';
NET_NAME
'M_L_DQ<21>'
 '@BASEBOARD_FAB2_LIB.BASEBOARD_FAB2(SCH_1):M_L_DQ'<21>:
 C_SIGNAL='@baseboard_fab2_lib.baseboard_fab2(sch_1):m_l_dq(21)';
NODE_NAME     U2D1 EB81
 '@BASEBOARD_FAB2_LIB.BASEBOARD_FAB2(SCH_1):PAGE61_I172@CHPSET_LIB.SKX_EXT_B(CHIPS)':
 'DDR4_DQ'<21>: CDS_PINID='DDR4_DQ(21)';
NODE_NAME     J1A2 25
 '@BASEBOARD_FAB2_LIB.BASEBOARD_FAB2(SCH_1):PAGE85_I111@MSTR_SCONN.SCONN288_H44441004(CHIPS)':
 'DQ'<20>: CDS_PINID='DQ(20)';
NODE_NAME     J9L2 170
 '@BASEBOARD_FAB2_LIB.BASEBOARD_FAB2(SCH_1):PAGE86_I12@MSTR_SCONN.SCONN288_H44441003(CHIPS)':
 'DQ'<21>: CDS_PINID='DQ(21)';
NET_NAME
'M_L_DQ<22>'
 '@BASEBOARD_FAB2_LIB.BASEBOARD_FAB2(SCH_1):M_L_DQ'<22>:
 C_SIGNAL='@baseboard_fab2_lib.baseboard_fab2(sch_1):m_l_dq(22)';
NODE_NAME     U2D1 DW78
 '@BASEBOARD_FAB2_LIB.BASEBOARD_FAB2(SCH_1):PAGE61_I172@CHPSET_LIB.SKX_EXT_B(CHIPS)':
 'DDR4_DQ'<22>: CDS_PINID='DDR4_DQ(22)';
NODE_NAME     J1A2 177
 '@BASEBOARD_FAB2_LIB.BASEBOARD_FAB2(SCH_1):PAGE85_I111@MSTR_SCONN.SCONN288_H44441004(CHIPS)':
 'DQ'<23>: CDS_PINID='DQ(23)';
NODE_NAME     J9L2 32
 '@BASEBOARD_FAB2_LIB.BASEBOARD_FAB2(SCH_1):PAGE86_I12@MSTR_SCONN.SCONN288_H44441003(CHIPS)':
 'DQ'<22>: CDS_PINID='DQ(22)';
NET_NAME
'M_L_DQ<23>'
 '@BASEBOARD_FAB2_LIB.BASEBOARD_FAB2(SCH_1):M_L_DQ'<23>:
 C_SIGNAL='@baseboard_fab2_lib.baseboard_fab2(sch_1):m_l_dq(23)';
NODE_NAME     U2D1 EC78
 '@BASEBOARD_FAB2_LIB.BASEBOARD_FAB2(SCH_1):PAGE61_I172@CHPSET_LIB.SKX_EXT_B(CHIPS)':
 'DDR4_DQ'<23>: CDS_PINID='DDR4_DQ(23)';
NODE_NAME     J1A2 32
 '@BASEBOARD_FAB2_LIB.BASEBOARD_FAB2(SCH_1):PAGE85_I111@MSTR_SCONN.SCONN288_H44441004(CHIPS)':
 'DQ'<22>: CDS_PINID='DQ(22)';
NODE_NAME     J9L2 177
 '@BASEBOARD_FAB2_LIB.BASEBOARD_FAB2(SCH_1):PAGE86_I12@MSTR_SCONN.SCONN288_H44441003(CHIPS)':
 'DQ'<23>: CDS_PINID='DQ(23)';
NET_NAME
'M_L_DQ<24>'
 '@BASEBOARD_FAB2_LIB.BASEBOARD_FAB2(SCH_1):M_L_DQ'<24>:
 C_SIGNAL='@baseboard_fab2_lib.baseboard_fab2(sch_1):m_l_dq(24)';
NODE_NAME     U2D1 ED75
 '@BASEBOARD_FAB2_LIB.BASEBOARD_FAB2(SCH_1):PAGE61_I172@CHPSET_LIB.SKX_EXT_B(CHIPS)':
 'DDR4_DQ'<24>: CDS_PINID='DDR4_DQ(24)';
NODE_NAME     J1A2 183
 '@BASEBOARD_FAB2_LIB.BASEBOARD_FAB2(SCH_1):PAGE85_I111@MSTR_SCONN.SCONN288_H44441004(CHIPS)':
 'DQ'<25>: CDS_PINID='DQ(25)';
NODE_NAME     J9L2 38
 '@BASEBOARD_FAB2_LIB.BASEBOARD_FAB2(SCH_1):PAGE86_I12@MSTR_SCONN.SCONN288_H44441003(CHIPS)':
 'DQ'<24>: CDS_PINID='DQ(24)';
NET_NAME
'M_L_DQ<25>'
 '@BASEBOARD_FAB2_LIB.BASEBOARD_FAB2(SCH_1):M_L_DQ'<25>:
 C_SIGNAL='@baseboard_fab2_lib.baseboard_fab2(sch_1):m_l_dq(25)';
NODE_NAME     U2D1 EE74
 '@BASEBOARD_FAB2_LIB.BASEBOARD_FAB2(SCH_1):PAGE61_I172@CHPSET_LIB.SKX_EXT_B(CHIPS)':
 'DDR4_DQ'<25>: CDS_PINID='DDR4_DQ(25)';
NODE_NAME     J1A2 38
 '@BASEBOARD_FAB2_LIB.BASEBOARD_FAB2(SCH_1):PAGE85_I111@MSTR_SCONN.SCONN288_H44441004(CHIPS)':
 'DQ'<24>: CDS_PINID='DQ(24)';
NODE_NAME     J9L2 183
 '@BASEBOARD_FAB2_LIB.BASEBOARD_FAB2(SCH_1):PAGE86_I12@MSTR_SCONN.SCONN288_H44441003(CHIPS)':
 'DQ'<25>: CDS_PINID='DQ(25)';
NET_NAME
'M_L_DQ<26>'
 '@BASEBOARD_FAB2_LIB.BASEBOARD_FAB2(SCH_1):M_L_DQ'<26>:
 C_SIGNAL='@baseboard_fab2_lib.baseboard_fab2(sch_1):m_l_dq(26)';
NODE_NAME     U2D1 EB71
 '@BASEBOARD_FAB2_LIB.BASEBOARD_FAB2(SCH_1):PAGE61_I172@CHPSET_LIB.SKX_EXT_B(CHIPS)':
 'DDR4_DQ'<26>: CDS_PINID='DDR4_DQ(26)';
NODE_NAME     J1A2 190
 '@BASEBOARD_FAB2_LIB.BASEBOARD_FAB2(SCH_1):PAGE85_I111@MSTR_SCONN.SCONN288_H44441004(CHIPS)':
 'DQ'<27>: CDS_PINID='DQ(27)';
NODE_NAME     J9L2 45
 '@BASEBOARD_FAB2_LIB.BASEBOARD_FAB2(SCH_1):PAGE86_I12@MSTR_SCONN.SCONN288_H44441003(CHIPS)':
 'DQ'<26>: CDS_PINID='DQ(26)';
NET_NAME
'M_L_DQ<27>'
 '@BASEBOARD_FAB2_LIB.BASEBOARD_FAB2(SCH_1):M_L_DQ'<27>:
 C_SIGNAL='@baseboard_fab2_lib.baseboard_fab2(sch_1):m_l_dq(27)';
NODE_NAME     U2D1 ED71
 '@BASEBOARD_FAB2_LIB.BASEBOARD_FAB2(SCH_1):PAGE61_I172@CHPSET_LIB.SKX_EXT_B(CHIPS)':
 'DDR4_DQ'<27>: CDS_PINID='DDR4_DQ(27)';
NODE_NAME     J1A2 45
 '@BASEBOARD_FAB2_LIB.BASEBOARD_FAB2(SCH_1):PAGE85_I111@MSTR_SCONN.SCONN288_H44441004(CHIPS)':
 'DQ'<26>: CDS_PINID='DQ(26)';
NODE_NAME     J9L2 190
 '@BASEBOARD_FAB2_LIB.BASEBOARD_FAB2(SCH_1):PAGE86_I12@MSTR_SCONN.SCONN288_H44441003(CHIPS)':
 'DQ'<27>: CDS_PINID='DQ(27)';
NET_NAME
'M_L_DQ<28>'
 '@BASEBOARD_FAB2_LIB.BASEBOARD_FAB2(SCH_1):M_L_DQ'<28>:
 C_SIGNAL='@baseboard_fab2_lib.baseboard_fab2(sch_1):m_l_dq(28)';
NODE_NAME     U2D1 EA74
 '@BASEBOARD_FAB2_LIB.BASEBOARD_FAB2(SCH_1):PAGE61_I172@CHPSET_LIB.SKX_EXT_B(CHIPS)':
 'DDR4_DQ'<28>: CDS_PINID='DDR4_DQ(28)';
NODE_NAME     J1A2 181
 '@BASEBOARD_FAB2_LIB.BASEBOARD_FAB2(SCH_1):PAGE85_I111@MSTR_SCONN.SCONN288_H44441004(CHIPS)':
 'DQ'<29>: CDS_PINID='DQ(29)';
NODE_NAME     J9L2 36
 '@BASEBOARD_FAB2_LIB.BASEBOARD_FAB2(SCH_1):PAGE86_I12@MSTR_SCONN.SCONN288_H44441003(CHIPS)':
 'DQ'<28>: CDS_PINID='DQ(28)';
NET_NAME
'M_L_DQ<29>'
 '@BASEBOARD_FAB2_LIB.BASEBOARD_FAB2(SCH_1):M_L_DQ'<29>:
 C_SIGNAL='@baseboard_fab2_lib.baseboard_fab2(sch_1):m_l_dq(29)';
NODE_NAME     U2D1 EB75
 '@BASEBOARD_FAB2_LIB.BASEBOARD_FAB2(SCH_1):PAGE61_I172@CHPSET_LIB.SKX_EXT_B(CHIPS)':
 'DDR4_DQ'<29>: CDS_PINID='DDR4_DQ(29)';
NODE_NAME     J1A2 36
 '@BASEBOARD_FAB2_LIB.BASEBOARD_FAB2(SCH_1):PAGE85_I111@MSTR_SCONN.SCONN288_H44441004(CHIPS)':
 'DQ'<28>: CDS_PINID='DQ(28)';
NODE_NAME     J9L2 181
 '@BASEBOARD_FAB2_LIB.BASEBOARD_FAB2(SCH_1):PAGE86_I12@MSTR_SCONN.SCONN288_H44441003(CHIPS)':
 'DQ'<29>: CDS_PINID='DQ(29)';
NET_NAME
'M_L_DQ<2>'
 '@BASEBOARD_FAB2_LIB.BASEBOARD_FAB2(SCH_1):M_L_DQ'<2>:
 C_SIGNAL='@baseboard_fab2_lib.baseboard_fab2(sch_1):m_l_dq(2)';
NODE_NAME     U2D1 CT81
 '@BASEBOARD_FAB2_LIB.BASEBOARD_FAB2(SCH_1):PAGE61_I172@CHPSET_LIB.SKX_EXT_B(CHIPS)':
 'DDR4_DQ'<2>: CDS_PINID='DDR4_DQ(2)';
NODE_NAME     J1A2 157
 '@BASEBOARD_FAB2_LIB.BASEBOARD_FAB2(SCH_1):PAGE85_I111@MSTR_SCONN.SCONN288_H44441004(CHIPS)':
 'DQ'<3>: CDS_PINID='DQ(3)';
NODE_NAME     J9L2 12
 '@BASEBOARD_FAB2_LIB.BASEBOARD_FAB2(SCH_1):PAGE86_I12@MSTR_SCONN.SCONN288_H44441003(CHIPS)':
 'DQ'<2>: CDS_PINID='DQ(2)';
NET_NAME
'M_L_DQ<30>'
 '@BASEBOARD_FAB2_LIB.BASEBOARD_FAB2(SCH_1):M_L_DQ'<30>:
 C_SIGNAL='@baseboard_fab2_lib.baseboard_fab2(sch_1):m_l_dq(30)';
NODE_NAME     U2D1 EA72
 '@BASEBOARD_FAB2_LIB.BASEBOARD_FAB2(SCH_1):PAGE61_I172@CHPSET_LIB.SKX_EXT_B(CHIPS)':
 'DDR4_DQ'<30>: CDS_PINID='DDR4_DQ(30)';
NODE_NAME     J1A2 188
 '@BASEBOARD_FAB2_LIB.BASEBOARD_FAB2(SCH_1):PAGE85_I111@MSTR_SCONN.SCONN288_H44441004(CHIPS)':
 'DQ'<31>: CDS_PINID='DQ(31)';
NODE_NAME     J9L2 43
 '@BASEBOARD_FAB2_LIB.BASEBOARD_FAB2(SCH_1):PAGE86_I12@MSTR_SCONN.SCONN288_H44441003(CHIPS)':
 'DQ'<30>: CDS_PINID='DQ(30)';
NET_NAME
'M_L_DQ<31>'
 '@BASEBOARD_FAB2_LIB.BASEBOARD_FAB2(SCH_1):M_L_DQ'<31>:
 C_SIGNAL='@baseboard_fab2_lib.baseboard_fab2(sch_1):m_l_dq(31)';
NODE_NAME     U2D1 EE72
 '@BASEBOARD_FAB2_LIB.BASEBOARD_FAB2(SCH_1):PAGE61_I172@CHPSET_LIB.SKX_EXT_B(CHIPS)':
 'DDR4_DQ'<31>: CDS_PINID='DDR4_DQ(31)';
NODE_NAME     J1A2 43
 '@BASEBOARD_FAB2_LIB.BASEBOARD_FAB2(SCH_1):PAGE85_I111@MSTR_SCONN.SCONN288_H44441004(CHIPS)':
 'DQ'<30>: CDS_PINID='DQ(30)';
NODE_NAME     J9L2 188
 '@BASEBOARD_FAB2_LIB.BASEBOARD_FAB2(SCH_1):PAGE86_I12@MSTR_SCONN.SCONN288_H44441003(CHIPS)':
 'DQ'<31>: CDS_PINID='DQ(31)';
NET_NAME
'M_L_DQ<32>'
 '@BASEBOARD_FAB2_LIB.BASEBOARD_FAB2(SCH_1):M_L_DQ'<32>:
 C_SIGNAL='@baseboard_fab2_lib.baseboard_fab2(sch_1):m_l_dq(32)';
NODE_NAME     U2D1 DU42
 '@BASEBOARD_FAB2_LIB.BASEBOARD_FAB2(SCH_1):PAGE61_I172@CHPSET_LIB.SKX_EXT_B(CHIPS)':
 'DDR4_DQ'<32>: CDS_PINID='DDR4_DQ(32)';
NODE_NAME     J1A2 242
 '@BASEBOARD_FAB2_LIB.BASEBOARD_FAB2(SCH_1):PAGE85_I111@MSTR_SCONN.SCONN288_H44441004(CHIPS)':
 'DQ'<33>: CDS_PINID='DQ(33)';
NODE_NAME     J9L2 97
 '@BASEBOARD_FAB2_LIB.BASEBOARD_FAB2(SCH_1):PAGE86_I12@MSTR_SCONN.SCONN288_H44441003(CHIPS)':
 'DQ'<32>: CDS_PINID='DQ(32)';
NET_NAME
'M_L_DQ<33>'
 '@BASEBOARD_FAB2_LIB.BASEBOARD_FAB2(SCH_1):M_L_DQ'<33>:
 C_SIGNAL='@baseboard_fab2_lib.baseboard_fab2(sch_1):m_l_dq(33)';
NODE_NAME     U2D1 DW42
 '@BASEBOARD_FAB2_LIB.BASEBOARD_FAB2(SCH_1):PAGE61_I172@CHPSET_LIB.SKX_EXT_B(CHIPS)':
 'DDR4_DQ'<33>: CDS_PINID='DDR4_DQ(33)';
NODE_NAME     J1A2 97
 '@BASEBOARD_FAB2_LIB.BASEBOARD_FAB2(SCH_1):PAGE85_I111@MSTR_SCONN.SCONN288_H44441004(CHIPS)':
 'DQ'<32>: CDS_PINID='DQ(32)';
NODE_NAME     J9L2 242
 '@BASEBOARD_FAB2_LIB.BASEBOARD_FAB2(SCH_1):PAGE86_I12@MSTR_SCONN.SCONN288_H44441003(CHIPS)':
 'DQ'<33>: CDS_PINID='DQ(33)';
NET_NAME
'M_L_DQ<34>'
 '@BASEBOARD_FAB2_LIB.BASEBOARD_FAB2(SCH_1):M_L_DQ'<34>:
 C_SIGNAL='@baseboard_fab2_lib.baseboard_fab2(sch_1):m_l_dq(34)';
NODE_NAME     U2D1 DP39
 '@BASEBOARD_FAB2_LIB.BASEBOARD_FAB2(SCH_1):PAGE61_I172@CHPSET_LIB.SKX_EXT_B(CHIPS)':
 'DDR4_DQ'<34>: CDS_PINID='DDR4_DQ(34)';
NODE_NAME     J1A2 249
 '@BASEBOARD_FAB2_LIB.BASEBOARD_FAB2(SCH_1):PAGE85_I111@MSTR_SCONN.SCONN288_H44441004(CHIPS)':
 'DQ'<35>: CDS_PINID='DQ(35)';
NODE_NAME     J9L2 104
 '@BASEBOARD_FAB2_LIB.BASEBOARD_FAB2(SCH_1):PAGE86_I12@MSTR_SCONN.SCONN288_H44441003(CHIPS)':
 'DQ'<34>: CDS_PINID='DQ(34)';
NET_NAME
'M_L_DQ<35>'
 '@BASEBOARD_FAB2_LIB.BASEBOARD_FAB2(SCH_1):M_L_DQ'<35>:
 C_SIGNAL='@baseboard_fab2_lib.baseboard_fab2(sch_1):m_l_dq(35)';
NODE_NAME     U2D1 DT39
 '@BASEBOARD_FAB2_LIB.BASEBOARD_FAB2(SCH_1):PAGE61_I172@CHPSET_LIB.SKX_EXT_B(CHIPS)':
 'DDR4_DQ'<35>: CDS_PINID='DDR4_DQ(35)';
NODE_NAME     J1A2 104
 '@BASEBOARD_FAB2_LIB.BASEBOARD_FAB2(SCH_1):PAGE85_I111@MSTR_SCONN.SCONN288_H44441004(CHIPS)':
 'DQ'<34>: CDS_PINID='DQ(34)';
NODE_NAME     J9L2 249
 '@BASEBOARD_FAB2_LIB.BASEBOARD_FAB2(SCH_1):PAGE86_I12@MSTR_SCONN.SCONN288_H44441003(CHIPS)':
 'DQ'<35>: CDS_PINID='DQ(35)';
NET_NAME
'M_L_DQ<36>'
 '@BASEBOARD_FAB2_LIB.BASEBOARD_FAB2(SCH_1):M_L_DQ'<36>:
 C_SIGNAL='@baseboard_fab2_lib.baseboard_fab2(sch_1):m_l_dq(36)';
NODE_NAME     U2D1 DL42
 '@BASEBOARD_FAB2_LIB.BASEBOARD_FAB2(SCH_1):PAGE61_I172@CHPSET_LIB.SKX_EXT_B(CHIPS)':
 'DDR4_DQ'<36>: CDS_PINID='DDR4_DQ(36)';
NODE_NAME     J1A2 240
 '@BASEBOARD_FAB2_LIB.BASEBOARD_FAB2(SCH_1):PAGE85_I111@MSTR_SCONN.SCONN288_H44441004(CHIPS)':
 'DQ'<37>: CDS_PINID='DQ(37)';
NODE_NAME     J9L2 95
 '@BASEBOARD_FAB2_LIB.BASEBOARD_FAB2(SCH_1):PAGE86_I12@MSTR_SCONN.SCONN288_H44441003(CHIPS)':
 'DQ'<36>: CDS_PINID='DQ(36)';
NET_NAME
'M_L_DQ<37>'
 '@BASEBOARD_FAB2_LIB.BASEBOARD_FAB2(SCH_1):M_L_DQ'<37>:
 C_SIGNAL='@baseboard_fab2_lib.baseboard_fab2(sch_1):m_l_dq(37)';
NODE_NAME     U2D1 DN42
 '@BASEBOARD_FAB2_LIB.BASEBOARD_FAB2(SCH_1):PAGE61_I172@CHPSET_LIB.SKX_EXT_B(CHIPS)':
 'DDR4_DQ'<37>: CDS_PINID='DDR4_DQ(37)';
NODE_NAME     J1A2 95
 '@BASEBOARD_FAB2_LIB.BASEBOARD_FAB2(SCH_1):PAGE85_I111@MSTR_SCONN.SCONN288_H44441004(CHIPS)':
 'DQ'<36>: CDS_PINID='DQ(36)';
NODE_NAME     J9L2 240
 '@BASEBOARD_FAB2_LIB.BASEBOARD_FAB2(SCH_1):PAGE86_I12@MSTR_SCONN.SCONN288_H44441003(CHIPS)':
 'DQ'<37>: CDS_PINID='DQ(37)';
NET_NAME
'M_L_DQ<38>'
 '@BASEBOARD_FAB2_LIB.BASEBOARD_FAB2(SCH_1):M_L_DQ'<38>:
 C_SIGNAL='@baseboard_fab2_lib.baseboard_fab2(sch_1):m_l_dq(38)';
NODE_NAME     U2D1 DN40
 '@BASEBOARD_FAB2_LIB.BASEBOARD_FAB2(SCH_1):PAGE61_I172@CHPSET_LIB.SKX_EXT_B(CHIPS)':
 'DDR4_DQ'<38>: CDS_PINID='DDR4_DQ(38)';
NODE_NAME     J1A2 247
 '@BASEBOARD_FAB2_LIB.BASEBOARD_FAB2(SCH_1):PAGE85_I111@MSTR_SCONN.SCONN288_H44441004(CHIPS)':
 'DQ'<39>: CDS_PINID='DQ(39)';
NODE_NAME     J9L2 102
 '@BASEBOARD_FAB2_LIB.BASEBOARD_FAB2(SCH_1):PAGE86_I12@MSTR_SCONN.SCONN288_H44441003(CHIPS)':
 'DQ'<38>: CDS_PINID='DQ(38)';
NET_NAME
'M_L_DQ<39>'
 '@BASEBOARD_FAB2_LIB.BASEBOARD_FAB2(SCH_1):M_L_DQ'<39>:
 C_SIGNAL='@baseboard_fab2_lib.baseboard_fab2(sch_1):m_l_dq(39)';
NODE_NAME     U2D1 DU40
 '@BASEBOARD_FAB2_LIB.BASEBOARD_FAB2(SCH_1):PAGE61_I172@CHPSET_LIB.SKX_EXT_B(CHIPS)':
 'DDR4_DQ'<39>: CDS_PINID='DDR4_DQ(39)';
NODE_NAME     J1A2 102
 '@BASEBOARD_FAB2_LIB.BASEBOARD_FAB2(SCH_1):PAGE85_I111@MSTR_SCONN.SCONN288_H44441004(CHIPS)':
 'DQ'<38>: CDS_PINID='DQ(38)';
NODE_NAME     J9L2 247
 '@BASEBOARD_FAB2_LIB.BASEBOARD_FAB2(SCH_1):PAGE86_I12@MSTR_SCONN.SCONN288_H44441003(CHIPS)':
 'DQ'<39>: CDS_PINID='DQ(39)';
NET_NAME
'M_L_DQ<3>'
 '@BASEBOARD_FAB2_LIB.BASEBOARD_FAB2(SCH_1):M_L_DQ'<3>:
 C_SIGNAL='@baseboard_fab2_lib.baseboard_fab2(sch_1):m_l_dq(3)';
NODE_NAME     U2D1 CR82
 '@BASEBOARD_FAB2_LIB.BASEBOARD_FAB2(SCH_1):PAGE61_I172@CHPSET_LIB.SKX_EXT_B(CHIPS)':
 'DDR4_DQ'<3>: CDS_PINID='DDR4_DQ(3)';
NODE_NAME     J1A2 12
 '@BASEBOARD_FAB2_LIB.BASEBOARD_FAB2(SCH_1):PAGE85_I111@MSTR_SCONN.SCONN288_H44441004(CHIPS)':
 'DQ'<2>: CDS_PINID='DQ(2)';
NODE_NAME     J9L2 157
 '@BASEBOARD_FAB2_LIB.BASEBOARD_FAB2(SCH_1):PAGE86_I12@MSTR_SCONN.SCONN288_H44441003(CHIPS)':
 'DQ'<3>: CDS_PINID='DQ(3)';
NET_NAME
'M_L_DQ<40>'
 '@BASEBOARD_FAB2_LIB.BASEBOARD_FAB2(SCH_1):M_L_DQ'<40>:
 C_SIGNAL='@baseboard_fab2_lib.baseboard_fab2(sch_1):m_l_dq(40)';
NODE_NAME     U2D1 EC34
 '@BASEBOARD_FAB2_LIB.BASEBOARD_FAB2(SCH_1):PAGE61_I172@CHPSET_LIB.SKX_EXT_B(CHIPS)':
 'DDR4_DQ'<40>: CDS_PINID='DDR4_DQ(40)';
NODE_NAME     J1A2 253
 '@BASEBOARD_FAB2_LIB.BASEBOARD_FAB2(SCH_1):PAGE85_I111@MSTR_SCONN.SCONN288_H44441004(CHIPS)':
 'DQ'<41>: CDS_PINID='DQ(41)';
NODE_NAME     J9L2 108
 '@BASEBOARD_FAB2_LIB.BASEBOARD_FAB2(SCH_1):PAGE86_I12@MSTR_SCONN.SCONN288_H44441003(CHIPS)':
 'DQ'<40>: CDS_PINID='DQ(40)';
NET_NAME
'M_L_DQ<41>'
 '@BASEBOARD_FAB2_LIB.BASEBOARD_FAB2(SCH_1):M_L_DQ'<41>:
 C_SIGNAL='@baseboard_fab2_lib.baseboard_fab2(sch_1):m_l_dq(41)';
NODE_NAME     U2D1 ED33
 '@BASEBOARD_FAB2_LIB.BASEBOARD_FAB2(SCH_1):PAGE61_I172@CHPSET_LIB.SKX_EXT_B(CHIPS)':
 'DDR4_DQ'<41>: CDS_PINID='DDR4_DQ(41)';
NODE_NAME     J1A2 108
 '@BASEBOARD_FAB2_LIB.BASEBOARD_FAB2(SCH_1):PAGE85_I111@MSTR_SCONN.SCONN288_H44441004(CHIPS)':
 'DQ'<40>: CDS_PINID='DQ(40)';
NODE_NAME     J9L2 253
 '@BASEBOARD_FAB2_LIB.BASEBOARD_FAB2(SCH_1):PAGE86_I12@MSTR_SCONN.SCONN288_H44441003(CHIPS)':
 'DQ'<41>: CDS_PINID='DQ(41)';
NET_NAME
'M_L_DQ<42>'
 '@BASEBOARD_FAB2_LIB.BASEBOARD_FAB2(SCH_1):M_L_DQ'<42>:
 C_SIGNAL='@baseboard_fab2_lib.baseboard_fab2(sch_1):m_l_dq(42)';
NODE_NAME     U2D1 EA30
 '@BASEBOARD_FAB2_LIB.BASEBOARD_FAB2(SCH_1):PAGE61_I172@CHPSET_LIB.SKX_EXT_B(CHIPS)':
 'DDR4_DQ'<42>: CDS_PINID='DDR4_DQ(42)';
NODE_NAME     J1A2 260
 '@BASEBOARD_FAB2_LIB.BASEBOARD_FAB2(SCH_1):PAGE85_I111@MSTR_SCONN.SCONN288_H44441004(CHIPS)':
 'DQ'<43>: CDS_PINID='DQ(43)';
NODE_NAME     J9L2 115
 '@BASEBOARD_FAB2_LIB.BASEBOARD_FAB2(SCH_1):PAGE86_I12@MSTR_SCONN.SCONN288_H44441003(CHIPS)':
 'DQ'<42>: CDS_PINID='DQ(42)';
NET_NAME
'M_L_DQ<43>'
 '@BASEBOARD_FAB2_LIB.BASEBOARD_FAB2(SCH_1):M_L_DQ'<43>:
 C_SIGNAL='@baseboard_fab2_lib.baseboard_fab2(sch_1):m_l_dq(43)';
NODE_NAME     U2D1 EC30
 '@BASEBOARD_FAB2_LIB.BASEBOARD_FAB2(SCH_1):PAGE61_I172@CHPSET_LIB.SKX_EXT_B(CHIPS)':
 'DDR4_DQ'<43>: CDS_PINID='DDR4_DQ(43)';
NODE_NAME     J1A2 115
 '@BASEBOARD_FAB2_LIB.BASEBOARD_FAB2(SCH_1):PAGE85_I111@MSTR_SCONN.SCONN288_H44441004(CHIPS)':
 'DQ'<42>: CDS_PINID='DQ(42)';
NODE_NAME     J9L2 260
 '@BASEBOARD_FAB2_LIB.BASEBOARD_FAB2(SCH_1):PAGE86_I12@MSTR_SCONN.SCONN288_H44441003(CHIPS)':
 'DQ'<43>: CDS_PINID='DQ(43)';
NET_NAME
'M_L_DQ<44>'
 '@BASEBOARD_FAB2_LIB.BASEBOARD_FAB2(SCH_1):M_L_DQ'<44>:
 C_SIGNAL='@baseboard_fab2_lib.baseboard_fab2(sch_1):m_l_dq(44)';
NODE_NAME     U2D1 DY33
 '@BASEBOARD_FAB2_LIB.BASEBOARD_FAB2(SCH_1):PAGE61_I172@CHPSET_LIB.SKX_EXT_B(CHIPS)':
 'DDR4_DQ'<44>: CDS_PINID='DDR4_DQ(44)';
NODE_NAME     J1A2 251
 '@BASEBOARD_FAB2_LIB.BASEBOARD_FAB2(SCH_1):PAGE85_I111@MSTR_SCONN.SCONN288_H44441004(CHIPS)':
 'DQ'<45>: CDS_PINID='DQ(45)';
NODE_NAME     J9L2 106
 '@BASEBOARD_FAB2_LIB.BASEBOARD_FAB2(SCH_1):PAGE86_I12@MSTR_SCONN.SCONN288_H44441003(CHIPS)':
 'DQ'<44>: CDS_PINID='DQ(44)';
NET_NAME
'M_L_DQ<45>'
 '@BASEBOARD_FAB2_LIB.BASEBOARD_FAB2(SCH_1):M_L_DQ'<45>:
 C_SIGNAL='@baseboard_fab2_lib.baseboard_fab2(sch_1):m_l_dq(45)';
NODE_NAME     U2D1 EA34
 '@BASEBOARD_FAB2_LIB.BASEBOARD_FAB2(SCH_1):PAGE61_I172@CHPSET_LIB.SKX_EXT_B(CHIPS)':
 'DDR4_DQ'<45>: CDS_PINID='DDR4_DQ(45)';
NODE_NAME     J1A2 106
 '@BASEBOARD_FAB2_LIB.BASEBOARD_FAB2(SCH_1):PAGE85_I111@MSTR_SCONN.SCONN288_H44441004(CHIPS)':
 'DQ'<44>: CDS_PINID='DQ(44)';
NODE_NAME     J9L2 251
 '@BASEBOARD_FAB2_LIB.BASEBOARD_FAB2(SCH_1):PAGE86_I12@MSTR_SCONN.SCONN288_H44441003(CHIPS)':
 'DQ'<45>: CDS_PINID='DQ(45)';
NET_NAME
'M_L_DQ<46>'
 '@BASEBOARD_FAB2_LIB.BASEBOARD_FAB2(SCH_1):M_L_DQ'<46>:
 C_SIGNAL='@baseboard_fab2_lib.baseboard_fab2(sch_1):m_l_dq(46)';
NODE_NAME     U2D1 DY31
 '@BASEBOARD_FAB2_LIB.BASEBOARD_FAB2(SCH_1):PAGE61_I172@CHPSET_LIB.SKX_EXT_B(CHIPS)':
 'DDR4_DQ'<46>: CDS_PINID='DDR4_DQ(46)';
NODE_NAME     J1A2 258
 '@BASEBOARD_FAB2_LIB.BASEBOARD_FAB2(SCH_1):PAGE85_I111@MSTR_SCONN.SCONN288_H44441004(CHIPS)':
 'DQ'<47>: CDS_PINID='DQ(47)';
NODE_NAME     J9L2 113
 '@BASEBOARD_FAB2_LIB.BASEBOARD_FAB2(SCH_1):PAGE86_I12@MSTR_SCONN.SCONN288_H44441003(CHIPS)':
 'DQ'<46>: CDS_PINID='DQ(46)';
NET_NAME
'M_L_DQ<47>'
 '@BASEBOARD_FAB2_LIB.BASEBOARD_FAB2(SCH_1):M_L_DQ'<47>:
 C_SIGNAL='@baseboard_fab2_lib.baseboard_fab2(sch_1):m_l_dq(47)';
NODE_NAME     U2D1 ED31
 '@BASEBOARD_FAB2_LIB.BASEBOARD_FAB2(SCH_1):PAGE61_I172@CHPSET_LIB.SKX_EXT_B(CHIPS)':
 'DDR4_DQ'<47>: CDS_PINID='DDR4_DQ(47)';
NODE_NAME     J1A2 113
 '@BASEBOARD_FAB2_LIB.BASEBOARD_FAB2(SCH_1):PAGE85_I111@MSTR_SCONN.SCONN288_H44441004(CHIPS)':
 'DQ'<46>: CDS_PINID='DQ(46)';
NODE_NAME     J9L2 258
 '@BASEBOARD_FAB2_LIB.BASEBOARD_FAB2(SCH_1):PAGE86_I12@MSTR_SCONN.SCONN288_H44441003(CHIPS)':
 'DQ'<47>: CDS_PINID='DQ(47)';
NET_NAME
'M_L_DQ<48>'
 '@BASEBOARD_FAB2_LIB.BASEBOARD_FAB2(SCH_1):M_L_DQ'<48>:
 C_SIGNAL='@baseboard_fab2_lib.baseboard_fab2(sch_1):m_l_dq(48)';
NODE_NAME     U2D1 EC28
 '@BASEBOARD_FAB2_LIB.BASEBOARD_FAB2(SCH_1):PAGE61_I172@CHPSET_LIB.SKX_EXT_B(CHIPS)':
 'DDR4_DQ'<48>: CDS_PINID='DDR4_DQ(48)';
NODE_NAME     J1A2 264
 '@BASEBOARD_FAB2_LIB.BASEBOARD_FAB2(SCH_1):PAGE85_I111@MSTR_SCONN.SCONN288_H44441004(CHIPS)':
 'DQ'<49>: CDS_PINID='DQ(49)';
NODE_NAME     J9L2 119
 '@BASEBOARD_FAB2_LIB.BASEBOARD_FAB2(SCH_1):PAGE86_I12@MSTR_SCONN.SCONN288_H44441003(CHIPS)':
 'DQ'<48>: CDS_PINID='DQ(48)';
NET_NAME
'M_L_DQ<49>'
 '@BASEBOARD_FAB2_LIB.BASEBOARD_FAB2(SCH_1):M_L_DQ'<49>:
 C_SIGNAL='@baseboard_fab2_lib.baseboard_fab2(sch_1):m_l_dq(49)';
NODE_NAME     U2D1 ED27
 '@BASEBOARD_FAB2_LIB.BASEBOARD_FAB2(SCH_1):PAGE61_I172@CHPSET_LIB.SKX_EXT_B(CHIPS)':
 'DDR4_DQ'<49>: CDS_PINID='DDR4_DQ(49)';
NODE_NAME     J1A2 119
 '@BASEBOARD_FAB2_LIB.BASEBOARD_FAB2(SCH_1):PAGE85_I111@MSTR_SCONN.SCONN288_H44441004(CHIPS)':
 'DQ'<48>: CDS_PINID='DQ(48)';
NODE_NAME     J9L2 264
 '@BASEBOARD_FAB2_LIB.BASEBOARD_FAB2(SCH_1):PAGE86_I12@MSTR_SCONN.SCONN288_H44441003(CHIPS)':
 'DQ'<49>: CDS_PINID='DQ(49)';
NET_NAME
'M_L_DQ<4>'
 '@BASEBOARD_FAB2_LIB.BASEBOARD_FAB2(SCH_1):M_L_DQ'<4>:
 C_SIGNAL='@baseboard_fab2_lib.baseboard_fab2(sch_1):m_l_dq(4)';
NODE_NAME     U2D1 CK79
 '@BASEBOARD_FAB2_LIB.BASEBOARD_FAB2(SCH_1):PAGE61_I172@CHPSET_LIB.SKX_EXT_B(CHIPS)':
 'DDR4_DQ'<4>: CDS_PINID='DDR4_DQ(4)';
NODE_NAME     J1A2 148
 '@BASEBOARD_FAB2_LIB.BASEBOARD_FAB2(SCH_1):PAGE85_I111@MSTR_SCONN.SCONN288_H44441004(CHIPS)':
 'DQ'<5>: CDS_PINID='DQ(5)';
NODE_NAME     J9L2 3
 '@BASEBOARD_FAB2_LIB.BASEBOARD_FAB2(SCH_1):PAGE86_I12@MSTR_SCONN.SCONN288_H44441003(CHIPS)':
 'DQ'<4>: CDS_PINID='DQ(4)';
NET_NAME
'M_L_DQ<50>'
 '@BASEBOARD_FAB2_LIB.BASEBOARD_FAB2(SCH_1):M_L_DQ'<50>:
 C_SIGNAL='@baseboard_fab2_lib.baseboard_fab2(sch_1):m_l_dq(50)';
NODE_NAME     U2D1 EA24
 '@BASEBOARD_FAB2_LIB.BASEBOARD_FAB2(SCH_1):PAGE61_I172@CHPSET_LIB.SKX_EXT_B(CHIPS)':
 'DDR4_DQ'<50>: CDS_PINID='DDR4_DQ(50)';
NODE_NAME     J1A2 271
 '@BASEBOARD_FAB2_LIB.BASEBOARD_FAB2(SCH_1):PAGE85_I111@MSTR_SCONN.SCONN288_H44441004(CHIPS)':
 'DQ'<51>: CDS_PINID='DQ(51)';
NODE_NAME     J9L2 126
 '@BASEBOARD_FAB2_LIB.BASEBOARD_FAB2(SCH_1):PAGE86_I12@MSTR_SCONN.SCONN288_H44441003(CHIPS)':
 'DQ'<50>: CDS_PINID='DQ(50)';
NET_NAME
'M_L_DQ<51>'
 '@BASEBOARD_FAB2_LIB.BASEBOARD_FAB2(SCH_1):M_L_DQ'<51>:
 C_SIGNAL='@baseboard_fab2_lib.baseboard_fab2(sch_1):m_l_dq(51)';
NODE_NAME     U2D1 EC24
 '@BASEBOARD_FAB2_LIB.BASEBOARD_FAB2(SCH_1):PAGE61_I172@CHPSET_LIB.SKX_EXT_B(CHIPS)':
 'DDR4_DQ'<51>: CDS_PINID='DDR4_DQ(51)';
NODE_NAME     J1A2 126
 '@BASEBOARD_FAB2_LIB.BASEBOARD_FAB2(SCH_1):PAGE85_I111@MSTR_SCONN.SCONN288_H44441004(CHIPS)':
 'DQ'<50>: CDS_PINID='DQ(50)';
NODE_NAME     J9L2 271
 '@BASEBOARD_FAB2_LIB.BASEBOARD_FAB2(SCH_1):PAGE86_I12@MSTR_SCONN.SCONN288_H44441003(CHIPS)':
 'DQ'<51>: CDS_PINID='DQ(51)';
NET_NAME
'M_L_DQ<52>'
 '@BASEBOARD_FAB2_LIB.BASEBOARD_FAB2(SCH_1):M_L_DQ'<52>:
 C_SIGNAL='@baseboard_fab2_lib.baseboard_fab2(sch_1):m_l_dq(52)';
NODE_NAME     U2D1 DY27
 '@BASEBOARD_FAB2_LIB.BASEBOARD_FAB2(SCH_1):PAGE61_I172@CHPSET_LIB.SKX_EXT_B(CHIPS)':
 'DDR4_DQ'<52>: CDS_PINID='DDR4_DQ(52)';
NODE_NAME     J1A2 262
 '@BASEBOARD_FAB2_LIB.BASEBOARD_FAB2(SCH_1):PAGE85_I111@MSTR_SCONN.SCONN288_H44441004(CHIPS)':
 'DQ'<53>: CDS_PINID='DQ(53)';
NODE_NAME     J9L2 117
 '@BASEBOARD_FAB2_LIB.BASEBOARD_FAB2(SCH_1):PAGE86_I12@MSTR_SCONN.SCONN288_H44441003(CHIPS)':
 'DQ'<52>: CDS_PINID='DQ(52)';
NET_NAME
'M_L_DQ<53>'
 '@BASEBOARD_FAB2_LIB.BASEBOARD_FAB2(SCH_1):M_L_DQ'<53>:
 C_SIGNAL='@baseboard_fab2_lib.baseboard_fab2(sch_1):m_l_dq(53)';
NODE_NAME     U2D1 EA28
 '@BASEBOARD_FAB2_LIB.BASEBOARD_FAB2(SCH_1):PAGE61_I172@CHPSET_LIB.SKX_EXT_B(CHIPS)':
 'DDR4_DQ'<53>: CDS_PINID='DDR4_DQ(53)';
NODE_NAME     J1A2 117
 '@BASEBOARD_FAB2_LIB.BASEBOARD_FAB2(SCH_1):PAGE85_I111@MSTR_SCONN.SCONN288_H44441004(CHIPS)':
 'DQ'<52>: CDS_PINID='DQ(52)';
NODE_NAME     J9L2 262
 '@BASEBOARD_FAB2_LIB.BASEBOARD_FAB2(SCH_1):PAGE86_I12@MSTR_SCONN.SCONN288_H44441003(CHIPS)':
 'DQ'<53>: CDS_PINID='DQ(53)';
NET_NAME
'M_L_DQ<54>'
 '@BASEBOARD_FAB2_LIB.BASEBOARD_FAB2(SCH_1):M_L_DQ'<54>:
 C_SIGNAL='@baseboard_fab2_lib.baseboard_fab2(sch_1):m_l_dq(54)';
NODE_NAME     U2D1 DY25
 '@BASEBOARD_FAB2_LIB.BASEBOARD_FAB2(SCH_1):PAGE61_I172@CHPSET_LIB.SKX_EXT_B(CHIPS)':
 'DDR4_DQ'<54>: CDS_PINID='DDR4_DQ(54)';
NODE_NAME     J1A2 269
 '@BASEBOARD_FAB2_LIB.BASEBOARD_FAB2(SCH_1):PAGE85_I111@MSTR_SCONN.SCONN288_H44441004(CHIPS)':
 'DQ'<55>: CDS_PINID='DQ(55)';
NODE_NAME     J9L2 124
 '@BASEBOARD_FAB2_LIB.BASEBOARD_FAB2(SCH_1):PAGE86_I12@MSTR_SCONN.SCONN288_H44441003(CHIPS)':
 'DQ'<54>: CDS_PINID='DQ(54)';
NET_NAME
'M_L_DQ<55>'
 '@BASEBOARD_FAB2_LIB.BASEBOARD_FAB2(SCH_1):M_L_DQ'<55>:
 C_SIGNAL='@baseboard_fab2_lib.baseboard_fab2(sch_1):m_l_dq(55)';
NODE_NAME     U2D1 ED25
 '@BASEBOARD_FAB2_LIB.BASEBOARD_FAB2(SCH_1):PAGE61_I172@CHPSET_LIB.SKX_EXT_B(CHIPS)':
 'DDR4_DQ'<55>: CDS_PINID='DDR4_DQ(55)';
NODE_NAME     J1A2 124
 '@BASEBOARD_FAB2_LIB.BASEBOARD_FAB2(SCH_1):PAGE85_I111@MSTR_SCONN.SCONN288_H44441004(CHIPS)':
 'DQ'<54>: CDS_PINID='DQ(54)';
NODE_NAME     J9L2 269
 '@BASEBOARD_FAB2_LIB.BASEBOARD_FAB2(SCH_1):PAGE86_I12@MSTR_SCONN.SCONN288_H44441003(CHIPS)':
 'DQ'<55>: CDS_PINID='DQ(55)';
NET_NAME
'M_L_DQ<56>'
 '@BASEBOARD_FAB2_LIB.BASEBOARD_FAB2(SCH_1):M_L_DQ'<56>:
 C_SIGNAL='@baseboard_fab2_lib.baseboard_fab2(sch_1):m_l_dq(56)';
NODE_NAME     U2D1 DF27
 '@BASEBOARD_FAB2_LIB.BASEBOARD_FAB2(SCH_1):PAGE61_I172@CHPSET_LIB.SKX_EXT_B(CHIPS)':
 'DDR4_DQ'<56>: CDS_PINID='DDR4_DQ(56)';
NODE_NAME     J1A2 275
 '@BASEBOARD_FAB2_LIB.BASEBOARD_FAB2(SCH_1):PAGE85_I111@MSTR_SCONN.SCONN288_H44441004(CHIPS)':
 'DQ'<57>: CDS_PINID='DQ(57)';
NODE_NAME     J9L2 130
 '@BASEBOARD_FAB2_LIB.BASEBOARD_FAB2(SCH_1):PAGE86_I12@MSTR_SCONN.SCONN288_H44441003(CHIPS)':
 'DQ'<56>: CDS_PINID='DQ(56)';
NET_NAME
'M_L_DQ<57>'
 '@BASEBOARD_FAB2_LIB.BASEBOARD_FAB2(SCH_1):M_L_DQ'<57>:
 C_SIGNAL='@baseboard_fab2_lib.baseboard_fab2(sch_1):m_l_dq(57)';
NODE_NAME     U2D1 DK27
 '@BASEBOARD_FAB2_LIB.BASEBOARD_FAB2(SCH_1):PAGE61_I172@CHPSET_LIB.SKX_EXT_B(CHIPS)':
 'DDR4_DQ'<57>: CDS_PINID='DDR4_DQ(57)';
NODE_NAME     J1A2 130
 '@BASEBOARD_FAB2_LIB.BASEBOARD_FAB2(SCH_1):PAGE85_I111@MSTR_SCONN.SCONN288_H44441004(CHIPS)':
 'DQ'<56>: CDS_PINID='DQ(56)';
NODE_NAME     J9L2 275
 '@BASEBOARD_FAB2_LIB.BASEBOARD_FAB2(SCH_1):PAGE86_I12@MSTR_SCONN.SCONN288_H44441003(CHIPS)':
 'DQ'<57>: CDS_PINID='DQ(57)';
NET_NAME
'M_L_DQ<58>'
 '@BASEBOARD_FAB2_LIB.BASEBOARD_FAB2(SCH_1):M_L_DQ'<58>:
 C_SIGNAL='@baseboard_fab2_lib.baseboard_fab2(sch_1):m_l_dq(58)';
NODE_NAME     U2D1 DD25
 '@BASEBOARD_FAB2_LIB.BASEBOARD_FAB2(SCH_1):PAGE61_I172@CHPSET_LIB.SKX_EXT_B(CHIPS)':
 'DDR4_DQ'<58>: CDS_PINID='DDR4_DQ(58)';
NODE_NAME     J1A2 282
 '@BASEBOARD_FAB2_LIB.BASEBOARD_FAB2(SCH_1):PAGE85_I111@MSTR_SCONN.SCONN288_H44441004(CHIPS)':
 'DQ'<59>: CDS_PINID='DQ(59)';
NODE_NAME     J9L2 137
 '@BASEBOARD_FAB2_LIB.BASEBOARD_FAB2(SCH_1):PAGE86_I12@MSTR_SCONN.SCONN288_H44441003(CHIPS)':
 'DQ'<58>: CDS_PINID='DQ(58)';
NET_NAME
'M_L_DQ<59>'
 '@BASEBOARD_FAB2_LIB.BASEBOARD_FAB2(SCH_1):M_L_DQ'<59>:
 C_SIGNAL='@baseboard_fab2_lib.baseboard_fab2(sch_1):m_l_dq(59)';
NODE_NAME     U2D1 DJ24
 '@BASEBOARD_FAB2_LIB.BASEBOARD_FAB2(SCH_1):PAGE61_I172@CHPSET_LIB.SKX_EXT_B(CHIPS)':
 'DDR4_DQ'<59>: CDS_PINID='DDR4_DQ(59)';
NODE_NAME     J1A2 137
 '@BASEBOARD_FAB2_LIB.BASEBOARD_FAB2(SCH_1):PAGE85_I111@MSTR_SCONN.SCONN288_H44441004(CHIPS)':
 'DQ'<58>: CDS_PINID='DQ(58)';
NODE_NAME     J9L2 282
 '@BASEBOARD_FAB2_LIB.BASEBOARD_FAB2(SCH_1):PAGE86_I12@MSTR_SCONN.SCONN288_H44441003(CHIPS)':
 'DQ'<59>: CDS_PINID='DQ(59)';
NET_NAME
'M_L_DQ<5>'
 '@BASEBOARD_FAB2_LIB.BASEBOARD_FAB2(SCH_1):M_L_DQ'<5>:
 C_SIGNAL='@baseboard_fab2_lib.baseboard_fab2(sch_1):m_l_dq(5)';
NODE_NAME     U2D1 CJ80
 '@BASEBOARD_FAB2_LIB.BASEBOARD_FAB2(SCH_1):PAGE61_I172@CHPSET_LIB.SKX_EXT_B(CHIPS)':
 'DDR4_DQ'<5>: CDS_PINID='DDR4_DQ(5)';
NODE_NAME     J1A2 3
 '@BASEBOARD_FAB2_LIB.BASEBOARD_FAB2(SCH_1):PAGE85_I111@MSTR_SCONN.SCONN288_H44441004(CHIPS)':
 'DQ'<4>: CDS_PINID='DQ(4)';
NODE_NAME     J9L2 148
 '@BASEBOARD_FAB2_LIB.BASEBOARD_FAB2(SCH_1):PAGE86_I12@MSTR_SCONN.SCONN288_H44441003(CHIPS)':
 'DQ'<5>: CDS_PINID='DQ(5)';
NET_NAME
'M_L_DQ<60>'
 '@BASEBOARD_FAB2_LIB.BASEBOARD_FAB2(SCH_1):M_L_DQ'<60>:
 C_SIGNAL='@baseboard_fab2_lib.baseboard_fab2(sch_1):m_l_dq(60)';
NODE_NAME     U2D1 DG28
 '@BASEBOARD_FAB2_LIB.BASEBOARD_FAB2(SCH_1):PAGE61_I172@CHPSET_LIB.SKX_EXT_B(CHIPS)':
 'DDR4_DQ'<60>: CDS_PINID='DDR4_DQ(60)';
NODE_NAME     J1A2 273
 '@BASEBOARD_FAB2_LIB.BASEBOARD_FAB2(SCH_1):PAGE85_I111@MSTR_SCONN.SCONN288_H44441004(CHIPS)':
 'DQ'<61>: CDS_PINID='DQ(61)';
NODE_NAME     J9L2 128
 '@BASEBOARD_FAB2_LIB.BASEBOARD_FAB2(SCH_1):PAGE86_I12@MSTR_SCONN.SCONN288_H44441003(CHIPS)':
 'DQ'<60>: CDS_PINID='DQ(60)';
NET_NAME
'M_L_DQ<61>'
 '@BASEBOARD_FAB2_LIB.BASEBOARD_FAB2(SCH_1):M_L_DQ'<61>:
 C_SIGNAL='@baseboard_fab2_lib.baseboard_fab2(sch_1):m_l_dq(61)';
NODE_NAME     U2D1 DJ28
 '@BASEBOARD_FAB2_LIB.BASEBOARD_FAB2(SCH_1):PAGE61_I172@CHPSET_LIB.SKX_EXT_B(CHIPS)':
 'DDR4_DQ'<61>: CDS_PINID='DDR4_DQ(61)';
NODE_NAME     J1A2 128
 '@BASEBOARD_FAB2_LIB.BASEBOARD_FAB2(SCH_1):PAGE85_I111@MSTR_SCONN.SCONN288_H44441004(CHIPS)':
 'DQ'<60>: CDS_PINID='DQ(60)';
NODE_NAME     J9L2 273
 '@BASEBOARD_FAB2_LIB.BASEBOARD_FAB2(SCH_1):PAGE86_I12@MSTR_SCONN.SCONN288_H44441003(CHIPS)':
 'DQ'<61>: CDS_PINID='DQ(61)';
NET_NAME
'M_L_DQ<62>'
 '@BASEBOARD_FAB2_LIB.BASEBOARD_FAB2(SCH_1):M_L_DQ'<62>:
 C_SIGNAL='@baseboard_fab2_lib.baseboard_fab2(sch_1):m_l_dq(62)';
NODE_NAME     U2D1 DF25
 '@BASEBOARD_FAB2_LIB.BASEBOARD_FAB2(SCH_1):PAGE61_I172@CHPSET_LIB.SKX_EXT_B(CHIPS)':
 'DDR4_DQ'<62>: CDS_PINID='DDR4_DQ(62)';
NODE_NAME     J1A2 280
 '@BASEBOARD_FAB2_LIB.BASEBOARD_FAB2(SCH_1):PAGE85_I111@MSTR_SCONN.SCONN288_H44441004(CHIPS)':
 'DQ'<63>: CDS_PINID='DQ(63)';
NODE_NAME     J9L2 135
 '@BASEBOARD_FAB2_LIB.BASEBOARD_FAB2(SCH_1):PAGE86_I12@MSTR_SCONN.SCONN288_H44441003(CHIPS)':
 'DQ'<62>: CDS_PINID='DQ(62)';
NET_NAME
'M_L_DQ<63>'
 '@BASEBOARD_FAB2_LIB.BASEBOARD_FAB2(SCH_1):M_L_DQ'<63>:
 C_SIGNAL='@baseboard_fab2_lib.baseboard_fab2(sch_1):m_l_dq(63)';
NODE_NAME     U2D1 DK25
 '@BASEBOARD_FAB2_LIB.BASEBOARD_FAB2(SCH_1):PAGE61_I172@CHPSET_LIB.SKX_EXT_B(CHIPS)':
 'DDR4_DQ'<63>: CDS_PINID='DDR4_DQ(63)';
NODE_NAME     J1A2 135
 '@BASEBOARD_FAB2_LIB.BASEBOARD_FAB2(SCH_1):PAGE85_I111@MSTR_SCONN.SCONN288_H44441004(CHIPS)':
 'DQ'<62>: CDS_PINID='DQ(62)';
NODE_NAME     J9L2 280
 '@BASEBOARD_FAB2_LIB.BASEBOARD_FAB2(SCH_1):PAGE86_I12@MSTR_SCONN.SCONN288_H44441003(CHIPS)':
 'DQ'<63>: CDS_PINID='DQ(63)';
NET_NAME
'M_L_DQ<6>'
 '@BASEBOARD_FAB2_LIB.BASEBOARD_FAB2(SCH_1):M_L_DQ'<6>:
 C_SIGNAL='@baseboard_fab2_lib.baseboard_fab2(sch_1):m_l_dq(6)';
NODE_NAME     U2D1 CR80
 '@BASEBOARD_FAB2_LIB.BASEBOARD_FAB2(SCH_1):PAGE61_I172@CHPSET_LIB.SKX_EXT_B(CHIPS)':
 'DDR4_DQ'<6>: CDS_PINID='DDR4_DQ(6)';
NODE_NAME     J1A2 155
 '@BASEBOARD_FAB2_LIB.BASEBOARD_FAB2(SCH_1):PAGE85_I111@MSTR_SCONN.SCONN288_H44441004(CHIPS)':
 'DQ'<7>: CDS_PINID='DQ(7)';
NODE_NAME     J9L2 10
 '@BASEBOARD_FAB2_LIB.BASEBOARD_FAB2(SCH_1):PAGE86_I12@MSTR_SCONN.SCONN288_H44441003(CHIPS)':
 'DQ'<6>: CDS_PINID='DQ(6)';
NET_NAME
'M_L_DQ<7>'
 '@BASEBOARD_FAB2_LIB.BASEBOARD_FAB2(SCH_1):M_L_DQ'<7>:
 C_SIGNAL='@baseboard_fab2_lib.baseboard_fab2(sch_1):m_l_dq(7)';
NODE_NAME     U2D1 CN82
 '@BASEBOARD_FAB2_LIB.BASEBOARD_FAB2(SCH_1):PAGE61_I172@CHPSET_LIB.SKX_EXT_B(CHIPS)':
 'DDR4_DQ'<7>: CDS_PINID='DDR4_DQ(7)';
NODE_NAME     J1A2 10
 '@BASEBOARD_FAB2_LIB.BASEBOARD_FAB2(SCH_1):PAGE85_I111@MSTR_SCONN.SCONN288_H44441004(CHIPS)':
 'DQ'<6>: CDS_PINID='DQ(6)';
NODE_NAME     J9L2 155
 '@BASEBOARD_FAB2_LIB.BASEBOARD_FAB2(SCH_1):PAGE86_I12@MSTR_SCONN.SCONN288_H44441003(CHIPS)':
 'DQ'<7>: CDS_PINID='DQ(7)';
NET_NAME
'M_L_DQ<8>'
 '@BASEBOARD_FAB2_LIB.BASEBOARD_FAB2(SCH_1):M_L_DQ'<8>:
 C_SIGNAL='@baseboard_fab2_lib.baseboard_fab2(sch_1):m_l_dq(8)';
NODE_NAME     U2D1 DB79
 '@BASEBOARD_FAB2_LIB.BASEBOARD_FAB2(SCH_1):PAGE61_I172@CHPSET_LIB.SKX_EXT_B(CHIPS)':
 'DDR4_DQ'<8>: CDS_PINID='DDR4_DQ(8)';
NODE_NAME     J1A2 161
 '@BASEBOARD_FAB2_LIB.BASEBOARD_FAB2(SCH_1):PAGE85_I111@MSTR_SCONN.SCONN288_H44441004(CHIPS)':
 'DQ'<9>: CDS_PINID='DQ(9)';
NODE_NAME     J9L2 16
 '@BASEBOARD_FAB2_LIB.BASEBOARD_FAB2(SCH_1):PAGE86_I12@MSTR_SCONN.SCONN288_H44441003(CHIPS)':
 'DQ'<8>: CDS_PINID='DQ(8)';
NET_NAME
'M_L_DQ<9>'
 '@BASEBOARD_FAB2_LIB.BASEBOARD_FAB2(SCH_1):M_L_DQ'<9>:
 C_SIGNAL='@baseboard_fab2_lib.baseboard_fab2(sch_1):m_l_dq(9)';
NODE_NAME     U2D1 CY81
 '@BASEBOARD_FAB2_LIB.BASEBOARD_FAB2(SCH_1):PAGE61_I172@CHPSET_LIB.SKX_EXT_B(CHIPS)':
 'DDR4_DQ'<9>: CDS_PINID='DDR4_DQ(9)';
NODE_NAME     J1A2 16
 '@BASEBOARD_FAB2_LIB.BASEBOARD_FAB2(SCH_1):PAGE85_I111@MSTR_SCONN.SCONN288_H44441004(CHIPS)':
 'DQ'<8>: CDS_PINID='DQ(8)';
NODE_NAME     J9L2 161
 '@BASEBOARD_FAB2_LIB.BASEBOARD_FAB2(SCH_1):PAGE86_I12@MSTR_SCONN.SCONN288_H44441003(CHIPS)':
 'DQ'<9>: CDS_PINID='DQ(9)';
NET_NAME
'M_L_DQS_DN<0>'
 '@BASEBOARD_FAB2_LIB.BASEBOARD_FAB2(SCH_1):M_L_DQS_DN'<0>:
 C_SIGNAL='@baseboard_fab2_lib.baseboard_fab2(sch_1):m_l_dqs_dn(0)';
NODE_NAME     U2D1 CL82
 '@BASEBOARD_FAB2_LIB.BASEBOARD_FAB2(SCH_1):PAGE61_I172@CHPSET_LIB.SKX_EXT_B(CHIPS)':
 'DDR4_DQS_DN'<0>: CDS_PINID='DDR4_DQS_DN(0)';
NODE_NAME     J1A2 152
 '@BASEBOARD_FAB2_LIB.BASEBOARD_FAB2(SCH_1):PAGE85_I66@MSTR_SCONN.SCONN288_H44441004(CHIPS)':
 'DQS0N': CDS_PINID='DQS0N';
NODE_NAME     J9L2 152
 '@BASEBOARD_FAB2_LIB.BASEBOARD_FAB2(SCH_1):PAGE86_I100@MSTR_SCONN.SCONN288_H44441003(CHIPS)':
 'DQS0N': CDS_PINID='DQS0N';
NET_NAME
'M_L_DQS_DN<10>'
 '@BASEBOARD_FAB2_LIB.BASEBOARD_FAB2(SCH_1):M_L_DQS_DN'<10>:
 C_SIGNAL='@baseboard_fab2_lib.baseboard_fab2(sch_1):m_l_dqs_dn(10)';
NODE_NAME     U2D1 DC80
 '@BASEBOARD_FAB2_LIB.BASEBOARD_FAB2(SCH_1):PAGE61_I172@CHPSET_LIB.SKX_EXT_B(CHIPS)':
 'DDR4_DQS_DN'<10>: CDS_PINID='DDR4_DQS_DN(10)';
NODE_NAME     J1A2 19
 '@BASEBOARD_FAB2_LIB.BASEBOARD_FAB2(SCH_1):PAGE85_I66@MSTR_SCONN.SCONN288_H44441004(CHIPS)':
 'DQS10N': CDS_PINID='DQS10N';
NODE_NAME     J9L2 19
 '@BASEBOARD_FAB2_LIB.BASEBOARD_FAB2(SCH_1):PAGE86_I100@MSTR_SCONN.SCONN288_H44441003(CHIPS)':
 'DQS10N': CDS_PINID='DQS10N';
NET_NAME
'M_L_DQS_DN<11>'
 '@BASEBOARD_FAB2_LIB.BASEBOARD_FAB2(SCH_1):M_L_DQS_DN'<11>:
 C_SIGNAL='@baseboard_fab2_lib.baseboard_fab2(sch_1):m_l_dqs_dn(11)';
NODE_NAME     U2D1 DY79
 '@BASEBOARD_FAB2_LIB.BASEBOARD_FAB2(SCH_1):PAGE61_I172@CHPSET_LIB.SKX_EXT_B(CHIPS)':
 'DDR4_DQS_DN'<11>: CDS_PINID='DDR4_DQS_DN(11)';
NODE_NAME     J1A2 30
 '@BASEBOARD_FAB2_LIB.BASEBOARD_FAB2(SCH_1):PAGE85_I66@MSTR_SCONN.SCONN288_H44441004(CHIPS)':
 'DQS11N': CDS_PINID='DQS11N';
NODE_NAME     J9L2 30
 '@BASEBOARD_FAB2_LIB.BASEBOARD_FAB2(SCH_1):PAGE86_I100@MSTR_SCONN.SCONN288_H44441003(CHIPS)':
 'DQS11N': CDS_PINID='DQS11N';
NET_NAME
'M_L_DQS_DN<12>'
 '@BASEBOARD_FAB2_LIB.BASEBOARD_FAB2(SCH_1):M_L_DQS_DN'<12>:
 C_SIGNAL='@baseboard_fab2_lib.baseboard_fab2(sch_1):m_l_dqs_dn(12)';
NODE_NAME     U2D1 EB73
 '@BASEBOARD_FAB2_LIB.BASEBOARD_FAB2(SCH_1):PAGE61_I172@CHPSET_LIB.SKX_EXT_B(CHIPS)':
 'DDR4_DQS_DN'<12>: CDS_PINID='DDR4_DQS_DN(12)';
NODE_NAME     J1A2 41
 '@BASEBOARD_FAB2_LIB.BASEBOARD_FAB2(SCH_1):PAGE85_I66@MSTR_SCONN.SCONN288_H44441004(CHIPS)':
 'DQS12N': CDS_PINID='DQS12N';
NODE_NAME     J9L2 41
 '@BASEBOARD_FAB2_LIB.BASEBOARD_FAB2(SCH_1):PAGE86_I100@MSTR_SCONN.SCONN288_H44441003(CHIPS)':
 'DQS12N': CDS_PINID='DQS12N';
NET_NAME
'M_L_DQS_DN<13>'
 '@BASEBOARD_FAB2_LIB.BASEBOARD_FAB2(SCH_1):M_L_DQS_DN'<13>:
 C_SIGNAL='@baseboard_fab2_lib.baseboard_fab2(sch_1):m_l_dqs_dn(13)';
NODE_NAME     U2D1 DP41
 '@BASEBOARD_FAB2_LIB.BASEBOARD_FAB2(SCH_1):PAGE61_I172@CHPSET_LIB.SKX_EXT_B(CHIPS)':
 'DDR4_DQS_DN'<13>: CDS_PINID='DDR4_DQS_DN(13)';
NODE_NAME     J1A2 100
 '@BASEBOARD_FAB2_LIB.BASEBOARD_FAB2(SCH_1):PAGE85_I66@MSTR_SCONN.SCONN288_H44441004(CHIPS)':
 'DQS13N': CDS_PINID='DQS13N';
NODE_NAME     J9L2 100
 '@BASEBOARD_FAB2_LIB.BASEBOARD_FAB2(SCH_1):PAGE86_I100@MSTR_SCONN.SCONN288_H44441003(CHIPS)':
 'DQS13N': CDS_PINID='DQS13N';
NET_NAME
'M_L_DQS_DN<14>'
 '@BASEBOARD_FAB2_LIB.BASEBOARD_FAB2(SCH_1):M_L_DQS_DN'<14>:
 C_SIGNAL='@baseboard_fab2_lib.baseboard_fab2(sch_1):m_l_dqs_dn(14)';
NODE_NAME     U2D1 EA32
 '@BASEBOARD_FAB2_LIB.BASEBOARD_FAB2(SCH_1):PAGE61_I172@CHPSET_LIB.SKX_EXT_B(CHIPS)':
 'DDR4_DQS_DN'<14>: CDS_PINID='DDR4_DQS_DN(14)';
NODE_NAME     J1A2 111
 '@BASEBOARD_FAB2_LIB.BASEBOARD_FAB2(SCH_1):PAGE85_I66@MSTR_SCONN.SCONN288_H44441004(CHIPS)':
 'DQS14N': CDS_PINID='DQS14N';
NODE_NAME     J9L2 111
 '@BASEBOARD_FAB2_LIB.BASEBOARD_FAB2(SCH_1):PAGE86_I100@MSTR_SCONN.SCONN288_H44441003(CHIPS)':
 'DQS14N': CDS_PINID='DQS14N';
NET_NAME
'M_L_DQS_DN<15>'
 '@BASEBOARD_FAB2_LIB.BASEBOARD_FAB2(SCH_1):M_L_DQS_DN'<15>:
 C_SIGNAL='@baseboard_fab2_lib.baseboard_fab2(sch_1):m_l_dqs_dn(15)';
NODE_NAME     U2D1 EA26
 '@BASEBOARD_FAB2_LIB.BASEBOARD_FAB2(SCH_1):PAGE61_I172@CHPSET_LIB.SKX_EXT_B(CHIPS)':
 'DDR4_DQS_DN'<15>: CDS_PINID='DDR4_DQS_DN(15)';
NODE_NAME     J1A2 122
 '@BASEBOARD_FAB2_LIB.BASEBOARD_FAB2(SCH_1):PAGE85_I66@MSTR_SCONN.SCONN288_H44441004(CHIPS)':
 'DQS15N': CDS_PINID='DQS15N';
NODE_NAME     J9L2 122
 '@BASEBOARD_FAB2_LIB.BASEBOARD_FAB2(SCH_1):PAGE86_I100@MSTR_SCONN.SCONN288_H44441003(CHIPS)':
 'DQS15N': CDS_PINID='DQS15N';
NET_NAME
'M_L_DQS_DN<16>'
 '@BASEBOARD_FAB2_LIB.BASEBOARD_FAB2(SCH_1):M_L_DQS_DN'<16>:
 C_SIGNAL='@baseboard_fab2_lib.baseboard_fab2(sch_1):m_l_dqs_dn(16)';
NODE_NAME     U2D1 DG26
 '@BASEBOARD_FAB2_LIB.BASEBOARD_FAB2(SCH_1):PAGE61_I172@CHPSET_LIB.SKX_EXT_B(CHIPS)':
 'DDR4_DQS_DN'<16>: CDS_PINID='DDR4_DQS_DN(16)';
NODE_NAME     J1A2 133
 '@BASEBOARD_FAB2_LIB.BASEBOARD_FAB2(SCH_1):PAGE85_I66@MSTR_SCONN.SCONN288_H44441004(CHIPS)':
 'DQS16N': CDS_PINID='DQS16N';
NODE_NAME     J9L2 133
 '@BASEBOARD_FAB2_LIB.BASEBOARD_FAB2(SCH_1):PAGE86_I100@MSTR_SCONN.SCONN288_H44441003(CHIPS)':
 'DQS16N': CDS_PINID='DQS16N';
NET_NAME
'M_L_DQS_DN<17>'
 '@BASEBOARD_FAB2_LIB.BASEBOARD_FAB2(SCH_1):M_L_DQS_DN'<17>:
 C_SIGNAL='@baseboard_fab2_lib.baseboard_fab2(sch_1):m_l_dqs_dn(17)';
NODE_NAME     U2D1 DV67
 '@BASEBOARD_FAB2_LIB.BASEBOARD_FAB2(SCH_1):PAGE61_I172@CHPSET_LIB.SKX_EXT_B(CHIPS)':
 'DDR4_DQS_DN'<17>: CDS_PINID='DDR4_DQS_DN(17)';
NODE_NAME     J1A2 52
 '@BASEBOARD_FAB2_LIB.BASEBOARD_FAB2(SCH_1):PAGE85_I66@MSTR_SCONN.SCONN288_H44441004(CHIPS)':
 'DQS17N': CDS_PINID='DQS17N';
NODE_NAME     J9L2 52
 '@BASEBOARD_FAB2_LIB.BASEBOARD_FAB2(SCH_1):PAGE86_I100@MSTR_SCONN.SCONN288_H44441003(CHIPS)':
 'DQS17N': CDS_PINID='DQS17N';
NET_NAME
'M_L_DQS_DN<1>'
 '@BASEBOARD_FAB2_LIB.BASEBOARD_FAB2(SCH_1):M_L_DQS_DN'<1>:
 C_SIGNAL='@baseboard_fab2_lib.baseboard_fab2(sch_1):m_l_dqs_dn(1)';
NODE_NAME     U2D1 DA82
 '@BASEBOARD_FAB2_LIB.BASEBOARD_FAB2(SCH_1):PAGE61_I172@CHPSET_LIB.SKX_EXT_B(CHIPS)':
 'DDR4_DQS_DN'<1>: CDS_PINID='DDR4_DQS_DN(1)';
NODE_NAME     J1A2 163
 '@BASEBOARD_FAB2_LIB.BASEBOARD_FAB2(SCH_1):PAGE85_I66@MSTR_SCONN.SCONN288_H44441004(CHIPS)':
 'DQS1N': CDS_PINID='DQS1N';
NODE_NAME     J9L2 163
 '@BASEBOARD_FAB2_LIB.BASEBOARD_FAB2(SCH_1):PAGE86_I100@MSTR_SCONN.SCONN288_H44441003(CHIPS)':
 'DQS1N': CDS_PINID='DQS1N';
NET_NAME
'M_L_DQS_DN<2>'
 '@BASEBOARD_FAB2_LIB.BASEBOARD_FAB2(SCH_1):M_L_DQS_DN'<2>:
 C_SIGNAL='@baseboard_fab2_lib.baseboard_fab2(sch_1):m_l_dqs_dn(2)';
NODE_NAME     U2D1 ED79
 '@BASEBOARD_FAB2_LIB.BASEBOARD_FAB2(SCH_1):PAGE61_I172@CHPSET_LIB.SKX_EXT_B(CHIPS)':
 'DDR4_DQS_DN'<2>: CDS_PINID='DDR4_DQS_DN(2)';
NODE_NAME     J1A2 174
 '@BASEBOARD_FAB2_LIB.BASEBOARD_FAB2(SCH_1):PAGE85_I66@MSTR_SCONN.SCONN288_H44441004(CHIPS)':
 'DQS2N': CDS_PINID='DQS2N';
NODE_NAME     J9L2 174
 '@BASEBOARD_FAB2_LIB.BASEBOARD_FAB2(SCH_1):PAGE86_I100@MSTR_SCONN.SCONN288_H44441003(CHIPS)':
 'DQS2N': CDS_PINID='DQS2N';
NET_NAME
'M_L_DQS_DN<3>'
 '@BASEBOARD_FAB2_LIB.BASEBOARD_FAB2(SCH_1):M_L_DQS_DN'<3>:
 C_SIGNAL='@baseboard_fab2_lib.baseboard_fab2(sch_1):m_l_dqs_dn(3)';
NODE_NAME     U2D1 EF73
 '@BASEBOARD_FAB2_LIB.BASEBOARD_FAB2(SCH_1):PAGE61_I172@CHPSET_LIB.SKX_EXT_B(CHIPS)':
 'DDR4_DQS_DN'<3>: CDS_PINID='DDR4_DQS_DN(3)';
NODE_NAME     J1A2 185
 '@BASEBOARD_FAB2_LIB.BASEBOARD_FAB2(SCH_1):PAGE85_I66@MSTR_SCONN.SCONN288_H44441004(CHIPS)':
 'DQS3N': CDS_PINID='DQS3N';
NODE_NAME     J9L2 185
 '@BASEBOARD_FAB2_LIB.BASEBOARD_FAB2(SCH_1):PAGE86_I100@MSTR_SCONN.SCONN288_H44441003(CHIPS)':
 'DQS3N': CDS_PINID='DQS3N';
NET_NAME
'M_L_DQS_DN<4>'
 '@BASEBOARD_FAB2_LIB.BASEBOARD_FAB2(SCH_1):M_L_DQS_DN'<4>:
 C_SIGNAL='@baseboard_fab2_lib.baseboard_fab2(sch_1):m_l_dqs_dn(4)';
NODE_NAME     U2D1 DV41
 '@BASEBOARD_FAB2_LIB.BASEBOARD_FAB2(SCH_1):PAGE61_I172@CHPSET_LIB.SKX_EXT_B(CHIPS)':
 'DDR4_DQS_DN'<4>: CDS_PINID='DDR4_DQS_DN(4)';
NODE_NAME     J1A2 244
 '@BASEBOARD_FAB2_LIB.BASEBOARD_FAB2(SCH_1):PAGE85_I66@MSTR_SCONN.SCONN288_H44441004(CHIPS)':
 'DQS4N': CDS_PINID='DQS4N';
NODE_NAME     J9L2 244
 '@BASEBOARD_FAB2_LIB.BASEBOARD_FAB2(SCH_1):PAGE86_I100@MSTR_SCONN.SCONN288_H44441003(CHIPS)':
 'DQS4N': CDS_PINID='DQS4N';
NET_NAME
'M_L_DQS_DN<5>'
 '@BASEBOARD_FAB2_LIB.BASEBOARD_FAB2(SCH_1):M_L_DQS_DN'<5>:
 C_SIGNAL='@baseboard_fab2_lib.baseboard_fab2(sch_1):m_l_dqs_dn(5)';
NODE_NAME     U2D1 EE32
 '@BASEBOARD_FAB2_LIB.BASEBOARD_FAB2(SCH_1):PAGE61_I172@CHPSET_LIB.SKX_EXT_B(CHIPS)':
 'DDR4_DQS_DN'<5>: CDS_PINID='DDR4_DQS_DN(5)';
NODE_NAME     J1A2 255
 '@BASEBOARD_FAB2_LIB.BASEBOARD_FAB2(SCH_1):PAGE85_I66@MSTR_SCONN.SCONN288_H44441004(CHIPS)':
 'DQS5N': CDS_PINID='DQS5N';
NODE_NAME     J9L2 255
 '@BASEBOARD_FAB2_LIB.BASEBOARD_FAB2(SCH_1):PAGE86_I100@MSTR_SCONN.SCONN288_H44441003(CHIPS)':
 'DQS5N': CDS_PINID='DQS5N';
NET_NAME
'M_L_DQS_DN<6>'
 '@BASEBOARD_FAB2_LIB.BASEBOARD_FAB2(SCH_1):M_L_DQS_DN'<6>:
 C_SIGNAL='@baseboard_fab2_lib.baseboard_fab2(sch_1):m_l_dqs_dn(6)';
NODE_NAME     U2D1 EE26
 '@BASEBOARD_FAB2_LIB.BASEBOARD_FAB2(SCH_1):PAGE61_I172@CHPSET_LIB.SKX_EXT_B(CHIPS)':
 'DDR4_DQS_DN'<6>: CDS_PINID='DDR4_DQS_DN(6)';
NODE_NAME     J1A2 266
 '@BASEBOARD_FAB2_LIB.BASEBOARD_FAB2(SCH_1):PAGE85_I66@MSTR_SCONN.SCONN288_H44441004(CHIPS)':
 'DQS6N': CDS_PINID='DQS6N';
NODE_NAME     J9L2 266
 '@BASEBOARD_FAB2_LIB.BASEBOARD_FAB2(SCH_1):PAGE86_I100@MSTR_SCONN.SCONN288_H44441003(CHIPS)':
 'DQS6N': CDS_PINID='DQS6N';
NET_NAME
'M_L_DQS_DN<7>'
 '@BASEBOARD_FAB2_LIB.BASEBOARD_FAB2(SCH_1):M_L_DQS_DN'<7>:
 C_SIGNAL='@baseboard_fab2_lib.baseboard_fab2(sch_1):m_l_dqs_dn(7)';
NODE_NAME     U2D1 DL26
 '@BASEBOARD_FAB2_LIB.BASEBOARD_FAB2(SCH_1):PAGE61_I172@CHPSET_LIB.SKX_EXT_B(CHIPS)':
 'DDR4_DQS_DN'<7>: CDS_PINID='DDR4_DQS_DN(7)';
NODE_NAME     J1A2 277
 '@BASEBOARD_FAB2_LIB.BASEBOARD_FAB2(SCH_1):PAGE85_I66@MSTR_SCONN.SCONN288_H44441004(CHIPS)':
 'DQS7N': CDS_PINID='DQS7N';
NODE_NAME     J9L2 277
 '@BASEBOARD_FAB2_LIB.BASEBOARD_FAB2(SCH_1):PAGE86_I100@MSTR_SCONN.SCONN288_H44441003(CHIPS)':
 'DQS7N': CDS_PINID='DQS7N';
NET_NAME
'M_L_DQS_DN<8>'
 '@BASEBOARD_FAB2_LIB.BASEBOARD_FAB2(SCH_1):M_L_DQS_DN'<8>:
 C_SIGNAL='@baseboard_fab2_lib.baseboard_fab2(sch_1):m_l_dqs_dn(8)';
NODE_NAME     U2D1 EB67
 '@BASEBOARD_FAB2_LIB.BASEBOARD_FAB2(SCH_1):PAGE61_I172@CHPSET_LIB.SKX_EXT_B(CHIPS)':
 'DDR4_DQS_DN'<8>: CDS_PINID='DDR4_DQS_DN(8)';
NODE_NAME     J1A2 196
 '@BASEBOARD_FAB2_LIB.BASEBOARD_FAB2(SCH_1):PAGE85_I66@MSTR_SCONN.SCONN288_H44441004(CHIPS)':
 'DQS8N': CDS_PINID='DQS8N';
NODE_NAME     J9L2 196
 '@BASEBOARD_FAB2_LIB.BASEBOARD_FAB2(SCH_1):PAGE86_I100@MSTR_SCONN.SCONN288_H44441003(CHIPS)':
 'DQS8N': CDS_PINID='DQS8N';
NET_NAME
'M_L_DQS_DN<9>'
 '@BASEBOARD_FAB2_LIB.BASEBOARD_FAB2(SCH_1):M_L_DQS_DN'<9>:
 C_SIGNAL='@baseboard_fab2_lib.baseboard_fab2(sch_1):m_l_dqs_dn(9)';
NODE_NAME     U2D1 CN80
 '@BASEBOARD_FAB2_LIB.BASEBOARD_FAB2(SCH_1):PAGE61_I172@CHPSET_LIB.SKX_EXT_B(CHIPS)':
 'DDR4_DQS_DN'<9>: CDS_PINID='DDR4_DQS_DN(9)';
NODE_NAME     J1A2 8
 '@BASEBOARD_FAB2_LIB.BASEBOARD_FAB2(SCH_1):PAGE85_I66@MSTR_SCONN.SCONN288_H44441004(CHIPS)':
 'DQS9N': CDS_PINID='DQS9N';
NODE_NAME     J9L2 8
 '@BASEBOARD_FAB2_LIB.BASEBOARD_FAB2(SCH_1):PAGE86_I100@MSTR_SCONN.SCONN288_H44441003(CHIPS)':
 'DQS9N': CDS_PINID='DQS9N';
NET_NAME
'M_L_DQS_DP<0>'
 '@BASEBOARD_FAB2_LIB.BASEBOARD_FAB2(SCH_1):M_L_DQS_DP'<0>:
 C_SIGNAL='@baseboard_fab2_lib.baseboard_fab2(sch_1):m_l_dqs_dp(0)';
NODE_NAME     U2D1 CM81
 '@BASEBOARD_FAB2_LIB.BASEBOARD_FAB2(SCH_1):PAGE61_I172@CHPSET_LIB.SKX_EXT_B(CHIPS)':
 'DDR4_DQS_DP'<0>: CDS_PINID='DDR4_DQS_DP(0)';
NODE_NAME     J1A2 153
 '@BASEBOARD_FAB2_LIB.BASEBOARD_FAB2(SCH_1):PAGE85_I66@MSTR_SCONN.SCONN288_H44441004(CHIPS)':
 'DQS0P': CDS_PINID='DQS0P';
NODE_NAME     J9L2 153
 '@BASEBOARD_FAB2_LIB.BASEBOARD_FAB2(SCH_1):PAGE86_I100@MSTR_SCONN.SCONN288_H44441003(CHIPS)':
 'DQS0P': CDS_PINID='DQS0P';
NET_NAME
'M_L_DQS_DP<10>'
 '@BASEBOARD_FAB2_LIB.BASEBOARD_FAB2(SCH_1):M_L_DQS_DP'<10>:
 C_SIGNAL='@baseboard_fab2_lib.baseboard_fab2(sch_1):m_l_dqs_dp(10)';
NODE_NAME     U2D1 DD79
 '@BASEBOARD_FAB2_LIB.BASEBOARD_FAB2(SCH_1):PAGE61_I172@CHPSET_LIB.SKX_EXT_B(CHIPS)':
 'DDR4_DQS_DP'<10>: CDS_PINID='DDR4_DQS_DP(10)';
NODE_NAME     J1A2 18
 '@BASEBOARD_FAB2_LIB.BASEBOARD_FAB2(SCH_1):PAGE85_I66@MSTR_SCONN.SCONN288_H44441004(CHIPS)':
 'DQS10P': CDS_PINID='DQS10P';
NODE_NAME     J9L2 18
 '@BASEBOARD_FAB2_LIB.BASEBOARD_FAB2(SCH_1):PAGE86_I100@MSTR_SCONN.SCONN288_H44441003(CHIPS)':
 'DQS10P': CDS_PINID='DQS10P';
NET_NAME
'M_L_DQS_DP<11>'
 '@BASEBOARD_FAB2_LIB.BASEBOARD_FAB2(SCH_1):M_L_DQS_DP'<11>:
 C_SIGNAL='@baseboard_fab2_lib.baseboard_fab2(sch_1):m_l_dqs_dp(11)';
NODE_NAME     U2D1 DV79
 '@BASEBOARD_FAB2_LIB.BASEBOARD_FAB2(SCH_1):PAGE61_I172@CHPSET_LIB.SKX_EXT_B(CHIPS)':
 'DDR4_DQS_DP'<11>: CDS_PINID='DDR4_DQS_DP(11)';
NODE_NAME     J1A2 29
 '@BASEBOARD_FAB2_LIB.BASEBOARD_FAB2(SCH_1):PAGE85_I66@MSTR_SCONN.SCONN288_H44441004(CHIPS)':
 'DQS11P': CDS_PINID='DQS11P';
NODE_NAME     J9L2 29
 '@BASEBOARD_FAB2_LIB.BASEBOARD_FAB2(SCH_1):PAGE86_I100@MSTR_SCONN.SCONN288_H44441003(CHIPS)':
 'DQS11P': CDS_PINID='DQS11P';
NET_NAME
'M_L_DQS_DP<12>'
 '@BASEBOARD_FAB2_LIB.BASEBOARD_FAB2(SCH_1):M_L_DQS_DP'<12>:
 C_SIGNAL='@baseboard_fab2_lib.baseboard_fab2(sch_1):m_l_dqs_dp(12)';
NODE_NAME     U2D1 DY73
 '@BASEBOARD_FAB2_LIB.BASEBOARD_FAB2(SCH_1):PAGE61_I172@CHPSET_LIB.SKX_EXT_B(CHIPS)':
 'DDR4_DQS_DP'<12>: CDS_PINID='DDR4_DQS_DP(12)';
NODE_NAME     J1A2 40
 '@BASEBOARD_FAB2_LIB.BASEBOARD_FAB2(SCH_1):PAGE85_I66@MSTR_SCONN.SCONN288_H44441004(CHIPS)':
 'DQS12P': CDS_PINID='DQS12P';
NODE_NAME     J9L2 40
 '@BASEBOARD_FAB2_LIB.BASEBOARD_FAB2(SCH_1):PAGE86_I100@MSTR_SCONN.SCONN288_H44441003(CHIPS)':
 'DQS12P': CDS_PINID='DQS12P';
NET_NAME
'M_L_DQS_DP<13>'
 '@BASEBOARD_FAB2_LIB.BASEBOARD_FAB2(SCH_1):M_L_DQS_DP'<13>:
 C_SIGNAL='@baseboard_fab2_lib.baseboard_fab2(sch_1):m_l_dqs_dp(13)';
NODE_NAME     U2D1 DM41
 '@BASEBOARD_FAB2_LIB.BASEBOARD_FAB2(SCH_1):PAGE61_I172@CHPSET_LIB.SKX_EXT_B(CHIPS)':
 'DDR4_DQS_DP'<13>: CDS_PINID='DDR4_DQS_DP(13)';
NODE_NAME     J1A2 99
 '@BASEBOARD_FAB2_LIB.BASEBOARD_FAB2(SCH_1):PAGE85_I66@MSTR_SCONN.SCONN288_H44441004(CHIPS)':
 'DQS13P': CDS_PINID='DQS13P';
NODE_NAME     J9L2 99
 '@BASEBOARD_FAB2_LIB.BASEBOARD_FAB2(SCH_1):PAGE86_I100@MSTR_SCONN.SCONN288_H44441003(CHIPS)':
 'DQS13P': CDS_PINID='DQS13P';
NET_NAME
'M_L_DQS_DP<14>'
 '@BASEBOARD_FAB2_LIB.BASEBOARD_FAB2(SCH_1):M_L_DQS_DP'<14>:
 C_SIGNAL='@baseboard_fab2_lib.baseboard_fab2(sch_1):m_l_dqs_dp(14)';
NODE_NAME     U2D1 DW32
 '@BASEBOARD_FAB2_LIB.BASEBOARD_FAB2(SCH_1):PAGE61_I172@CHPSET_LIB.SKX_EXT_B(CHIPS)':
 'DDR4_DQS_DP'<14>: CDS_PINID='DDR4_DQS_DP(14)';
NODE_NAME     J1A2 110
 '@BASEBOARD_FAB2_LIB.BASEBOARD_FAB2(SCH_1):PAGE85_I66@MSTR_SCONN.SCONN288_H44441004(CHIPS)':
 'DQS14P': CDS_PINID='DQS14P';
NODE_NAME     J9L2 110
 '@BASEBOARD_FAB2_LIB.BASEBOARD_FAB2(SCH_1):PAGE86_I100@MSTR_SCONN.SCONN288_H44441003(CHIPS)':
 'DQS14P': CDS_PINID='DQS14P';
NET_NAME
'M_L_DQS_DP<15>'
 '@BASEBOARD_FAB2_LIB.BASEBOARD_FAB2(SCH_1):M_L_DQS_DP'<15>:
 C_SIGNAL='@baseboard_fab2_lib.baseboard_fab2(sch_1):m_l_dqs_dp(15)';
NODE_NAME     U2D1 DW26
 '@BASEBOARD_FAB2_LIB.BASEBOARD_FAB2(SCH_1):PAGE61_I172@CHPSET_LIB.SKX_EXT_B(CHIPS)':
 'DDR4_DQS_DP'<15>: CDS_PINID='DDR4_DQS_DP(15)';
NODE_NAME     J1A2 121
 '@BASEBOARD_FAB2_LIB.BASEBOARD_FAB2(SCH_1):PAGE85_I66@MSTR_SCONN.SCONN288_H44441004(CHIPS)':
 'DQS15P': CDS_PINID='DQS15P';
NODE_NAME     J9L2 121
 '@BASEBOARD_FAB2_LIB.BASEBOARD_FAB2(SCH_1):PAGE86_I100@MSTR_SCONN.SCONN288_H44441003(CHIPS)':
 'DQS15P': CDS_PINID='DQS15P';
NET_NAME
'M_L_DQS_DP<16>'
 '@BASEBOARD_FAB2_LIB.BASEBOARD_FAB2(SCH_1):M_L_DQS_DP'<16>:
 C_SIGNAL='@baseboard_fab2_lib.baseboard_fab2(sch_1):m_l_dqs_dp(16)';
NODE_NAME     U2D1 DE26
 '@BASEBOARD_FAB2_LIB.BASEBOARD_FAB2(SCH_1):PAGE61_I172@CHPSET_LIB.SKX_EXT_B(CHIPS)':
 'DDR4_DQS_DP'<16>: CDS_PINID='DDR4_DQS_DP(16)';
NODE_NAME     J1A2 132
 '@BASEBOARD_FAB2_LIB.BASEBOARD_FAB2(SCH_1):PAGE85_I66@MSTR_SCONN.SCONN288_H44441004(CHIPS)':
 'DQS16P': CDS_PINID='DQS16P';
NODE_NAME     J9L2 132
 '@BASEBOARD_FAB2_LIB.BASEBOARD_FAB2(SCH_1):PAGE86_I100@MSTR_SCONN.SCONN288_H44441003(CHIPS)':
 'DQS16P': CDS_PINID='DQS16P';
NET_NAME
'M_L_DQS_DP<17>'
 '@BASEBOARD_FAB2_LIB.BASEBOARD_FAB2(SCH_1):M_L_DQS_DP'<17>:
 C_SIGNAL='@baseboard_fab2_lib.baseboard_fab2(sch_1):m_l_dqs_dp(17)';
NODE_NAME     U2D1 DT67
 '@BASEBOARD_FAB2_LIB.BASEBOARD_FAB2(SCH_1):PAGE61_I172@CHPSET_LIB.SKX_EXT_B(CHIPS)':
 'DDR4_DQS_DP'<17>: CDS_PINID='DDR4_DQS_DP(17)';
NODE_NAME     J1A2 51
 '@BASEBOARD_FAB2_LIB.BASEBOARD_FAB2(SCH_1):PAGE85_I66@MSTR_SCONN.SCONN288_H44441004(CHIPS)':
 'DQS17P': CDS_PINID='DQS17P';
NODE_NAME     J9L2 51
 '@BASEBOARD_FAB2_LIB.BASEBOARD_FAB2(SCH_1):PAGE86_I100@MSTR_SCONN.SCONN288_H44441003(CHIPS)':
 'DQS17P': CDS_PINID='DQS17P';
NET_NAME
'M_L_DQS_DP<1>'
 '@BASEBOARD_FAB2_LIB.BASEBOARD_FAB2(SCH_1):M_L_DQS_DP'<1>:
 C_SIGNAL='@baseboard_fab2_lib.baseboard_fab2(sch_1):m_l_dqs_dp(1)';
NODE_NAME     U2D1 DB81
 '@BASEBOARD_FAB2_LIB.BASEBOARD_FAB2(SCH_1):PAGE61_I172@CHPSET_LIB.SKX_EXT_B(CHIPS)':
 'DDR4_DQS_DP'<1>: CDS_PINID='DDR4_DQS_DP(1)';
NODE_NAME     J1A2 164
 '@BASEBOARD_FAB2_LIB.BASEBOARD_FAB2(SCH_1):PAGE85_I66@MSTR_SCONN.SCONN288_H44441004(CHIPS)':
 'DQS1P': CDS_PINID='DQS1P';
NODE_NAME     J9L2 164
 '@BASEBOARD_FAB2_LIB.BASEBOARD_FAB2(SCH_1):PAGE86_I100@MSTR_SCONN.SCONN288_H44441003(CHIPS)':
 'DQS1P': CDS_PINID='DQS1P';
NET_NAME
'M_L_DQS_DP<2>'
 '@BASEBOARD_FAB2_LIB.BASEBOARD_FAB2(SCH_1):M_L_DQS_DP'<2>:
 C_SIGNAL='@baseboard_fab2_lib.baseboard_fab2(sch_1):m_l_dqs_dp(2)';
NODE_NAME     U2D1 EB79
 '@BASEBOARD_FAB2_LIB.BASEBOARD_FAB2(SCH_1):PAGE61_I172@CHPSET_LIB.SKX_EXT_B(CHIPS)':
 'DDR4_DQS_DP'<2>: CDS_PINID='DDR4_DQS_DP(2)';
NODE_NAME     J1A2 175
 '@BASEBOARD_FAB2_LIB.BASEBOARD_FAB2(SCH_1):PAGE85_I66@MSTR_SCONN.SCONN288_H44441004(CHIPS)':
 'DQS2P': CDS_PINID='DQS2P';
NODE_NAME     J9L2 175
 '@BASEBOARD_FAB2_LIB.BASEBOARD_FAB2(SCH_1):PAGE86_I100@MSTR_SCONN.SCONN288_H44441003(CHIPS)':
 'DQS2P': CDS_PINID='DQS2P';
NET_NAME
'M_L_DQS_DP<3>'
 '@BASEBOARD_FAB2_LIB.BASEBOARD_FAB2(SCH_1):M_L_DQS_DP'<3>:
 C_SIGNAL='@baseboard_fab2_lib.baseboard_fab2(sch_1):m_l_dqs_dp(3)';
NODE_NAME     U2D1 ED73
 '@BASEBOARD_FAB2_LIB.BASEBOARD_FAB2(SCH_1):PAGE61_I172@CHPSET_LIB.SKX_EXT_B(CHIPS)':
 'DDR4_DQS_DP'<3>: CDS_PINID='DDR4_DQS_DP(3)';
NODE_NAME     J1A2 186
 '@BASEBOARD_FAB2_LIB.BASEBOARD_FAB2(SCH_1):PAGE85_I66@MSTR_SCONN.SCONN288_H44441004(CHIPS)':
 'DQS3P': CDS_PINID='DQS3P';
NODE_NAME     J9L2 186
 '@BASEBOARD_FAB2_LIB.BASEBOARD_FAB2(SCH_1):PAGE86_I100@MSTR_SCONN.SCONN288_H44441003(CHIPS)':
 'DQS3P': CDS_PINID='DQS3P';
NET_NAME
'M_L_DQS_DP<4>'
 '@BASEBOARD_FAB2_LIB.BASEBOARD_FAB2(SCH_1):M_L_DQS_DP'<4>:
 C_SIGNAL='@baseboard_fab2_lib.baseboard_fab2(sch_1):m_l_dqs_dp(4)';
NODE_NAME     U2D1 DT41
 '@BASEBOARD_FAB2_LIB.BASEBOARD_FAB2(SCH_1):PAGE61_I172@CHPSET_LIB.SKX_EXT_B(CHIPS)':
 'DDR4_DQS_DP'<4>: CDS_PINID='DDR4_DQS_DP(4)';
NODE_NAME     J1A2 245
 '@BASEBOARD_FAB2_LIB.BASEBOARD_FAB2(SCH_1):PAGE85_I66@MSTR_SCONN.SCONN288_H44441004(CHIPS)':
 'DQS4P': CDS_PINID='DQS4P';
NODE_NAME     J9L2 245
 '@BASEBOARD_FAB2_LIB.BASEBOARD_FAB2(SCH_1):PAGE86_I100@MSTR_SCONN.SCONN288_H44441003(CHIPS)':
 'DQS4P': CDS_PINID='DQS4P';
NET_NAME
'M_L_DQS_DP<5>'
 '@BASEBOARD_FAB2_LIB.BASEBOARD_FAB2(SCH_1):M_L_DQS_DP'<5>:
 C_SIGNAL='@baseboard_fab2_lib.baseboard_fab2(sch_1):m_l_dqs_dp(5)';
NODE_NAME     U2D1 EC32
 '@BASEBOARD_FAB2_LIB.BASEBOARD_FAB2(SCH_1):PAGE61_I172@CHPSET_LIB.SKX_EXT_B(CHIPS)':
 'DDR4_DQS_DP'<5>: CDS_PINID='DDR4_DQS_DP(5)';
NODE_NAME     J1A2 256
 '@BASEBOARD_FAB2_LIB.BASEBOARD_FAB2(SCH_1):PAGE85_I66@MSTR_SCONN.SCONN288_H44441004(CHIPS)':
 'DQS5P': CDS_PINID='DQS5P';
NODE_NAME     J9L2 256
 '@BASEBOARD_FAB2_LIB.BASEBOARD_FAB2(SCH_1):PAGE86_I100@MSTR_SCONN.SCONN288_H44441003(CHIPS)':
 'DQS5P': CDS_PINID='DQS5P';
NET_NAME
'M_L_DQS_DP<6>'
 '@BASEBOARD_FAB2_LIB.BASEBOARD_FAB2(SCH_1):M_L_DQS_DP'<6>:
 C_SIGNAL='@baseboard_fab2_lib.baseboard_fab2(sch_1):m_l_dqs_dp(6)';
NODE_NAME     U2D1 EC26
 '@BASEBOARD_FAB2_LIB.BASEBOARD_FAB2(SCH_1):PAGE61_I172@CHPSET_LIB.SKX_EXT_B(CHIPS)':
 'DDR4_DQS_DP'<6>: CDS_PINID='DDR4_DQS_DP(6)';
NODE_NAME     J1A2 267
 '@BASEBOARD_FAB2_LIB.BASEBOARD_FAB2(SCH_1):PAGE85_I66@MSTR_SCONN.SCONN288_H44441004(CHIPS)':
 'DQS6P': CDS_PINID='DQS6P';
NODE_NAME     J9L2 267
 '@BASEBOARD_FAB2_LIB.BASEBOARD_FAB2(SCH_1):PAGE86_I100@MSTR_SCONN.SCONN288_H44441003(CHIPS)':
 'DQS6P': CDS_PINID='DQS6P';
NET_NAME
'M_L_DQS_DP<7>'
 '@BASEBOARD_FAB2_LIB.BASEBOARD_FAB2(SCH_1):M_L_DQS_DP'<7>:
 C_SIGNAL='@baseboard_fab2_lib.baseboard_fab2(sch_1):m_l_dqs_dp(7)';
NODE_NAME     U2D1 DJ26
 '@BASEBOARD_FAB2_LIB.BASEBOARD_FAB2(SCH_1):PAGE61_I172@CHPSET_LIB.SKX_EXT_B(CHIPS)':
 'DDR4_DQS_DP'<7>: CDS_PINID='DDR4_DQS_DP(7)';
NODE_NAME     J1A2 278
 '@BASEBOARD_FAB2_LIB.BASEBOARD_FAB2(SCH_1):PAGE85_I66@MSTR_SCONN.SCONN288_H44441004(CHIPS)':
 'DQS7P': CDS_PINID='DQS7P';
NODE_NAME     J9L2 278
 '@BASEBOARD_FAB2_LIB.BASEBOARD_FAB2(SCH_1):PAGE86_I100@MSTR_SCONN.SCONN288_H44441003(CHIPS)':
 'DQS7P': CDS_PINID='DQS7P';
NET_NAME
'M_L_DQS_DP<8>'
 '@BASEBOARD_FAB2_LIB.BASEBOARD_FAB2(SCH_1):M_L_DQS_DP'<8>:
 C_SIGNAL='@baseboard_fab2_lib.baseboard_fab2(sch_1):m_l_dqs_dp(8)';
NODE_NAME     U2D1 DY67
 '@BASEBOARD_FAB2_LIB.BASEBOARD_FAB2(SCH_1):PAGE61_I172@CHPSET_LIB.SKX_EXT_B(CHIPS)':
 'DDR4_DQS_DP'<8>: CDS_PINID='DDR4_DQS_DP(8)';
NODE_NAME     J1A2 197
 '@BASEBOARD_FAB2_LIB.BASEBOARD_FAB2(SCH_1):PAGE85_I66@MSTR_SCONN.SCONN288_H44441004(CHIPS)':
 'DQS8P': CDS_PINID='DQS8P';
NODE_NAME     J9L2 197
 '@BASEBOARD_FAB2_LIB.BASEBOARD_FAB2(SCH_1):PAGE86_I100@MSTR_SCONN.SCONN288_H44441003(CHIPS)':
 'DQS8P': CDS_PINID='DQS8P';
NET_NAME
'M_L_DQS_DP<9>'
 '@BASEBOARD_FAB2_LIB.BASEBOARD_FAB2(SCH_1):M_L_DQS_DP'<9>:
 C_SIGNAL='@baseboard_fab2_lib.baseboard_fab2(sch_1):m_l_dqs_dp(9)';
NODE_NAME     U2D1 CP79
 '@BASEBOARD_FAB2_LIB.BASEBOARD_FAB2(SCH_1):PAGE61_I172@CHPSET_LIB.SKX_EXT_B(CHIPS)':
 'DDR4_DQS_DP'<9>: CDS_PINID='DDR4_DQS_DP(9)';
NODE_NAME     J1A2 7
 '@BASEBOARD_FAB2_LIB.BASEBOARD_FAB2(SCH_1):PAGE85_I66@MSTR_SCONN.SCONN288_H44441004(CHIPS)':
 'DQS9P': CDS_PINID='DQS9P';
NODE_NAME     J9L2 7
 '@BASEBOARD_FAB2_LIB.BASEBOARD_FAB2(SCH_1):PAGE86_I100@MSTR_SCONN.SCONN288_H44441003(CHIPS)':
 'DQS9P': CDS_PINID='DQS9P';
NET_NAME
'M_L_ECC<0>'
 '@BASEBOARD_FAB2_LIB.BASEBOARD_FAB2(SCH_1):M_L_ECC'<0>:
 C_SIGNAL='@baseboard_fab2_lib.baseboard_fab2(sch_1):m_l_ecc(0)';
NODE_NAME     U2D1 DY69
 '@BASEBOARD_FAB2_LIB.BASEBOARD_FAB2(SCH_1):PAGE61_I172@CHPSET_LIB.SKX_EXT_B(CHIPS)':
 'DDR4_ECC'<0>: CDS_PINID='DDR4_ECC(0)';
NODE_NAME     J1A2 194
 '@BASEBOARD_FAB2_LIB.BASEBOARD_FAB2(SCH_1):PAGE85_I111@MSTR_SCONN.SCONN288_H44441004(CHIPS)':
 'CB'<1>: CDS_PINID='CB(1)';
NODE_NAME     J9L2 49
 '@BASEBOARD_FAB2_LIB.BASEBOARD_FAB2(SCH_1):PAGE86_I12@MSTR_SCONN.SCONN288_H44441003(CHIPS)':
 'CB'<0>: CDS_PINID='CB(0)';
NET_NAME
'M_L_ECC<1>'
 '@BASEBOARD_FAB2_LIB.BASEBOARD_FAB2(SCH_1):M_L_ECC'<1>:
 C_SIGNAL='@baseboard_fab2_lib.baseboard_fab2(sch_1):m_l_ecc(1)';
NODE_NAME     U2D1 EA68
 '@BASEBOARD_FAB2_LIB.BASEBOARD_FAB2(SCH_1):PAGE61_I172@CHPSET_LIB.SKX_EXT_B(CHIPS)':
 'DDR4_ECC'<1>: CDS_PINID='DDR4_ECC(1)';
NODE_NAME     J1A2 49
 '@BASEBOARD_FAB2_LIB.BASEBOARD_FAB2(SCH_1):PAGE85_I111@MSTR_SCONN.SCONN288_H44441004(CHIPS)':
 'CB'<0>: CDS_PINID='CB(0)';
NODE_NAME     J9L2 194
 '@BASEBOARD_FAB2_LIB.BASEBOARD_FAB2(SCH_1):PAGE86_I12@MSTR_SCONN.SCONN288_H44441003(CHIPS)':
 'CB'<1>: CDS_PINID='CB(1)';
NET_NAME
'M_L_ECC<2>'
 '@BASEBOARD_FAB2_LIB.BASEBOARD_FAB2(SCH_1):M_L_ECC'<2>:
 C_SIGNAL='@baseboard_fab2_lib.baseboard_fab2(sch_1):m_l_ecc(2)';
NODE_NAME     U2D1 DV65
 '@BASEBOARD_FAB2_LIB.BASEBOARD_FAB2(SCH_1):PAGE61_I172@CHPSET_LIB.SKX_EXT_B(CHIPS)':
 'DDR4_ECC'<2>: CDS_PINID='DDR4_ECC(2)';
NODE_NAME     J1A2 201
 '@BASEBOARD_FAB2_LIB.BASEBOARD_FAB2(SCH_1):PAGE85_I111@MSTR_SCONN.SCONN288_H44441004(CHIPS)':
 'CB'<3>: CDS_PINID='CB(3)';
NODE_NAME     J9L2 56
 '@BASEBOARD_FAB2_LIB.BASEBOARD_FAB2(SCH_1):PAGE86_I12@MSTR_SCONN.SCONN288_H44441003(CHIPS)':
 'CB'<2>: CDS_PINID='CB(2)';
NET_NAME
'M_L_ECC<3>'
 '@BASEBOARD_FAB2_LIB.BASEBOARD_FAB2(SCH_1):M_L_ECC'<3>:
 C_SIGNAL='@baseboard_fab2_lib.baseboard_fab2(sch_1):m_l_ecc(3)';
NODE_NAME     U2D1 DY65
 '@BASEBOARD_FAB2_LIB.BASEBOARD_FAB2(SCH_1):PAGE61_I172@CHPSET_LIB.SKX_EXT_B(CHIPS)':
 'DDR4_ECC'<3>: CDS_PINID='DDR4_ECC(3)';
NODE_NAME     J1A2 56
 '@BASEBOARD_FAB2_LIB.BASEBOARD_FAB2(SCH_1):PAGE85_I111@MSTR_SCONN.SCONN288_H44441004(CHIPS)':
 'CB'<2>: CDS_PINID='CB(2)';
NODE_NAME     J9L2 201
 '@BASEBOARD_FAB2_LIB.BASEBOARD_FAB2(SCH_1):PAGE86_I12@MSTR_SCONN.SCONN288_H44441003(CHIPS)':
 'CB'<3>: CDS_PINID='CB(3)';
NET_NAME
'M_L_ECC<4>'
 '@BASEBOARD_FAB2_LIB.BASEBOARD_FAB2(SCH_1):M_L_ECC'<4>:
 C_SIGNAL='@baseboard_fab2_lib.baseboard_fab2(sch_1):m_l_ecc(4)';
NODE_NAME     U2D1 DU68
 '@BASEBOARD_FAB2_LIB.BASEBOARD_FAB2(SCH_1):PAGE61_I172@CHPSET_LIB.SKX_EXT_B(CHIPS)':
 'DDR4_ECC'<4>: CDS_PINID='DDR4_ECC(4)';
NODE_NAME     J1A2 192
 '@BASEBOARD_FAB2_LIB.BASEBOARD_FAB2(SCH_1):PAGE85_I111@MSTR_SCONN.SCONN288_H44441004(CHIPS)':
 'CB'<5>: CDS_PINID='CB(5)';
NODE_NAME     J9L2 47
 '@BASEBOARD_FAB2_LIB.BASEBOARD_FAB2(SCH_1):PAGE86_I12@MSTR_SCONN.SCONN288_H44441003(CHIPS)':
 'CB'<4>: CDS_PINID='CB(4)';
NET_NAME
'M_L_ECC<5>'
 '@BASEBOARD_FAB2_LIB.BASEBOARD_FAB2(SCH_1):M_L_ECC'<5>:
 C_SIGNAL='@baseboard_fab2_lib.baseboard_fab2(sch_1):m_l_ecc(5)';
NODE_NAME     U2D1 DV69
 '@BASEBOARD_FAB2_LIB.BASEBOARD_FAB2(SCH_1):PAGE61_I172@CHPSET_LIB.SKX_EXT_B(CHIPS)':
 'DDR4_ECC'<5>: CDS_PINID='DDR4_ECC(5)';
NODE_NAME     J1A2 47
 '@BASEBOARD_FAB2_LIB.BASEBOARD_FAB2(SCH_1):PAGE85_I111@MSTR_SCONN.SCONN288_H44441004(CHIPS)':
 'CB'<4>: CDS_PINID='CB(4)';
NODE_NAME     J9L2 192
 '@BASEBOARD_FAB2_LIB.BASEBOARD_FAB2(SCH_1):PAGE86_I12@MSTR_SCONN.SCONN288_H44441003(CHIPS)':
 'CB'<5>: CDS_PINID='CB(5)';
NET_NAME
'M_L_ECC<6>'
 '@BASEBOARD_FAB2_LIB.BASEBOARD_FAB2(SCH_1):M_L_ECC'<6>:
 C_SIGNAL='@baseboard_fab2_lib.baseboard_fab2(sch_1):m_l_ecc(6)';
NODE_NAME     U2D1 DU66
 '@BASEBOARD_FAB2_LIB.BASEBOARD_FAB2(SCH_1):PAGE61_I172@CHPSET_LIB.SKX_EXT_B(CHIPS)':
 'DDR4_ECC'<6>: CDS_PINID='DDR4_ECC(6)';
NODE_NAME     J1A2 199
 '@BASEBOARD_FAB2_LIB.BASEBOARD_FAB2(SCH_1):PAGE85_I111@MSTR_SCONN.SCONN288_H44441004(CHIPS)':
 'CB'<7>: CDS_PINID='CB(7)';
NODE_NAME     J9L2 54
 '@BASEBOARD_FAB2_LIB.BASEBOARD_FAB2(SCH_1):PAGE86_I12@MSTR_SCONN.SCONN288_H44441003(CHIPS)':
 'CB'<6>: CDS_PINID='CB(6)';
NET_NAME
'M_L_ECC<7>'
 '@BASEBOARD_FAB2_LIB.BASEBOARD_FAB2(SCH_1):M_L_ECC'<7>:
 C_SIGNAL='@baseboard_fab2_lib.baseboard_fab2(sch_1):m_l_ecc(7)';
NODE_NAME     U2D1 EA66
 '@BASEBOARD_FAB2_LIB.BASEBOARD_FAB2(SCH_1):PAGE61_I172@CHPSET_LIB.SKX_EXT_B(CHIPS)':
 'DDR4_ECC'<7>: CDS_PINID='DDR4_ECC(7)';
NODE_NAME     J1A2 54
 '@BASEBOARD_FAB2_LIB.BASEBOARD_FAB2(SCH_1):PAGE85_I111@MSTR_SCONN.SCONN288_H44441004(CHIPS)':
 'CB'<6>: CDS_PINID='CB(6)';
NODE_NAME     J9L2 199
 '@BASEBOARD_FAB2_LIB.BASEBOARD_FAB2(SCH_1):PAGE86_I12@MSTR_SCONN.SCONN288_H44441003(CHIPS)':
 'CB'<7>: CDS_PINID='CB(7)';
NET_NAME
'M_L_MA<0>'
 '@BASEBOARD_FAB2_LIB.BASEBOARD_FAB2(SCH_1):M_L_MA'<0>:
 C_SIGNAL='@baseboard_fab2_lib.baseboard_fab2(sch_1):m_l_ma(0)';
NODE_NAME     U2D1 DW52
 '@BASEBOARD_FAB2_LIB.BASEBOARD_FAB2(SCH_1):PAGE61_I172@CHPSET_LIB.SKX_EXT_B(CHIPS)':
 'DDR4_MA'<0>: CDS_PINID='DDR4_MA(0)';
NODE_NAME     J1A2 79
 '@BASEBOARD_FAB2_LIB.BASEBOARD_FAB2(SCH_1):PAGE85_I111@MSTR_SCONN.SCONN288_H44441004(CHIPS)':
 'A0': CDS_PINID='A0';
NODE_NAME     J9L2 79
 '@BASEBOARD_FAB2_LIB.BASEBOARD_FAB2(SCH_1):PAGE86_I12@MSTR_SCONN.SCONN288_H44441003(CHIPS)':
 'A0': CDS_PINID='A0';
NET_NAME
'M_L_MA<10>'
 '@BASEBOARD_FAB2_LIB.BASEBOARD_FAB2(SCH_1):M_L_MA'<10>:
 C_SIGNAL='@baseboard_fab2_lib.baseboard_fab2(sch_1):m_l_ma(10)';
NODE_NAME     U2D1 DT55
 '@BASEBOARD_FAB2_LIB.BASEBOARD_FAB2(SCH_1):PAGE61_I172@CHPSET_LIB.SKX_EXT_B(CHIPS)':
 'DDR4_MA'<10>: CDS_PINID='DDR4_MA(10)';
NODE_NAME     J1A2 225
 '@BASEBOARD_FAB2_LIB.BASEBOARD_FAB2(SCH_1):PAGE85_I111@MSTR_SCONN.SCONN288_H44441004(CHIPS)':
 'A10': CDS_PINID='A10';
NODE_NAME     J9L2 225
 '@BASEBOARD_FAB2_LIB.BASEBOARD_FAB2(SCH_1):PAGE86_I12@MSTR_SCONN.SCONN288_H44441003(CHIPS)':
 'A10': CDS_PINID='A10';
NET_NAME
'M_L_MA<11>'
 '@BASEBOARD_FAB2_LIB.BASEBOARD_FAB2(SCH_1):M_L_MA'<11>:
 C_SIGNAL='@baseboard_fab2_lib.baseboard_fab2(sch_1):m_l_ma(11)';
NODE_NAME     U2D1 DR60
 '@BASEBOARD_FAB2_LIB.BASEBOARD_FAB2(SCH_1):PAGE61_I172@CHPSET_LIB.SKX_EXT_B(CHIPS)':
 'DDR4_MA'<11>: CDS_PINID='DDR4_MA(11)';
NODE_NAME     J1A2 210
 '@BASEBOARD_FAB2_LIB.BASEBOARD_FAB2(SCH_1):PAGE85_I111@MSTR_SCONN.SCONN288_H44441004(CHIPS)':
 'A11': CDS_PINID='A11';
NODE_NAME     J9L2 210
 '@BASEBOARD_FAB2_LIB.BASEBOARD_FAB2(SCH_1):PAGE86_I12@MSTR_SCONN.SCONN288_H44441003(CHIPS)':
 'A11': CDS_PINID='A11';
NET_NAME
'M_L_MA<12>'
 '@BASEBOARD_FAB2_LIB.BASEBOARD_FAB2(SCH_1):M_L_MA'<12>:
 C_SIGNAL='@baseboard_fab2_lib.baseboard_fab2(sch_1):m_l_ma(12)';
NODE_NAME     U2D1 DN60
 '@BASEBOARD_FAB2_LIB.BASEBOARD_FAB2(SCH_1):PAGE61_I172@CHPSET_LIB.SKX_EXT_B(CHIPS)':
 'DDR4_MA'<12>: CDS_PINID='DDR4_MA(12)';
NODE_NAME     J1A2 65
 '@BASEBOARD_FAB2_LIB.BASEBOARD_FAB2(SCH_1):PAGE85_I111@MSTR_SCONN.SCONN288_H44441004(CHIPS)':
 'A12': CDS_PINID='A12';
NODE_NAME     J9L2 65
 '@BASEBOARD_FAB2_LIB.BASEBOARD_FAB2(SCH_1):PAGE86_I12@MSTR_SCONN.SCONN288_H44441003(CHIPS)':
 'A12': CDS_PINID='A12';
NET_NAME
'M_L_MA<13>'
 '@BASEBOARD_FAB2_LIB.BASEBOARD_FAB2(SCH_1):M_L_MA'<13>:
 C_SIGNAL='@baseboard_fab2_lib.baseboard_fab2(sch_1):m_l_ma(13)';
NODE_NAME     U2D1 DT51
 '@BASEBOARD_FAB2_LIB.BASEBOARD_FAB2(SCH_1):PAGE61_I172@CHPSET_LIB.SKX_EXT_B(CHIPS)':
 'DDR4_MA'<13>: CDS_PINID='DDR4_MA(13)';
NODE_NAME     J1A2 232
 '@BASEBOARD_FAB2_LIB.BASEBOARD_FAB2(SCH_1):PAGE85_I111@MSTR_SCONN.SCONN288_H44441004(CHIPS)':
 'A13': CDS_PINID='A13';
NODE_NAME     J9L2 232
 '@BASEBOARD_FAB2_LIB.BASEBOARD_FAB2(SCH_1):PAGE86_I12@MSTR_SCONN.SCONN288_H44441003(CHIPS)':
 'A13': CDS_PINID='A13';
NET_NAME
'M_L_MA<14>'
 '@BASEBOARD_FAB2_LIB.BASEBOARD_FAB2(SCH_1):M_L_MA'<14>:
 C_SIGNAL='@baseboard_fab2_lib.baseboard_fab2(sch_1):m_l_ma(14)';
NODE_NAME     U2D1 DM51
 '@BASEBOARD_FAB2_LIB.BASEBOARD_FAB2(SCH_1):PAGE61_I172@CHPSET_LIB.SKX_EXT_B(CHIPS)':
 'DDR4_MA'<14>: CDS_PINID='DDR4_MA(14)';
NODE_NAME     J1A2 228
 '@BASEBOARD_FAB2_LIB.BASEBOARD_FAB2(SCH_1):PAGE85_I111@MSTR_SCONN.SCONN288_H44441004(CHIPS)':
 'A14_WE_N': CDS_PINID='A14_WE_N';
NODE_NAME     J9L2 228
 '@BASEBOARD_FAB2_LIB.BASEBOARD_FAB2(SCH_1):PAGE86_I12@MSTR_SCONN.SCONN288_H44441003(CHIPS)':
 'A14_WE_N': CDS_PINID='A14_WE_N';
NET_NAME
'M_L_MA<15>'
 '@BASEBOARD_FAB2_LIB.BASEBOARD_FAB2(SCH_1):M_L_MA'<15>:
 C_SIGNAL='@baseboard_fab2_lib.baseboard_fab2(sch_1):m_l_ma(15)';
NODE_NAME     U2D1 DR52
 '@BASEBOARD_FAB2_LIB.BASEBOARD_FAB2(SCH_1):PAGE61_I172@CHPSET_LIB.SKX_EXT_B(CHIPS)':
 'DDR4_MA'<15>: CDS_PINID='DDR4_MA(15)';
NODE_NAME     J1A2 86
 '@BASEBOARD_FAB2_LIB.BASEBOARD_FAB2(SCH_1):PAGE85_I111@MSTR_SCONN.SCONN288_H44441004(CHIPS)':
 'A15_CAS_N': CDS_PINID='A15_CAS_N';
NODE_NAME     J9L2 86
 '@BASEBOARD_FAB2_LIB.BASEBOARD_FAB2(SCH_1):PAGE86_I12@MSTR_SCONN.SCONN288_H44441003(CHIPS)':
 'A15_CAS_N': CDS_PINID='A15_CAS_N';
NET_NAME
'M_L_MA<16>'
 '@BASEBOARD_FAB2_LIB.BASEBOARD_FAB2(SCH_1):M_L_MA'<16>:
 C_SIGNAL='@baseboard_fab2_lib.baseboard_fab2(sch_1):m_l_ma(16)';
NODE_NAME     U2D1 DN52
 '@BASEBOARD_FAB2_LIB.BASEBOARD_FAB2(SCH_1):PAGE61_I172@CHPSET_LIB.SKX_EXT_B(CHIPS)':
 'DDR4_MA'<16>: CDS_PINID='DDR4_MA(16)';
NODE_NAME     J1A2 82
 '@BASEBOARD_FAB2_LIB.BASEBOARD_FAB2(SCH_1):PAGE85_I111@MSTR_SCONN.SCONN288_H44441004(CHIPS)':
 'A16_RAS_N': CDS_PINID='A16_RAS_N';
NODE_NAME     J9L2 82
 '@BASEBOARD_FAB2_LIB.BASEBOARD_FAB2(SCH_1):PAGE86_I12@MSTR_SCONN.SCONN288_H44441003(CHIPS)':
 'A16_RAS_N': CDS_PINID='A16_RAS_N';
NET_NAME
'M_L_MA<17>'
 '@BASEBOARD_FAB2_LIB.BASEBOARD_FAB2(SCH_1):M_L_MA'<17>:
 C_SIGNAL='@baseboard_fab2_lib.baseboard_fab2(sch_1):m_l_ma(17)';
NODE_NAME     U2D1 DR48
 '@BASEBOARD_FAB2_LIB.BASEBOARD_FAB2(SCH_1):PAGE61_I172@CHPSET_LIB.SKX_EXT_B(CHIPS)':
 'DDR4_MA'<17>: CDS_PINID='DDR4_MA(17)';
NODE_NAME     J1A2 234
 '@BASEBOARD_FAB2_LIB.BASEBOARD_FAB2(SCH_1):PAGE85_I111@MSTR_SCONN.SCONN288_H44441004(CHIPS)':
 'A17': CDS_PINID='A17';
NODE_NAME     J9L2 234
 '@BASEBOARD_FAB2_LIB.BASEBOARD_FAB2(SCH_1):PAGE86_I12@MSTR_SCONN.SCONN288_H44441003(CHIPS)':
 'A17': CDS_PINID='A17';
NET_NAME
'M_L_MA<1>'
 '@BASEBOARD_FAB2_LIB.BASEBOARD_FAB2(SCH_1):M_L_MA'<1>:
 C_SIGNAL='@baseboard_fab2_lib.baseboard_fab2(sch_1):m_l_ma(1)';
NODE_NAME     U2D1 DW58
 '@BASEBOARD_FAB2_LIB.BASEBOARD_FAB2(SCH_1):PAGE61_I172@CHPSET_LIB.SKX_EXT_B(CHIPS)':
 'DDR4_MA'<1>: CDS_PINID='DDR4_MA(1)';
NODE_NAME     J1A2 72
 '@BASEBOARD_FAB2_LIB.BASEBOARD_FAB2(SCH_1):PAGE85_I111@MSTR_SCONN.SCONN288_H44441004(CHIPS)':
 'A1': CDS_PINID='A1';
NODE_NAME     J9L2 72
 '@BASEBOARD_FAB2_LIB.BASEBOARD_FAB2(SCH_1):PAGE86_I12@MSTR_SCONN.SCONN288_H44441003(CHIPS)':
 'A1': CDS_PINID='A1';
NET_NAME
'M_L_MA<2>'
 '@BASEBOARD_FAB2_LIB.BASEBOARD_FAB2(SCH_1):M_L_MA'<2>:
 C_SIGNAL='@baseboard_fab2_lib.baseboard_fab2(sch_1):m_l_ma(2)';
NODE_NAME     U2D1 DV57
 '@BASEBOARD_FAB2_LIB.BASEBOARD_FAB2(SCH_1):PAGE61_I172@CHPSET_LIB.SKX_EXT_B(CHIPS)':
 'DDR4_MA'<2>: CDS_PINID='DDR4_MA(2)';
NODE_NAME     J1A2 216
 '@BASEBOARD_FAB2_LIB.BASEBOARD_FAB2(SCH_1):PAGE85_I111@MSTR_SCONN.SCONN288_H44441004(CHIPS)':
 'A2': CDS_PINID='A2';
NODE_NAME     J9L2 216
 '@BASEBOARD_FAB2_LIB.BASEBOARD_FAB2(SCH_1):PAGE86_I12@MSTR_SCONN.SCONN288_H44441003(CHIPS)':
 'A2': CDS_PINID='A2';
NET_NAME
'M_L_MA<3>'
 '@BASEBOARD_FAB2_LIB.BASEBOARD_FAB2(SCH_1):M_L_MA'<3>:
 C_SIGNAL='@baseboard_fab2_lib.baseboard_fab2(sch_1):m_l_ma(3)';
NODE_NAME     U2D1 DR58
 '@BASEBOARD_FAB2_LIB.BASEBOARD_FAB2(SCH_1):PAGE61_I172@CHPSET_LIB.SKX_EXT_B(CHIPS)':
 'DDR4_MA'<3>: CDS_PINID='DDR4_MA(3)';
NODE_NAME     J1A2 71
 '@BASEBOARD_FAB2_LIB.BASEBOARD_FAB2(SCH_1):PAGE85_I111@MSTR_SCONN.SCONN288_H44441004(CHIPS)':
 'A3': CDS_PINID='A3';
NODE_NAME     J9L2 71
 '@BASEBOARD_FAB2_LIB.BASEBOARD_FAB2(SCH_1):PAGE86_I12@MSTR_SCONN.SCONN288_H44441003(CHIPS)':
 'A3': CDS_PINID='A3';
NET_NAME
'M_L_MA<4>'
 '@BASEBOARD_FAB2_LIB.BASEBOARD_FAB2(SCH_1):M_L_MA'<4>:
 C_SIGNAL='@baseboard_fab2_lib.baseboard_fab2(sch_1):m_l_ma(4)';
NODE_NAME     U2D1 DT59
 '@BASEBOARD_FAB2_LIB.BASEBOARD_FAB2(SCH_1):PAGE61_I172@CHPSET_LIB.SKX_EXT_B(CHIPS)':
 'DDR4_MA'<4>: CDS_PINID='DDR4_MA(4)';
NODE_NAME     J1A2 214
 '@BASEBOARD_FAB2_LIB.BASEBOARD_FAB2(SCH_1):PAGE85_I111@MSTR_SCONN.SCONN288_H44441004(CHIPS)':
 'A4': CDS_PINID='A4';
NODE_NAME     J9L2 214
 '@BASEBOARD_FAB2_LIB.BASEBOARD_FAB2(SCH_1):PAGE86_I12@MSTR_SCONN.SCONN288_H44441003(CHIPS)':
 'A4': CDS_PINID='A4';
NET_NAME
'M_L_MA<5>'
 '@BASEBOARD_FAB2_LIB.BASEBOARD_FAB2(SCH_1):M_L_MA'<5>:
 C_SIGNAL='@baseboard_fab2_lib.baseboard_fab2(sch_1):m_l_ma(5)';
NODE_NAME     U2D1 DN58
 '@BASEBOARD_FAB2_LIB.BASEBOARD_FAB2(SCH_1):PAGE61_I172@CHPSET_LIB.SKX_EXT_B(CHIPS)':
 'DDR4_MA'<5>: CDS_PINID='DDR4_MA(5)';
NODE_NAME     J1A2 213
 '@BASEBOARD_FAB2_LIB.BASEBOARD_FAB2(SCH_1):PAGE85_I111@MSTR_SCONN.SCONN288_H44441004(CHIPS)':
 'A5': CDS_PINID='A5';
NODE_NAME     J9L2 213
 '@BASEBOARD_FAB2_LIB.BASEBOARD_FAB2(SCH_1):PAGE86_I12@MSTR_SCONN.SCONN288_H44441003(CHIPS)':
 'A5': CDS_PINID='A5';
NET_NAME
'M_L_MA<6>'
 '@BASEBOARD_FAB2_LIB.BASEBOARD_FAB2(SCH_1):M_L_MA'<6>:
 C_SIGNAL='@baseboard_fab2_lib.baseboard_fab2(sch_1):m_l_ma(6)';
NODE_NAME     U2D1 DM59
 '@BASEBOARD_FAB2_LIB.BASEBOARD_FAB2(SCH_1):PAGE61_I172@CHPSET_LIB.SKX_EXT_B(CHIPS)':
 'DDR4_MA'<6>: CDS_PINID='DDR4_MA(6)';
NODE_NAME     J1A2 69
 '@BASEBOARD_FAB2_LIB.BASEBOARD_FAB2(SCH_1):PAGE85_I111@MSTR_SCONN.SCONN288_H44441004(CHIPS)':
 'A6': CDS_PINID='A6';
NODE_NAME     J9L2 69
 '@BASEBOARD_FAB2_LIB.BASEBOARD_FAB2(SCH_1):PAGE86_I12@MSTR_SCONN.SCONN288_H44441003(CHIPS)':
 'A6': CDS_PINID='A6';
NET_NAME
'M_L_MA<7>'
 '@BASEBOARD_FAB2_LIB.BASEBOARD_FAB2(SCH_1):M_L_MA'<7>:
 C_SIGNAL='@baseboard_fab2_lib.baseboard_fab2(sch_1):m_l_ma(7)';
NODE_NAME     U2D1 DK61
 '@BASEBOARD_FAB2_LIB.BASEBOARD_FAB2(SCH_1):PAGE61_I172@CHPSET_LIB.SKX_EXT_B(CHIPS)':
 'DDR4_MA'<7>: CDS_PINID='DDR4_MA(7)';
NODE_NAME     J1A2 211
 '@BASEBOARD_FAB2_LIB.BASEBOARD_FAB2(SCH_1):PAGE85_I111@MSTR_SCONN.SCONN288_H44441004(CHIPS)':
 'A7': CDS_PINID='A7';
NODE_NAME     J9L2 211
 '@BASEBOARD_FAB2_LIB.BASEBOARD_FAB2(SCH_1):PAGE86_I12@MSTR_SCONN.SCONN288_H44441003(CHIPS)':
 'A7': CDS_PINID='A7';
NET_NAME
'M_L_MA<8>'
 '@BASEBOARD_FAB2_LIB.BASEBOARD_FAB2(SCH_1):M_L_MA'<8>:
 C_SIGNAL='@baseboard_fab2_lib.baseboard_fab2(sch_1):m_l_ma(8)';
NODE_NAME     U2D1 DJ60
 '@BASEBOARD_FAB2_LIB.BASEBOARD_FAB2(SCH_1):PAGE61_I172@CHPSET_LIB.SKX_EXT_B(CHIPS)':
 'DDR4_MA'<8>: CDS_PINID='DDR4_MA(8)';
NODE_NAME     J1A2 68
 '@BASEBOARD_FAB2_LIB.BASEBOARD_FAB2(SCH_1):PAGE85_I111@MSTR_SCONN.SCONN288_H44441004(CHIPS)':
 'A8': CDS_PINID='A8';
NODE_NAME     J9L2 68
 '@BASEBOARD_FAB2_LIB.BASEBOARD_FAB2(SCH_1):PAGE86_I12@MSTR_SCONN.SCONN288_H44441003(CHIPS)':
 'A8': CDS_PINID='A8';
NET_NAME
'M_L_MA<9>'
 '@BASEBOARD_FAB2_LIB.BASEBOARD_FAB2(SCH_1):M_L_MA'<9>:
 C_SIGNAL='@baseboard_fab2_lib.baseboard_fab2(sch_1):m_l_ma(9)';
NODE_NAME     U2D1 DV59
 '@BASEBOARD_FAB2_LIB.BASEBOARD_FAB2(SCH_1):PAGE61_I172@CHPSET_LIB.SKX_EXT_B(CHIPS)':
 'DDR4_MA'<9>: CDS_PINID='DDR4_MA(9)';
NODE_NAME     J1A2 66
 '@BASEBOARD_FAB2_LIB.BASEBOARD_FAB2(SCH_1):PAGE85_I111@MSTR_SCONN.SCONN288_H44441004(CHIPS)':
 'A9': CDS_PINID='A9';
NODE_NAME     J9L2 66
 '@BASEBOARD_FAB2_LIB.BASEBOARD_FAB2(SCH_1):PAGE86_I12@MSTR_SCONN.SCONN288_H44441003(CHIPS)':
 'A9': CDS_PINID='A9';
NET_NAME
'M_L_ODT<0>'
 '@BASEBOARD_FAB2_LIB.BASEBOARD_FAB2(SCH_1):M_L_ODT'<0>:
 C_SIGNAL='@baseboard_fab2_lib.baseboard_fab2(sch_1):m_l_odt(0)';
NODE_NAME     U2D1 DR50
 '@BASEBOARD_FAB2_LIB.BASEBOARD_FAB2(SCH_1):PAGE61_I172@CHPSET_LIB.SKX_EXT_B(CHIPS)':
 'DDR4_ODT'<0>: CDS_PINID='DDR4_ODT(0)';
NODE_NAME     J1A2 87
 '@BASEBOARD_FAB2_LIB.BASEBOARD_FAB2(SCH_1):PAGE85_I111@MSTR_SCONN.SCONN288_H44441004(CHIPS)':
 'ODT'<0>: CDS_PINID='ODT(0)';
NET_NAME
'M_L_ODT<1>'
 '@BASEBOARD_FAB2_LIB.BASEBOARD_FAB2(SCH_1):M_L_ODT'<1>:
 C_SIGNAL='@baseboard_fab2_lib.baseboard_fab2(sch_1):m_l_odt(1)';
NODE_NAME     U2D1 DN48
 '@BASEBOARD_FAB2_LIB.BASEBOARD_FAB2(SCH_1):PAGE61_I172@CHPSET_LIB.SKX_EXT_B(CHIPS)':
 'DDR4_ODT'<1>: CDS_PINID='DDR4_ODT(1)';
NODE_NAME     J1A2 91
 '@BASEBOARD_FAB2_LIB.BASEBOARD_FAB2(SCH_1):PAGE85_I111@MSTR_SCONN.SCONN288_H44441004(CHIPS)':
 'ODT'<1>: CDS_PINID='ODT(1)';
NET_NAME
'M_L_ODT<2>'
 '@BASEBOARD_FAB2_LIB.BASEBOARD_FAB2(SCH_1):M_L_ODT'<2>:
 C_SIGNAL='@baseboard_fab2_lib.baseboard_fab2(sch_1):m_l_odt(2)';
NODE_NAME     U2D1 DT49
 '@BASEBOARD_FAB2_LIB.BASEBOARD_FAB2(SCH_1):PAGE61_I172@CHPSET_LIB.SKX_EXT_B(CHIPS)':
 'DDR4_ODT'<2>: CDS_PINID='DDR4_ODT(2)';
NODE_NAME     J9L2 87
 '@BASEBOARD_FAB2_LIB.BASEBOARD_FAB2(SCH_1):PAGE86_I12@MSTR_SCONN.SCONN288_H44441003(CHIPS)':
 'ODT'<0>: CDS_PINID='ODT(0)';
NET_NAME
'M_L_ODT<3>'
 '@BASEBOARD_FAB2_LIB.BASEBOARD_FAB2(SCH_1):M_L_ODT'<3>:
 C_SIGNAL='@baseboard_fab2_lib.baseboard_fab2(sch_1):m_l_odt(3)';
NODE_NAME     U2D1 DM47
 '@BASEBOARD_FAB2_LIB.BASEBOARD_FAB2(SCH_1):PAGE61_I172@CHPSET_LIB.SKX_EXT_B(CHIPS)':
 'DDR4_ODT'<3>: CDS_PINID='DDR4_ODT(3)';
NODE_NAME     J9L2 91
 '@BASEBOARD_FAB2_LIB.BASEBOARD_FAB2(SCH_1):PAGE86_I12@MSTR_SCONN.SCONN288_H44441003(CHIPS)':
 'ODT'<1>: CDS_PINID='ODT(1)';
NET_NAME
'M_L_PAR'
 '@BASEBOARD_FAB2_LIB.BASEBOARD_FAB2(SCH_1):M_L_PAR':
 C_SIGNAL='@baseboard_fab2_lib.baseboard_fab2(sch_1):m_l_par';
NODE_NAME     U2D1 DV53
 '@BASEBOARD_FAB2_LIB.BASEBOARD_FAB2(SCH_1):PAGE61_I172@CHPSET_LIB.SKX_EXT_B(CHIPS)':
 'DDR4_PAR': CDS_PINID='DDR4_PAR';
NODE_NAME     J1A2 222
 '@BASEBOARD_FAB2_LIB.BASEBOARD_FAB2(SCH_1):PAGE85_I111@MSTR_SCONN.SCONN288_H44441004(CHIPS)':
 'PAR': CDS_PINID='PAR';
NODE_NAME     J9L2 222
 '@BASEBOARD_FAB2_LIB.BASEBOARD_FAB2(SCH_1):PAGE86_I12@MSTR_SCONN.SCONN288_H44441003(CHIPS)':
 'PAR': CDS_PINID='PAR';
NET_NAME
'M_L_VREF'
 '@BASEBOARD_FAB2_LIB.BASEBOARD_FAB2(SCH_1):M_L_VREF':
 C_SIGNAL='@baseboard_fab2_lib.baseboard_fab2(sch_1):m_l_vref';
NODE_NAME     J1A2 146
 '@BASEBOARD_FAB2_LIB.BASEBOARD_FAB2(SCH_1):PAGE85_I111@MSTR_SCONN.SCONN288_H44441004(CHIPS)':
 'VREFCA': CDS_PINID='VREFCA';
NODE_NAME     C9L7 1
 '@BASEBOARD_FAB2_LIB.BASEBOARD_FAB2(SCH_1):PAGE85_I181@DEV_DISCRETE.CAP_A(CHIPS)':
 'A': CDS_PINID='A';
NODE_NAME     J9L2 146
 '@BASEBOARD_FAB2_LIB.BASEBOARD_FAB2(SCH_1):PAGE86_I12@MSTR_SCONN.SCONN288_H44441003(CHIPS)':
 'VREFCA': CDS_PINID='VREFCA';
NODE_NAME     C1A17 1
 '@BASEBOARD_FAB2_LIB.BASEBOARD_FAB2(SCH_1):PAGE86_I182@DEV_DISCRETE.CAP_A(CHIPS)':
 'A': CDS_PINID='A';
NODE_NAME     R9L7 2
 '@BASEBOARD_FAB2_LIB.BASEBOARD_FAB2(SCH_1):PAGE100_I22@MSTR_DISCRETE.RES(CHIPS)':
 'B': CDS_PINID='B';
NODE_NAME     R9L6 1
 '@BASEBOARD_FAB2_LIB.BASEBOARD_FAB2(SCH_1):PAGE100_I24@MSTR_DISCRETE.RES(CHIPS)':
 'A': CDS_PINID='A';
NODE_NAME     R9L8 2
 '@BASEBOARD_FAB2_LIB.BASEBOARD_FAB2(SCH_1):PAGE100_I29@MSTR_DISCRETE.RES(CHIPS)':
 'B': CDS_PINID='B';
NET_NAME
'M_M_ACT_N'
 '@BASEBOARD_FAB2_LIB.BASEBOARD_FAB2(SCH_1):M_M_ACT_N':
 C_SIGNAL='@baseboard_fab2_lib.baseboard_fab2(sch_1):m_m_act_n';
NODE_NAME     U2D1 DC62
 '@BASEBOARD_FAB2_LIB.BASEBOARD_FAB2(SCH_1):PAGE62_I172@CHPSET_LIB.SKX_EXT_B(CHIPS)':
 'DDR5_ACT_N': CDS_PINID='DDR5_ACT_N';
NODE_NAME     J1A1 62
 '@BASEBOARD_FAB2_LIB.BASEBOARD_FAB2(SCH_1):PAGE87_I186@MSTR_SCONN.SCONN288_H44441004(CHIPS)':
 'ACT_N': CDS_PINID='ACT_N';
NODE_NAME     J9L1 62
 '@BASEBOARD_FAB2_LIB.BASEBOARD_FAB2(SCH_1):PAGE88_I111@MSTR_SCONN.SCONN288_H44441003(CHIPS)':
 'ACT_N': CDS_PINID='ACT_N';
NET_NAME
'M_M_ALERT_N'
 '@BASEBOARD_FAB2_LIB.BASEBOARD_FAB2(SCH_1):M_M_ALERT_N':
 C_SIGNAL='@baseboard_fab2_lib.baseboard_fab2(sch_1):m_m_alert_n';
NODE_NAME     U2D1 DD61
 '@BASEBOARD_FAB2_LIB.BASEBOARD_FAB2(SCH_1):PAGE62_I172@CHPSET_LIB.SKX_EXT_B(CHIPS)':
 'DDR5_ALERT_N': CDS_PINID='DDR5_ALERT_N';
NODE_NAME     J1A1 208
 '@BASEBOARD_FAB2_LIB.BASEBOARD_FAB2(SCH_1):PAGE87_I186@MSTR_SCONN.SCONN288_H44441004(CHIPS)':
 'ALERT_N': CDS_PINID='ALERT_N';
NODE_NAME     J9L1 208
 '@BASEBOARD_FAB2_LIB.BASEBOARD_FAB2(SCH_1):PAGE88_I111@MSTR_SCONN.SCONN288_H44441003(CHIPS)':
 'ALERT_N': CDS_PINID='ALERT_N';
NET_NAME
'M_M_BA<0>'
 '@BASEBOARD_FAB2_LIB.BASEBOARD_FAB2(SCH_1):M_M_BA'<0>:
 C_SIGNAL='@baseboard_fab2_lib.baseboard_fab2(sch_1):m_m_ba(0)';
NODE_NAME     U2D1 DJ52
 '@BASEBOARD_FAB2_LIB.BASEBOARD_FAB2(SCH_1):PAGE62_I172@CHPSET_LIB.SKX_EXT_B(CHIPS)':
 'DDR5_BA'<0>: CDS_PINID='DDR5_BA(0)';
NODE_NAME     J1A1 81
 '@BASEBOARD_FAB2_LIB.BASEBOARD_FAB2(SCH_1):PAGE87_I186@MSTR_SCONN.SCONN288_H44441004(CHIPS)':
 'BA'<0>: CDS_PINID='BA(0)';
NODE_NAME     J9L1 81
 '@BASEBOARD_FAB2_LIB.BASEBOARD_FAB2(SCH_1):PAGE88_I111@MSTR_SCONN.SCONN288_H44441003(CHIPS)':
 'BA'<0>: CDS_PINID='BA(0)';
NET_NAME
'M_M_BA<1>'
 '@BASEBOARD_FAB2_LIB.BASEBOARD_FAB2(SCH_1):M_M_BA'<1>:
 C_SIGNAL='@baseboard_fab2_lib.baseboard_fab2(sch_1):m_m_ba(1)';
NODE_NAME     U2D1 DC56
 '@BASEBOARD_FAB2_LIB.BASEBOARD_FAB2(SCH_1):PAGE62_I172@CHPSET_LIB.SKX_EXT_B(CHIPS)':
 'DDR5_BA'<1>: CDS_PINID='DDR5_BA(1)';
NODE_NAME     J1A1 224
 '@BASEBOARD_FAB2_LIB.BASEBOARD_FAB2(SCH_1):PAGE87_I186@MSTR_SCONN.SCONN288_H44441004(CHIPS)':
 'BA'<1>: CDS_PINID='BA(1)';
NODE_NAME     J9L1 224
 '@BASEBOARD_FAB2_LIB.BASEBOARD_FAB2(SCH_1):PAGE88_I111@MSTR_SCONN.SCONN288_H44441003(CHIPS)':
 'BA'<1>: CDS_PINID='BA(1)';
NET_NAME
'M_M_BG<0>'
 '@BASEBOARD_FAB2_LIB.BASEBOARD_FAB2(SCH_1):M_M_BG'<0>:
 C_SIGNAL='@baseboard_fab2_lib.baseboard_fab2(sch_1):m_m_bg(0)';
NODE_NAME     U2D1 DA62
 '@BASEBOARD_FAB2_LIB.BASEBOARD_FAB2(SCH_1):PAGE62_I172@CHPSET_LIB.SKX_EXT_B(CHIPS)':
 'DDR5_BG'<0>: CDS_PINID='DDR5_BG(0)';
NODE_NAME     J1A1 63
 '@BASEBOARD_FAB2_LIB.BASEBOARD_FAB2(SCH_1):PAGE87_I186@MSTR_SCONN.SCONN288_H44441004(CHIPS)':
 'BG'<0>: CDS_PINID='BG(0)';
NODE_NAME     J9L1 63
 '@BASEBOARD_FAB2_LIB.BASEBOARD_FAB2(SCH_1):PAGE88_I111@MSTR_SCONN.SCONN288_H44441003(CHIPS)':
 'BG'<0>: CDS_PINID='BG(0)';
NET_NAME
'M_M_BG<1>'
 '@BASEBOARD_FAB2_LIB.BASEBOARD_FAB2(SCH_1):M_M_BG'<1>:
 C_SIGNAL='@baseboard_fab2_lib.baseboard_fab2(sch_1):m_m_bg(1)';
NODE_NAME     U2D1 DF61
 '@BASEBOARD_FAB2_LIB.BASEBOARD_FAB2(SCH_1):PAGE62_I172@CHPSET_LIB.SKX_EXT_B(CHIPS)':
 'DDR5_BG'<1>: CDS_PINID='DDR5_BG(1)';
NODE_NAME     J1A1 207
 '@BASEBOARD_FAB2_LIB.BASEBOARD_FAB2(SCH_1):PAGE87_I186@MSTR_SCONN.SCONN288_H44441004(CHIPS)':
 'BG'<1>: CDS_PINID='BG(1)';
NODE_NAME     J9L1 207
 '@BASEBOARD_FAB2_LIB.BASEBOARD_FAB2(SCH_1):PAGE88_I111@MSTR_SCONN.SCONN288_H44441003(CHIPS)':
 'BG'<1>: CDS_PINID='BG(1)';
NET_NAME
'M_M_C<2>'
 '@BASEBOARD_FAB2_LIB.BASEBOARD_FAB2(SCH_1):M_M_C'<2>:
 C_SIGNAL='@baseboard_fab2_lib.baseboard_fab2(sch_1):m_m_c(2)';
NODE_NAME     U2D1 DF45
 '@BASEBOARD_FAB2_LIB.BASEBOARD_FAB2(SCH_1):PAGE62_I172@CHPSET_LIB.SKX_EXT_B(CHIPS)':
 'DDR5_CID'<2>: CDS_PINID='DDR5_CID(2)';
NODE_NAME     J1A1 235
 '@BASEBOARD_FAB2_LIB.BASEBOARD_FAB2(SCH_1):PAGE87_I186@MSTR_SCONN.SCONN288_H44441004(CHIPS)':
 'C'<2>: CDS_PINID='C(2)';
NODE_NAME     J9L1 235
 '@BASEBOARD_FAB2_LIB.BASEBOARD_FAB2(SCH_1):PAGE88_I111@MSTR_SCONN.SCONN288_H44441003(CHIPS)':
 'C'<2>: CDS_PINID='C(2)';
NET_NAME
'M_M_CKE<0>'
 '@BASEBOARD_FAB2_LIB.BASEBOARD_FAB2(SCH_1):M_M_CKE'<0>:
 C_SIGNAL='@baseboard_fab2_lib.baseboard_fab2(sch_1):m_m_cke(0)';
NODE_NAME     U2D1 DG62
 '@BASEBOARD_FAB2_LIB.BASEBOARD_FAB2(SCH_1):PAGE62_I172@CHPSET_LIB.SKX_EXT_B(CHIPS)':
 'DDR5_CKE'<0>: CDS_PINID='DDR5_CKE(0)';
NODE_NAME     J1A1 60
 '@BASEBOARD_FAB2_LIB.BASEBOARD_FAB2(SCH_1):PAGE87_I186@MSTR_SCONN.SCONN288_H44441004(CHIPS)':
 'CKE'<0>: CDS_PINID='CKE(0)';
NET_NAME
'M_M_CKE<1>'
 '@BASEBOARD_FAB2_LIB.BASEBOARD_FAB2(SCH_1):M_M_CKE'<1>:
 C_SIGNAL='@baseboard_fab2_lib.baseboard_fab2(sch_1):m_m_cke(1)';
NODE_NAME     U2D1 DD63
 '@BASEBOARD_FAB2_LIB.BASEBOARD_FAB2(SCH_1):PAGE62_I172@CHPSET_LIB.SKX_EXT_B(CHIPS)':
 'DDR5_CKE'<1>: CDS_PINID='DDR5_CKE(1)';
NODE_NAME     J1A1 203
 '@BASEBOARD_FAB2_LIB.BASEBOARD_FAB2(SCH_1):PAGE87_I186@MSTR_SCONN.SCONN288_H44441004(CHIPS)':
 'CKE'<1>: CDS_PINID='CKE(1)';
NET_NAME
'M_M_CKE<2>'
 '@BASEBOARD_FAB2_LIB.BASEBOARD_FAB2(SCH_1):M_M_CKE'<2>:
 C_SIGNAL='@baseboard_fab2_lib.baseboard_fab2(sch_1):m_m_cke(2)';
NODE_NAME     U2D1 DK63
 '@BASEBOARD_FAB2_LIB.BASEBOARD_FAB2(SCH_1):PAGE62_I172@CHPSET_LIB.SKX_EXT_B(CHIPS)':
 'DDR5_CKE'<2>: CDS_PINID='DDR5_CKE(2)';
NODE_NAME     J9L1 60
 '@BASEBOARD_FAB2_LIB.BASEBOARD_FAB2(SCH_1):PAGE88_I111@MSTR_SCONN.SCONN288_H44441003(CHIPS)':
 'CKE'<0>: CDS_PINID='CKE(0)';
NET_NAME
'M_M_CKE<3>'
 '@BASEBOARD_FAB2_LIB.BASEBOARD_FAB2(SCH_1):M_M_CKE'<3>:
 C_SIGNAL='@baseboard_fab2_lib.baseboard_fab2(sch_1):m_m_cke(3)';
NODE_NAME     U2D1 DF63
 '@BASEBOARD_FAB2_LIB.BASEBOARD_FAB2(SCH_1):PAGE62_I172@CHPSET_LIB.SKX_EXT_B(CHIPS)':
 'DDR5_CKE'<3>: CDS_PINID='DDR5_CKE(3)';
NODE_NAME     J9L1 203
 '@BASEBOARD_FAB2_LIB.BASEBOARD_FAB2(SCH_1):PAGE88_I111@MSTR_SCONN.SCONN288_H44441003(CHIPS)':
 'CKE'<1>: CDS_PINID='CKE(1)';
NET_NAME
'M_M_CLK_DN<0>'
 '@BASEBOARD_FAB2_LIB.BASEBOARD_FAB2(SCH_1):M_M_CLK_DN'<0>:
 C_SIGNAL='@baseboard_fab2_lib.baseboard_fab2(sch_1):m_m_clk_dn(0)';
NODE_NAME     U2D1 DK55
 '@BASEBOARD_FAB2_LIB.BASEBOARD_FAB2(SCH_1):PAGE62_I172@CHPSET_LIB.SKX_EXT_B(CHIPS)':
 'DDR5_CLK_DN'<0>: CDS_PINID='DDR5_CLK_DN(0)';
NODE_NAME     J1A1 75
 '@BASEBOARD_FAB2_LIB.BASEBOARD_FAB2(SCH_1):PAGE87_I186@MSTR_SCONN.SCONN288_H44441004(CHIPS)':
 'CK0N': CDS_PINID='CK0N';
NET_NAME
'M_M_CLK_DN<1>'
 '@BASEBOARD_FAB2_LIB.BASEBOARD_FAB2(SCH_1):M_M_CLK_DN'<1>:
 C_SIGNAL='@baseboard_fab2_lib.baseboard_fab2(sch_1):m_m_clk_dn(1)';
NODE_NAME     U2D1 DF55
 '@BASEBOARD_FAB2_LIB.BASEBOARD_FAB2(SCH_1):PAGE62_I172@CHPSET_LIB.SKX_EXT_B(CHIPS)':
 'DDR5_CLK_DN'<1>: CDS_PINID='DDR5_CLK_DN(1)';
NODE_NAME     J1A1 219
 '@BASEBOARD_FAB2_LIB.BASEBOARD_FAB2(SCH_1):PAGE87_I186@MSTR_SCONN.SCONN288_H44441004(CHIPS)':
 'CK1N': CDS_PINID='CK1N';
NET_NAME
'M_M_CLK_DN<2>'
 '@BASEBOARD_FAB2_LIB.BASEBOARD_FAB2(SCH_1):M_M_CLK_DN'<2>:
 C_SIGNAL='@baseboard_fab2_lib.baseboard_fab2(sch_1):m_m_clk_dn(2)';
NODE_NAME     U2D1 DK57
 '@BASEBOARD_FAB2_LIB.BASEBOARD_FAB2(SCH_1):PAGE62_I172@CHPSET_LIB.SKX_EXT_B(CHIPS)':
 'DDR5_CLK_DN'<2>: CDS_PINID='DDR5_CLK_DN(2)';
NODE_NAME     J9L1 75
 '@BASEBOARD_FAB2_LIB.BASEBOARD_FAB2(SCH_1):PAGE88_I111@MSTR_SCONN.SCONN288_H44441003(CHIPS)':
 'CK0N': CDS_PINID='CK0N';
NET_NAME
'M_M_CLK_DN<3>'
 '@BASEBOARD_FAB2_LIB.BASEBOARD_FAB2(SCH_1):M_M_CLK_DN'<3>:
 C_SIGNAL='@baseboard_fab2_lib.baseboard_fab2(sch_1):m_m_clk_dn(3)';
NODE_NAME     U2D1 DF57
 '@BASEBOARD_FAB2_LIB.BASEBOARD_FAB2(SCH_1):PAGE62_I172@CHPSET_LIB.SKX_EXT_B(CHIPS)':
 'DDR5_CLK_DN'<3>: CDS_PINID='DDR5_CLK_DN(3)';
NODE_NAME     J9L1 219
 '@BASEBOARD_FAB2_LIB.BASEBOARD_FAB2(SCH_1):PAGE88_I111@MSTR_SCONN.SCONN288_H44441003(CHIPS)':
 'CK1N': CDS_PINID='CK1N';
NET_NAME
'M_M_CLK_DP<0>'
 '@BASEBOARD_FAB2_LIB.BASEBOARD_FAB2(SCH_1):M_M_CLK_DP'<0>:
 C_SIGNAL='@baseboard_fab2_lib.baseboard_fab2(sch_1):m_m_clk_dp(0)';
NODE_NAME     U2D1 DJ54
 '@BASEBOARD_FAB2_LIB.BASEBOARD_FAB2(SCH_1):PAGE62_I172@CHPSET_LIB.SKX_EXT_B(CHIPS)':
 'DDR5_CLK_DP'<0>: CDS_PINID='DDR5_CLK_DP(0)';
NODE_NAME     J1A1 74
 '@BASEBOARD_FAB2_LIB.BASEBOARD_FAB2(SCH_1):PAGE87_I186@MSTR_SCONN.SCONN288_H44441004(CHIPS)':
 'CK0P': CDS_PINID='CK0P';
NET_NAME
'M_M_CLK_DP<1>'
 '@BASEBOARD_FAB2_LIB.BASEBOARD_FAB2(SCH_1):M_M_CLK_DP'<1>:
 C_SIGNAL='@baseboard_fab2_lib.baseboard_fab2(sch_1):m_m_clk_dp(1)';
NODE_NAME     U2D1 DG54
 '@BASEBOARD_FAB2_LIB.BASEBOARD_FAB2(SCH_1):PAGE62_I172@CHPSET_LIB.SKX_EXT_B(CHIPS)':
 'DDR5_CLK_DP'<1>: CDS_PINID='DDR5_CLK_DP(1)';
NODE_NAME     J1A1 218
 '@BASEBOARD_FAB2_LIB.BASEBOARD_FAB2(SCH_1):PAGE87_I186@MSTR_SCONN.SCONN288_H44441004(CHIPS)':
 'CK1P': CDS_PINID='CK1P';
NET_NAME
'M_M_CLK_DP<2>'
 '@BASEBOARD_FAB2_LIB.BASEBOARD_FAB2(SCH_1):M_M_CLK_DP'<2>:
 C_SIGNAL='@baseboard_fab2_lib.baseboard_fab2(sch_1):m_m_clk_dp(2)';
NODE_NAME     U2D1 DJ56
 '@BASEBOARD_FAB2_LIB.BASEBOARD_FAB2(SCH_1):PAGE62_I172@CHPSET_LIB.SKX_EXT_B(CHIPS)':
 'DDR5_CLK_DP'<2>: CDS_PINID='DDR5_CLK_DP(2)';
NODE_NAME     J9L1 74
 '@BASEBOARD_FAB2_LIB.BASEBOARD_FAB2(SCH_1):PAGE88_I111@MSTR_SCONN.SCONN288_H44441003(CHIPS)':
 'CK0P': CDS_PINID='CK0P';
NET_NAME
'M_M_CLK_DP<3>'
 '@BASEBOARD_FAB2_LIB.BASEBOARD_FAB2(SCH_1):M_M_CLK_DP'<3>:
 C_SIGNAL='@baseboard_fab2_lib.baseboard_fab2(sch_1):m_m_clk_dp(3)';
NODE_NAME     U2D1 DG56
 '@BASEBOARD_FAB2_LIB.BASEBOARD_FAB2(SCH_1):PAGE62_I172@CHPSET_LIB.SKX_EXT_B(CHIPS)':
 'DDR5_CLK_DP'<3>: CDS_PINID='DDR5_CLK_DP(3)';
NODE_NAME     J9L1 218
 '@BASEBOARD_FAB2_LIB.BASEBOARD_FAB2(SCH_1):PAGE88_I111@MSTR_SCONN.SCONN288_H44441003(CHIPS)':
 'CK1P': CDS_PINID='CK1P';
NET_NAME
'M_M_CPU_VREF'
 '@BASEBOARD_FAB2_LIB.BASEBOARD_FAB2(SCH_1):M_M_CPU_VREF':
 C_SIGNAL='@baseboard_fab2_lib.baseboard_fab2(sch_1):m_m_cpu_vref';
NODE_NAME     U2D1 CV61
 '@BASEBOARD_FAB2_LIB.BASEBOARD_FAB2(SCH_1):PAGE55_I172@CHPSET_LIB.SKX_EXT_B(CHIPS)':
 'DDR5_CAVREF': CDS_PINID='DDR5_CAVREF';
NODE_NAME     R9L3 1
 '@BASEBOARD_FAB2_LIB.BASEBOARD_FAB2(SCH_1):PAGE100_I45@MSTR_DISCRETE.RES(CHIPS)':
 'A': CDS_PINID='A';
NODE_NAME     C9L3 1
 '@BASEBOARD_FAB2_LIB.BASEBOARD_FAB2(SCH_1):PAGE100_I46@DEV_DISCRETE.CAP_A(CHIPS)':
 'A': CDS_PINID='A';
NET_NAME
'M_M_CS_N<0>'
 '@BASEBOARD_FAB2_LIB.BASEBOARD_FAB2(SCH_1):M_M_CS_N'<0>:
 C_SIGNAL='@baseboard_fab2_lib.baseboard_fab2(sch_1):m_m_cs_n(0)';
NODE_NAME     U2D1 DK51
 '@BASEBOARD_FAB2_LIB.BASEBOARD_FAB2(SCH_1):PAGE62_I172@CHPSET_LIB.SKX_EXT_B(CHIPS)':
 'DDR5_CS_N'<0>: CDS_PINID='DDR5_CS_N(0)';
NODE_NAME     J1A1 84
 '@BASEBOARD_FAB2_LIB.BASEBOARD_FAB2(SCH_1):PAGE87_I186@MSTR_SCONN.SCONN288_H44441004(CHIPS)':
 'S0_N': CDS_PINID='S0_N';
NET_NAME
'M_M_CS_N<1>'
 '@BASEBOARD_FAB2_LIB.BASEBOARD_FAB2(SCH_1):M_M_CS_N'<1>:
 C_SIGNAL='@baseboard_fab2_lib.baseboard_fab2(sch_1):m_m_cs_n(1)';
NODE_NAME     U2D1 DF49
 '@BASEBOARD_FAB2_LIB.BASEBOARD_FAB2(SCH_1):PAGE62_I172@CHPSET_LIB.SKX_EXT_B(CHIPS)':
 'DDR5_CS_N'<1>: CDS_PINID='DDR5_CS_N(1)';
NODE_NAME     J1A1 89
 '@BASEBOARD_FAB2_LIB.BASEBOARD_FAB2(SCH_1):PAGE87_I186@MSTR_SCONN.SCONN288_H44441004(CHIPS)':
 'S1_N': CDS_PINID='S1_N';
NET_NAME
'M_M_CS_N<2>'
 '@BASEBOARD_FAB2_LIB.BASEBOARD_FAB2(SCH_1):M_M_CS_N'<2>:
 C_SIGNAL='@baseboard_fab2_lib.baseboard_fab2(sch_1):m_m_cs_n(2)';
NODE_NAME     U2D1 DJ46
 '@BASEBOARD_FAB2_LIB.BASEBOARD_FAB2(SCH_1):PAGE62_I172@CHPSET_LIB.SKX_EXT_B(CHIPS)':
 'DDR5_CS_N'<2>: CDS_PINID='DDR5_CS_N(2)';
NODE_NAME     J1A1 93
 '@BASEBOARD_FAB2_LIB.BASEBOARD_FAB2(SCH_1):PAGE87_I186@MSTR_SCONN.SCONN288_H44441004(CHIPS)':
 'S2_N_C'<0>: CDS_PINID='S2_N_C(0)';
NET_NAME
'M_M_CS_N<3>'
 '@BASEBOARD_FAB2_LIB.BASEBOARD_FAB2(SCH_1):M_M_CS_N'<3>:
 C_SIGNAL='@baseboard_fab2_lib.baseboard_fab2(sch_1):m_m_cs_n(3)';
NODE_NAME     U2D1 DG46
 '@BASEBOARD_FAB2_LIB.BASEBOARD_FAB2(SCH_1):PAGE62_I172@CHPSET_LIB.SKX_EXT_B(CHIPS)':
 'DDR5_CS_N'<3>: CDS_PINID='DDR5_CS_N(3)';
NODE_NAME     J1A1 237
 '@BASEBOARD_FAB2_LIB.BASEBOARD_FAB2(SCH_1):PAGE87_I186@MSTR_SCONN.SCONN288_H44441004(CHIPS)':
 'S3_N_C'<1>: CDS_PINID='S3_N_C(1)';
NET_NAME
'M_M_CS_N<4>'
 '@BASEBOARD_FAB2_LIB.BASEBOARD_FAB2(SCH_1):M_M_CS_N'<4>:
 C_SIGNAL='@baseboard_fab2_lib.baseboard_fab2(sch_1):m_m_cs_n(4)';
NODE_NAME     U2D1 DF51
 '@BASEBOARD_FAB2_LIB.BASEBOARD_FAB2(SCH_1):PAGE62_I172@CHPSET_LIB.SKX_EXT_B(CHIPS)':
 'DDR5_CS_N'<4>: CDS_PINID='DDR5_CS_N(4)';
NODE_NAME     J9L1 84
 '@BASEBOARD_FAB2_LIB.BASEBOARD_FAB2(SCH_1):PAGE88_I111@MSTR_SCONN.SCONN288_H44441003(CHIPS)':
 'S0_N': CDS_PINID='S0_N';
NET_NAME
'M_M_CS_N<5>'
 '@BASEBOARD_FAB2_LIB.BASEBOARD_FAB2(SCH_1):M_M_CS_N'<5>:
 C_SIGNAL='@baseboard_fab2_lib.baseboard_fab2(sch_1):m_m_cs_n(5)';
NODE_NAME     U2D1 DJ48
 '@BASEBOARD_FAB2_LIB.BASEBOARD_FAB2(SCH_1):PAGE62_I172@CHPSET_LIB.SKX_EXT_B(CHIPS)':
 'DDR5_CS_N'<5>: CDS_PINID='DDR5_CS_N(5)';
NODE_NAME     J9L1 89
 '@BASEBOARD_FAB2_LIB.BASEBOARD_FAB2(SCH_1):PAGE88_I111@MSTR_SCONN.SCONN288_H44441003(CHIPS)':
 'S1_N': CDS_PINID='S1_N';
NET_NAME
'M_M_CS_N<6>'
 '@BASEBOARD_FAB2_LIB.BASEBOARD_FAB2(SCH_1):M_M_CS_N'<6>:
 C_SIGNAL='@baseboard_fab2_lib.baseboard_fab2(sch_1):m_m_cs_n(6)';
NODE_NAME     U2D1 DM45
 '@BASEBOARD_FAB2_LIB.BASEBOARD_FAB2(SCH_1):PAGE62_I172@CHPSET_LIB.SKX_EXT_B(CHIPS)':
 'DDR5_CS_N'<6>: CDS_PINID='DDR5_CS_N(6)';
NODE_NAME     J9L1 93
 '@BASEBOARD_FAB2_LIB.BASEBOARD_FAB2(SCH_1):PAGE88_I111@MSTR_SCONN.SCONN288_H44441003(CHIPS)':
 'S2_N_C'<0>: CDS_PINID='S2_N_C(0)';
NET_NAME
'M_M_CS_N<7>'
 '@BASEBOARD_FAB2_LIB.BASEBOARD_FAB2(SCH_1):M_M_CS_N'<7>:
 C_SIGNAL='@baseboard_fab2_lib.baseboard_fab2(sch_1):m_m_cs_n(7)';
NODE_NAME     U2D1 DK45
 '@BASEBOARD_FAB2_LIB.BASEBOARD_FAB2(SCH_1):PAGE62_I172@CHPSET_LIB.SKX_EXT_B(CHIPS)':
 'DDR5_CS_N'<7>: CDS_PINID='DDR5_CS_N(7)';
NODE_NAME     J9L1 237
 '@BASEBOARD_FAB2_LIB.BASEBOARD_FAB2(SCH_1):PAGE88_I111@MSTR_SCONN.SCONN288_H44441003(CHIPS)':
 'S3_N_C'<1>: CDS_PINID='S3_N_C(1)';
NET_NAME
'M_M_DQ<0>'
 '@BASEBOARD_FAB2_LIB.BASEBOARD_FAB2(SCH_1):M_M_DQ'<0>:
 C_SIGNAL='@baseboard_fab2_lib.baseboard_fab2(sch_1):m_m_dq(0)';
NODE_NAME     U2D1 CR74
 '@BASEBOARD_FAB2_LIB.BASEBOARD_FAB2(SCH_1):PAGE62_I172@CHPSET_LIB.SKX_EXT_B(CHIPS)':
 'DDR5_DQ'<0>: CDS_PINID='DDR5_DQ(0)';
NODE_NAME     J1A1 150
 '@BASEBOARD_FAB2_LIB.BASEBOARD_FAB2(SCH_1):PAGE87_I186@MSTR_SCONN.SCONN288_H44441004(CHIPS)':
 'DQ'<1>: CDS_PINID='DQ(1)';
NODE_NAME     J9L1 5
 '@BASEBOARD_FAB2_LIB.BASEBOARD_FAB2(SCH_1):PAGE88_I111@MSTR_SCONN.SCONN288_H44441003(CHIPS)':
 'DQ'<0>: CDS_PINID='DQ(0)';
NET_NAME
'M_M_DQ<10>'
 '@BASEBOARD_FAB2_LIB.BASEBOARD_FAB2(SCH_1):M_M_DQ'<10>:
 C_SIGNAL='@baseboard_fab2_lib.baseboard_fab2(sch_1):m_m_dq(10)';
NODE_NAME     U2D1 DH75
 '@BASEBOARD_FAB2_LIB.BASEBOARD_FAB2(SCH_1):PAGE62_I172@CHPSET_LIB.SKX_EXT_B(CHIPS)':
 'DDR5_DQ'<10>: CDS_PINID='DDR5_DQ(10)';
NODE_NAME     J1A1 168
 '@BASEBOARD_FAB2_LIB.BASEBOARD_FAB2(SCH_1):PAGE87_I186@MSTR_SCONN.SCONN288_H44441004(CHIPS)':
 'DQ'<11>: CDS_PINID='DQ(11)';
NODE_NAME     J9L1 23
 '@BASEBOARD_FAB2_LIB.BASEBOARD_FAB2(SCH_1):PAGE88_I111@MSTR_SCONN.SCONN288_H44441003(CHIPS)':
 'DQ'<10>: CDS_PINID='DQ(10)';
NET_NAME
'M_M_DQ<11>'
 '@BASEBOARD_FAB2_LIB.BASEBOARD_FAB2(SCH_1):M_M_DQ'<11>:
 C_SIGNAL='@baseboard_fab2_lib.baseboard_fab2(sch_1):m_m_dq(11)';
NODE_NAME     U2D1 DJ76
 '@BASEBOARD_FAB2_LIB.BASEBOARD_FAB2(SCH_1):PAGE62_I172@CHPSET_LIB.SKX_EXT_B(CHIPS)':
 'DDR5_DQ'<11>: CDS_PINID='DDR5_DQ(11)';
NODE_NAME     J1A1 23
 '@BASEBOARD_FAB2_LIB.BASEBOARD_FAB2(SCH_1):PAGE87_I186@MSTR_SCONN.SCONN288_H44441004(CHIPS)':
 'DQ'<10>: CDS_PINID='DQ(10)';
NODE_NAME     J9L1 168
 '@BASEBOARD_FAB2_LIB.BASEBOARD_FAB2(SCH_1):PAGE88_I111@MSTR_SCONN.SCONN288_H44441003(CHIPS)':
 'DQ'<11>: CDS_PINID='DQ(11)';
NET_NAME
'M_M_DQ<12>'
 '@BASEBOARD_FAB2_LIB.BASEBOARD_FAB2(SCH_1):M_M_DQ'<12>:
 C_SIGNAL='@baseboard_fab2_lib.baseboard_fab2(sch_1):m_m_dq(12)';
NODE_NAME     U2D1 DC74
 '@BASEBOARD_FAB2_LIB.BASEBOARD_FAB2(SCH_1):PAGE62_I172@CHPSET_LIB.SKX_EXT_B(CHIPS)':
 'DDR5_DQ'<12>: CDS_PINID='DDR5_DQ(12)';
NODE_NAME     J1A1 159
 '@BASEBOARD_FAB2_LIB.BASEBOARD_FAB2(SCH_1):PAGE87_I186@MSTR_SCONN.SCONN288_H44441004(CHIPS)':
 'DQ'<13>: CDS_PINID='DQ(13)';
NODE_NAME     J9L1 14
 '@BASEBOARD_FAB2_LIB.BASEBOARD_FAB2(SCH_1):PAGE88_I111@MSTR_SCONN.SCONN288_H44441003(CHIPS)':
 'DQ'<12>: CDS_PINID='DQ(12)';
NET_NAME
'M_M_DQ<13>'
 '@BASEBOARD_FAB2_LIB.BASEBOARD_FAB2(SCH_1):M_M_DQ'<13>:
 C_SIGNAL='@baseboard_fab2_lib.baseboard_fab2(sch_1):m_m_dq(13)';
NODE_NAME     U2D1 DB75
 '@BASEBOARD_FAB2_LIB.BASEBOARD_FAB2(SCH_1):PAGE62_I172@CHPSET_LIB.SKX_EXT_B(CHIPS)':
 'DDR5_DQ'<13>: CDS_PINID='DDR5_DQ(13)';
NODE_NAME     J1A1 14
 '@BASEBOARD_FAB2_LIB.BASEBOARD_FAB2(SCH_1):PAGE87_I186@MSTR_SCONN.SCONN288_H44441004(CHIPS)':
 'DQ'<12>: CDS_PINID='DQ(12)';
NODE_NAME     J9L1 159
 '@BASEBOARD_FAB2_LIB.BASEBOARD_FAB2(SCH_1):PAGE88_I111@MSTR_SCONN.SCONN288_H44441003(CHIPS)':
 'DQ'<13>: CDS_PINID='DQ(13)';
NET_NAME
'M_M_DQ<14>'
 '@BASEBOARD_FAB2_LIB.BASEBOARD_FAB2(SCH_1):M_M_DQ'<14>:
 C_SIGNAL='@baseboard_fab2_lib.baseboard_fab2(sch_1):m_m_dq(14)';
NODE_NAME     U2D1 DF77
 '@BASEBOARD_FAB2_LIB.BASEBOARD_FAB2(SCH_1):PAGE62_I172@CHPSET_LIB.SKX_EXT_B(CHIPS)':
 'DDR5_DQ'<14>: CDS_PINID='DDR5_DQ(14)';
NODE_NAME     J1A1 166
 '@BASEBOARD_FAB2_LIB.BASEBOARD_FAB2(SCH_1):PAGE87_I186@MSTR_SCONN.SCONN288_H44441004(CHIPS)':
 'DQ'<15>: CDS_PINID='DQ(15)';
NODE_NAME     J9L1 21
 '@BASEBOARD_FAB2_LIB.BASEBOARD_FAB2(SCH_1):PAGE88_I111@MSTR_SCONN.SCONN288_H44441003(CHIPS)':
 'DQ'<14>: CDS_PINID='DQ(14)';
NET_NAME
'M_M_DQ<15>'
 '@BASEBOARD_FAB2_LIB.BASEBOARD_FAB2(SCH_1):M_M_DQ'<15>:
 C_SIGNAL='@baseboard_fab2_lib.baseboard_fab2(sch_1):m_m_dq(15)';
NODE_NAME     U2D1 DH77
 '@BASEBOARD_FAB2_LIB.BASEBOARD_FAB2(SCH_1):PAGE62_I172@CHPSET_LIB.SKX_EXT_B(CHIPS)':
 'DDR5_DQ'<15>: CDS_PINID='DDR5_DQ(15)';
NODE_NAME     J1A1 21
 '@BASEBOARD_FAB2_LIB.BASEBOARD_FAB2(SCH_1):PAGE87_I186@MSTR_SCONN.SCONN288_H44441004(CHIPS)':
 'DQ'<14>: CDS_PINID='DQ(14)';
NODE_NAME     J9L1 166
 '@BASEBOARD_FAB2_LIB.BASEBOARD_FAB2(SCH_1):PAGE88_I111@MSTR_SCONN.SCONN288_H44441003(CHIPS)':
 'DQ'<15>: CDS_PINID='DQ(15)';
NET_NAME
'M_M_DQ<16>'
 '@BASEBOARD_FAB2_LIB.BASEBOARD_FAB2(SCH_1):M_M_DQ'<16>:
 C_SIGNAL='@baseboard_fab2_lib.baseboard_fab2(sch_1):m_m_dq(16)';
NODE_NAME     U2D1 DG70
 '@BASEBOARD_FAB2_LIB.BASEBOARD_FAB2(SCH_1):PAGE62_I172@CHPSET_LIB.SKX_EXT_B(CHIPS)':
 'DDR5_DQ'<16>: CDS_PINID='DDR5_DQ(16)';
NODE_NAME     J1A1 172
 '@BASEBOARD_FAB2_LIB.BASEBOARD_FAB2(SCH_1):PAGE87_I186@MSTR_SCONN.SCONN288_H44441004(CHIPS)':
 'DQ'<17>: CDS_PINID='DQ(17)';
NODE_NAME     J9L1 27
 '@BASEBOARD_FAB2_LIB.BASEBOARD_FAB2(SCH_1):PAGE88_I111@MSTR_SCONN.SCONN288_H44441003(CHIPS)':
 'DQ'<16>: CDS_PINID='DQ(16)';
NET_NAME
'M_M_DQ<17>'
 '@BASEBOARD_FAB2_LIB.BASEBOARD_FAB2(SCH_1):M_M_DQ'<17>:
 C_SIGNAL='@baseboard_fab2_lib.baseboard_fab2(sch_1):m_m_dq(17)';
NODE_NAME     U2D1 DJ72
 '@BASEBOARD_FAB2_LIB.BASEBOARD_FAB2(SCH_1):PAGE62_I172@CHPSET_LIB.SKX_EXT_B(CHIPS)':
 'DDR5_DQ'<17>: CDS_PINID='DDR5_DQ(17)';
NODE_NAME     J1A1 27
 '@BASEBOARD_FAB2_LIB.BASEBOARD_FAB2(SCH_1):PAGE87_I186@MSTR_SCONN.SCONN288_H44441004(CHIPS)':
 'DQ'<16>: CDS_PINID='DQ(16)';
NODE_NAME     J9L1 172
 '@BASEBOARD_FAB2_LIB.BASEBOARD_FAB2(SCH_1):PAGE88_I111@MSTR_SCONN.SCONN288_H44441003(CHIPS)':
 'DQ'<17>: CDS_PINID='DQ(17)';
NET_NAME
'M_M_DQ<18>'
 '@BASEBOARD_FAB2_LIB.BASEBOARD_FAB2(SCH_1):M_M_DQ'<18>:
 C_SIGNAL='@baseboard_fab2_lib.baseboard_fab2(sch_1):m_m_dq(18)';
NODE_NAME     U2D1 DM69
 '@BASEBOARD_FAB2_LIB.BASEBOARD_FAB2(SCH_1):PAGE62_I172@CHPSET_LIB.SKX_EXT_B(CHIPS)':
 'DDR5_DQ'<18>: CDS_PINID='DDR5_DQ(18)';
NODE_NAME     J1A1 179
 '@BASEBOARD_FAB2_LIB.BASEBOARD_FAB2(SCH_1):PAGE87_I186@MSTR_SCONN.SCONN288_H44441004(CHIPS)':
 'DQ'<19>: CDS_PINID='DQ(19)';
NODE_NAME     J9L1 34
 '@BASEBOARD_FAB2_LIB.BASEBOARD_FAB2(SCH_1):PAGE88_I111@MSTR_SCONN.SCONN288_H44441003(CHIPS)':
 'DQ'<18>: CDS_PINID='DQ(18)';
NET_NAME
'M_M_DQ<19>'
 '@BASEBOARD_FAB2_LIB.BASEBOARD_FAB2(SCH_1):M_M_DQ'<19>:
 C_SIGNAL='@baseboard_fab2_lib.baseboard_fab2(sch_1):m_m_dq(19)';
NODE_NAME     U2D1 DN70
 '@BASEBOARD_FAB2_LIB.BASEBOARD_FAB2(SCH_1):PAGE62_I172@CHPSET_LIB.SKX_EXT_B(CHIPS)':
 'DDR5_DQ'<19>: CDS_PINID='DDR5_DQ(19)';
NODE_NAME     J1A1 34
 '@BASEBOARD_FAB2_LIB.BASEBOARD_FAB2(SCH_1):PAGE87_I186@MSTR_SCONN.SCONN288_H44441004(CHIPS)':
 'DQ'<18>: CDS_PINID='DQ(18)';
NODE_NAME     J9L1 179
 '@BASEBOARD_FAB2_LIB.BASEBOARD_FAB2(SCH_1):PAGE88_I111@MSTR_SCONN.SCONN288_H44441003(CHIPS)':
 'DQ'<19>: CDS_PINID='DQ(19)';
NET_NAME
'M_M_DQ<1>'
 '@BASEBOARD_FAB2_LIB.BASEBOARD_FAB2(SCH_1):M_M_DQ'<1>:
 C_SIGNAL='@baseboard_fab2_lib.baseboard_fab2(sch_1):m_m_dq(1)';
NODE_NAME     U2D1 CN76
 '@BASEBOARD_FAB2_LIB.BASEBOARD_FAB2(SCH_1):PAGE62_I172@CHPSET_LIB.SKX_EXT_B(CHIPS)':
 'DDR5_DQ'<1>: CDS_PINID='DDR5_DQ(1)';
NODE_NAME     J1A1 5
 '@BASEBOARD_FAB2_LIB.BASEBOARD_FAB2(SCH_1):PAGE87_I186@MSTR_SCONN.SCONN288_H44441004(CHIPS)':
 'DQ'<0>: CDS_PINID='DQ(0)';
NODE_NAME     J9L1 150
 '@BASEBOARD_FAB2_LIB.BASEBOARD_FAB2(SCH_1):PAGE88_I111@MSTR_SCONN.SCONN288_H44441003(CHIPS)':
 'DQ'<1>: CDS_PINID='DQ(1)';
NET_NAME
'M_M_DQ<20>'
 '@BASEBOARD_FAB2_LIB.BASEBOARD_FAB2(SCH_1):M_M_DQ'<20>:
 C_SIGNAL='@baseboard_fab2_lib.baseboard_fab2(sch_1):m_m_dq(20)';
NODE_NAME     U2D1 DF71
 '@BASEBOARD_FAB2_LIB.BASEBOARD_FAB2(SCH_1):PAGE62_I172@CHPSET_LIB.SKX_EXT_B(CHIPS)':
 'DDR5_DQ'<20>: CDS_PINID='DDR5_DQ(20)';
NODE_NAME     J1A1 170
 '@BASEBOARD_FAB2_LIB.BASEBOARD_FAB2(SCH_1):PAGE87_I186@MSTR_SCONN.SCONN288_H44441004(CHIPS)':
 'DQ'<21>: CDS_PINID='DQ(21)';
NODE_NAME     J9L1 25
 '@BASEBOARD_FAB2_LIB.BASEBOARD_FAB2(SCH_1):PAGE88_I111@MSTR_SCONN.SCONN288_H44441003(CHIPS)':
 'DQ'<20>: CDS_PINID='DQ(20)';
NET_NAME
'M_M_DQ<21>'
 '@BASEBOARD_FAB2_LIB.BASEBOARD_FAB2(SCH_1):M_M_DQ'<21>:
 C_SIGNAL='@baseboard_fab2_lib.baseboard_fab2(sch_1):m_m_dq(21)';
NODE_NAME     U2D1 DG72
 '@BASEBOARD_FAB2_LIB.BASEBOARD_FAB2(SCH_1):PAGE62_I172@CHPSET_LIB.SKX_EXT_B(CHIPS)':
 'DDR5_DQ'<21>: CDS_PINID='DDR5_DQ(21)';
NODE_NAME     J1A1 25
 '@BASEBOARD_FAB2_LIB.BASEBOARD_FAB2(SCH_1):PAGE87_I186@MSTR_SCONN.SCONN288_H44441004(CHIPS)':
 'DQ'<20>: CDS_PINID='DQ(20)';
NODE_NAME     J9L1 170
 '@BASEBOARD_FAB2_LIB.BASEBOARD_FAB2(SCH_1):PAGE88_I111@MSTR_SCONN.SCONN288_H44441003(CHIPS)':
 'DQ'<21>: CDS_PINID='DQ(21)';
NET_NAME
'M_M_DQ<22>'
 '@BASEBOARD_FAB2_LIB.BASEBOARD_FAB2(SCH_1):M_M_DQ'<22>:
 C_SIGNAL='@baseboard_fab2_lib.baseboard_fab2(sch_1):m_m_dq(22)';
NODE_NAME     U2D1 DK69
 '@BASEBOARD_FAB2_LIB.BASEBOARD_FAB2(SCH_1):PAGE62_I172@CHPSET_LIB.SKX_EXT_B(CHIPS)':
 'DDR5_DQ'<22>: CDS_PINID='DDR5_DQ(22)';
NODE_NAME     J1A1 177
 '@BASEBOARD_FAB2_LIB.BASEBOARD_FAB2(SCH_1):PAGE87_I186@MSTR_SCONN.SCONN288_H44441004(CHIPS)':
 'DQ'<23>: CDS_PINID='DQ(23)';
NODE_NAME     J9L1 32
 '@BASEBOARD_FAB2_LIB.BASEBOARD_FAB2(SCH_1):PAGE88_I111@MSTR_SCONN.SCONN288_H44441003(CHIPS)':
 'DQ'<22>: CDS_PINID='DQ(22)';
NET_NAME
'M_M_DQ<23>'
 '@BASEBOARD_FAB2_LIB.BASEBOARD_FAB2(SCH_1):M_M_DQ'<23>:
 C_SIGNAL='@baseboard_fab2_lib.baseboard_fab2(sch_1):m_m_dq(23)';
NODE_NAME     U2D1 DM71
 '@BASEBOARD_FAB2_LIB.BASEBOARD_FAB2(SCH_1):PAGE62_I172@CHPSET_LIB.SKX_EXT_B(CHIPS)':
 'DDR5_DQ'<23>: CDS_PINID='DDR5_DQ(23)';
NODE_NAME     J1A1 32
 '@BASEBOARD_FAB2_LIB.BASEBOARD_FAB2(SCH_1):PAGE87_I186@MSTR_SCONN.SCONN288_H44441004(CHIPS)':
 'DQ'<22>: CDS_PINID='DQ(22)';
NODE_NAME     J9L1 177
 '@BASEBOARD_FAB2_LIB.BASEBOARD_FAB2(SCH_1):PAGE88_I111@MSTR_SCONN.SCONN288_H44441003(CHIPS)':
 'DQ'<23>: CDS_PINID='DQ(23)';
NET_NAME
'M_M_DQ<24>'
 '@BASEBOARD_FAB2_LIB.BASEBOARD_FAB2(SCH_1):M_M_DQ'<24>:
 C_SIGNAL='@baseboard_fab2_lib.baseboard_fab2(sch_1):m_m_dq(24)';
NODE_NAME     U2D1 CN66
 '@BASEBOARD_FAB2_LIB.BASEBOARD_FAB2(SCH_1):PAGE62_I172@CHPSET_LIB.SKX_EXT_B(CHIPS)':
 'DDR5_DQ'<24>: CDS_PINID='DDR5_DQ(24)';
NODE_NAME     J1A1 183
 '@BASEBOARD_FAB2_LIB.BASEBOARD_FAB2(SCH_1):PAGE87_I186@MSTR_SCONN.SCONN288_H44441004(CHIPS)':
 'DQ'<25>: CDS_PINID='DQ(25)';
NODE_NAME     J9L1 38
 '@BASEBOARD_FAB2_LIB.BASEBOARD_FAB2(SCH_1):PAGE88_I111@MSTR_SCONN.SCONN288_H44441003(CHIPS)':
 'DQ'<24>: CDS_PINID='DQ(24)';
NET_NAME
'M_M_DQ<25>'
 '@BASEBOARD_FAB2_LIB.BASEBOARD_FAB2(SCH_1):M_M_DQ'<25>:
 C_SIGNAL='@baseboard_fab2_lib.baseboard_fab2(sch_1):m_m_dq(25)';
NODE_NAME     U2D1 CU66
 '@BASEBOARD_FAB2_LIB.BASEBOARD_FAB2(SCH_1):PAGE62_I172@CHPSET_LIB.SKX_EXT_B(CHIPS)':
 'DDR5_DQ'<25>: CDS_PINID='DDR5_DQ(25)';
NODE_NAME     J1A1 38
 '@BASEBOARD_FAB2_LIB.BASEBOARD_FAB2(SCH_1):PAGE87_I186@MSTR_SCONN.SCONN288_H44441004(CHIPS)':
 'DQ'<24>: CDS_PINID='DQ(24)';
NODE_NAME     J9L1 183
 '@BASEBOARD_FAB2_LIB.BASEBOARD_FAB2(SCH_1):PAGE88_I111@MSTR_SCONN.SCONN288_H44441003(CHIPS)':
 'DQ'<25>: CDS_PINID='DQ(25)';
NET_NAME
'M_M_DQ<26>'
 '@BASEBOARD_FAB2_LIB.BASEBOARD_FAB2(SCH_1):M_M_DQ'<26>:
 C_SIGNAL='@baseboard_fab2_lib.baseboard_fab2(sch_1):m_m_dq(26)';
NODE_NAME     U2D1 CP63
 '@BASEBOARD_FAB2_LIB.BASEBOARD_FAB2(SCH_1):PAGE62_I172@CHPSET_LIB.SKX_EXT_B(CHIPS)':
 'DDR5_DQ'<26>: CDS_PINID='DDR5_DQ(26)';
NODE_NAME     J1A1 190
 '@BASEBOARD_FAB2_LIB.BASEBOARD_FAB2(SCH_1):PAGE87_I186@MSTR_SCONN.SCONN288_H44441004(CHIPS)':
 'DQ'<27>: CDS_PINID='DQ(27)';
NODE_NAME     J9L1 45
 '@BASEBOARD_FAB2_LIB.BASEBOARD_FAB2(SCH_1):PAGE88_I111@MSTR_SCONN.SCONN288_H44441003(CHIPS)':
 'DQ'<26>: CDS_PINID='DQ(26)';
NET_NAME
'M_M_DQ<27>'
 '@BASEBOARD_FAB2_LIB.BASEBOARD_FAB2(SCH_1):M_M_DQ'<27>:
 C_SIGNAL='@baseboard_fab2_lib.baseboard_fab2(sch_1):m_m_dq(27)';
NODE_NAME     U2D1 CT63
 '@BASEBOARD_FAB2_LIB.BASEBOARD_FAB2(SCH_1):PAGE62_I172@CHPSET_LIB.SKX_EXT_B(CHIPS)':
 'DDR5_DQ'<27>: CDS_PINID='DDR5_DQ(27)';
NODE_NAME     J1A1 45
 '@BASEBOARD_FAB2_LIB.BASEBOARD_FAB2(SCH_1):PAGE87_I186@MSTR_SCONN.SCONN288_H44441004(CHIPS)':
 'DQ'<26>: CDS_PINID='DQ(26)';
NODE_NAME     J9L1 190
 '@BASEBOARD_FAB2_LIB.BASEBOARD_FAB2(SCH_1):PAGE88_I111@MSTR_SCONN.SCONN288_H44441003(CHIPS)':
 'DQ'<27>: CDS_PINID='DQ(27)';
NET_NAME
'M_M_DQ<28>'
 '@BASEBOARD_FAB2_LIB.BASEBOARD_FAB2(SCH_1):M_M_DQ'<28>:
 C_SIGNAL='@baseboard_fab2_lib.baseboard_fab2(sch_1):m_m_dq(28)';
NODE_NAME     U2D1 CP67
 '@BASEBOARD_FAB2_LIB.BASEBOARD_FAB2(SCH_1):PAGE62_I172@CHPSET_LIB.SKX_EXT_B(CHIPS)':
 'DDR5_DQ'<28>: CDS_PINID='DDR5_DQ(28)';
NODE_NAME     J1A1 181
 '@BASEBOARD_FAB2_LIB.BASEBOARD_FAB2(SCH_1):PAGE87_I186@MSTR_SCONN.SCONN288_H44441004(CHIPS)':
 'DQ'<29>: CDS_PINID='DQ(29)';
NODE_NAME     J9L1 36
 '@BASEBOARD_FAB2_LIB.BASEBOARD_FAB2(SCH_1):PAGE88_I111@MSTR_SCONN.SCONN288_H44441003(CHIPS)':
 'DQ'<28>: CDS_PINID='DQ(28)';
NET_NAME
'M_M_DQ<29>'
 '@BASEBOARD_FAB2_LIB.BASEBOARD_FAB2(SCH_1):M_M_DQ'<29>:
 C_SIGNAL='@baseboard_fab2_lib.baseboard_fab2(sch_1):m_m_dq(29)';
NODE_NAME     U2D1 CT67
 '@BASEBOARD_FAB2_LIB.BASEBOARD_FAB2(SCH_1):PAGE62_I172@CHPSET_LIB.SKX_EXT_B(CHIPS)':
 'DDR5_DQ'<29>: CDS_PINID='DDR5_DQ(29)';
NODE_NAME     J1A1 36
 '@BASEBOARD_FAB2_LIB.BASEBOARD_FAB2(SCH_1):PAGE87_I186@MSTR_SCONN.SCONN288_H44441004(CHIPS)':
 'DQ'<28>: CDS_PINID='DQ(28)';
NODE_NAME     J9L1 181
 '@BASEBOARD_FAB2_LIB.BASEBOARD_FAB2(SCH_1):PAGE88_I111@MSTR_SCONN.SCONN288_H44441003(CHIPS)':
 'DQ'<29>: CDS_PINID='DQ(29)';
NET_NAME
'M_M_DQ<2>'
 '@BASEBOARD_FAB2_LIB.BASEBOARD_FAB2(SCH_1):M_M_DQ'<2>:
 C_SIGNAL='@baseboard_fab2_lib.baseboard_fab2(sch_1):m_m_dq(2)';
NODE_NAME     U2D1 CW76
 '@BASEBOARD_FAB2_LIB.BASEBOARD_FAB2(SCH_1):PAGE62_I172@CHPSET_LIB.SKX_EXT_B(CHIPS)':
 'DDR5_DQ'<2>: CDS_PINID='DDR5_DQ(2)';
NODE_NAME     J1A1 157
 '@BASEBOARD_FAB2_LIB.BASEBOARD_FAB2(SCH_1):PAGE87_I186@MSTR_SCONN.SCONN288_H44441004(CHIPS)':
 'DQ'<3>: CDS_PINID='DQ(3)';
NODE_NAME     J9L1 12
 '@BASEBOARD_FAB2_LIB.BASEBOARD_FAB2(SCH_1):PAGE88_I111@MSTR_SCONN.SCONN288_H44441003(CHIPS)':
 'DQ'<2>: CDS_PINID='DQ(2)';
NET_NAME
'M_M_DQ<30>'
 '@BASEBOARD_FAB2_LIB.BASEBOARD_FAB2(SCH_1):M_M_DQ'<30>:
 C_SIGNAL='@baseboard_fab2_lib.baseboard_fab2(sch_1):m_m_dq(30)';
NODE_NAME     U2D1 CN64
 '@BASEBOARD_FAB2_LIB.BASEBOARD_FAB2(SCH_1):PAGE62_I172@CHPSET_LIB.SKX_EXT_B(CHIPS)':
 'DDR5_DQ'<30>: CDS_PINID='DDR5_DQ(30)';
NODE_NAME     J1A1 188
 '@BASEBOARD_FAB2_LIB.BASEBOARD_FAB2(SCH_1):PAGE87_I186@MSTR_SCONN.SCONN288_H44441004(CHIPS)':
 'DQ'<31>: CDS_PINID='DQ(31)';
NODE_NAME     J9L1 43
 '@BASEBOARD_FAB2_LIB.BASEBOARD_FAB2(SCH_1):PAGE88_I111@MSTR_SCONN.SCONN288_H44441003(CHIPS)':
 'DQ'<30>: CDS_PINID='DQ(30)';
NET_NAME
'M_M_DQ<31>'
 '@BASEBOARD_FAB2_LIB.BASEBOARD_FAB2(SCH_1):M_M_DQ'<31>:
 C_SIGNAL='@baseboard_fab2_lib.baseboard_fab2(sch_1):m_m_dq(31)';
NODE_NAME     U2D1 CU64
 '@BASEBOARD_FAB2_LIB.BASEBOARD_FAB2(SCH_1):PAGE62_I172@CHPSET_LIB.SKX_EXT_B(CHIPS)':
 'DDR5_DQ'<31>: CDS_PINID='DDR5_DQ(31)';
NODE_NAME     J1A1 43
 '@BASEBOARD_FAB2_LIB.BASEBOARD_FAB2(SCH_1):PAGE87_I186@MSTR_SCONN.SCONN288_H44441004(CHIPS)':
 'DQ'<30>: CDS_PINID='DQ(30)';
NODE_NAME     J9L1 188
 '@BASEBOARD_FAB2_LIB.BASEBOARD_FAB2(SCH_1):PAGE88_I111@MSTR_SCONN.SCONN288_H44441003(CHIPS)':
 'DQ'<31>: CDS_PINID='DQ(31)';
NET_NAME
'M_M_DQ<32>'
 '@BASEBOARD_FAB2_LIB.BASEBOARD_FAB2(SCH_1):M_M_DQ'<32>:
 C_SIGNAL='@baseboard_fab2_lib.baseboard_fab2(sch_1):m_m_dq(32)';
NODE_NAME     U2D1 DD41
 '@BASEBOARD_FAB2_LIB.BASEBOARD_FAB2(SCH_1):PAGE62_I172@CHPSET_LIB.SKX_EXT_B(CHIPS)':
 'DDR5_DQ'<32>: CDS_PINID='DDR5_DQ(32)';
NODE_NAME     J1A1 242
 '@BASEBOARD_FAB2_LIB.BASEBOARD_FAB2(SCH_1):PAGE87_I186@MSTR_SCONN.SCONN288_H44441004(CHIPS)':
 'DQ'<33>: CDS_PINID='DQ(33)';
NODE_NAME     J9L1 97
 '@BASEBOARD_FAB2_LIB.BASEBOARD_FAB2(SCH_1):PAGE88_I111@MSTR_SCONN.SCONN288_H44441003(CHIPS)':
 'DQ'<32>: CDS_PINID='DQ(32)';
NET_NAME
'M_M_DQ<33>'
 '@BASEBOARD_FAB2_LIB.BASEBOARD_FAB2(SCH_1):M_M_DQ'<33>:
 C_SIGNAL='@baseboard_fab2_lib.baseboard_fab2(sch_1):m_m_dq(33)';
NODE_NAME     U2D1 DG42
 '@BASEBOARD_FAB2_LIB.BASEBOARD_FAB2(SCH_1):PAGE62_I172@CHPSET_LIB.SKX_EXT_B(CHIPS)':
 'DDR5_DQ'<33>: CDS_PINID='DDR5_DQ(33)';
NODE_NAME     J1A1 97
 '@BASEBOARD_FAB2_LIB.BASEBOARD_FAB2(SCH_1):PAGE87_I186@MSTR_SCONN.SCONN288_H44441004(CHIPS)':
 'DQ'<32>: CDS_PINID='DQ(32)';
NODE_NAME     J9L1 242
 '@BASEBOARD_FAB2_LIB.BASEBOARD_FAB2(SCH_1):PAGE88_I111@MSTR_SCONN.SCONN288_H44441003(CHIPS)':
 'DQ'<33>: CDS_PINID='DQ(33)';
NET_NAME
'M_M_DQ<34>'
 '@BASEBOARD_FAB2_LIB.BASEBOARD_FAB2(SCH_1):M_M_DQ'<34>:
 C_SIGNAL='@baseboard_fab2_lib.baseboard_fab2(sch_1):m_m_dq(34)';
NODE_NAME     U2D1 DE38
 '@BASEBOARD_FAB2_LIB.BASEBOARD_FAB2(SCH_1):PAGE62_I172@CHPSET_LIB.SKX_EXT_B(CHIPS)':
 'DDR5_DQ'<34>: CDS_PINID='DDR5_DQ(34)';
NODE_NAME     J1A1 249
 '@BASEBOARD_FAB2_LIB.BASEBOARD_FAB2(SCH_1):PAGE87_I186@MSTR_SCONN.SCONN288_H44441004(CHIPS)':
 'DQ'<35>: CDS_PINID='DQ(35)';
NODE_NAME     J9L1 104
 '@BASEBOARD_FAB2_LIB.BASEBOARD_FAB2(SCH_1):PAGE88_I111@MSTR_SCONN.SCONN288_H44441003(CHIPS)':
 'DQ'<34>: CDS_PINID='DQ(34)';
NET_NAME
'M_M_DQ<35>'
 '@BASEBOARD_FAB2_LIB.BASEBOARD_FAB2(SCH_1):M_M_DQ'<35>:
 C_SIGNAL='@baseboard_fab2_lib.baseboard_fab2(sch_1):m_m_dq(35)';
NODE_NAME     U2D1 DG38
 '@BASEBOARD_FAB2_LIB.BASEBOARD_FAB2(SCH_1):PAGE62_I172@CHPSET_LIB.SKX_EXT_B(CHIPS)':
 'DDR5_DQ'<35>: CDS_PINID='DDR5_DQ(35)';
NODE_NAME     J1A1 104
 '@BASEBOARD_FAB2_LIB.BASEBOARD_FAB2(SCH_1):PAGE87_I186@MSTR_SCONN.SCONN288_H44441004(CHIPS)':
 'DQ'<34>: CDS_PINID='DQ(34)';
NODE_NAME     J9L1 249
 '@BASEBOARD_FAB2_LIB.BASEBOARD_FAB2(SCH_1):PAGE88_I111@MSTR_SCONN.SCONN288_H44441003(CHIPS)':
 'DQ'<35>: CDS_PINID='DQ(35)';
NET_NAME
'M_M_DQ<36>'
 '@BASEBOARD_FAB2_LIB.BASEBOARD_FAB2(SCH_1):M_M_DQ'<36>:
 C_SIGNAL='@baseboard_fab2_lib.baseboard_fab2(sch_1):m_m_dq(36)';
NODE_NAME     U2D1 DA42
 '@BASEBOARD_FAB2_LIB.BASEBOARD_FAB2(SCH_1):PAGE62_I172@CHPSET_LIB.SKX_EXT_B(CHIPS)':
 'DDR5_DQ'<36>: CDS_PINID='DDR5_DQ(36)';
NODE_NAME     J1A1 240
 '@BASEBOARD_FAB2_LIB.BASEBOARD_FAB2(SCH_1):PAGE87_I186@MSTR_SCONN.SCONN288_H44441004(CHIPS)':
 'DQ'<37>: CDS_PINID='DQ(37)';
NODE_NAME     J9L1 95
 '@BASEBOARD_FAB2_LIB.BASEBOARD_FAB2(SCH_1):PAGE88_I111@MSTR_SCONN.SCONN288_H44441003(CHIPS)':
 'DQ'<36>: CDS_PINID='DQ(36)';
NET_NAME
'M_M_DQ<37>'
 '@BASEBOARD_FAB2_LIB.BASEBOARD_FAB2(SCH_1):M_M_DQ'<37>:
 C_SIGNAL='@baseboard_fab2_lib.baseboard_fab2(sch_1):m_m_dq(37)';
NODE_NAME     U2D1 DE42
 '@BASEBOARD_FAB2_LIB.BASEBOARD_FAB2(SCH_1):PAGE62_I172@CHPSET_LIB.SKX_EXT_B(CHIPS)':
 'DDR5_DQ'<37>: CDS_PINID='DDR5_DQ(37)';
NODE_NAME     J1A1 95
 '@BASEBOARD_FAB2_LIB.BASEBOARD_FAB2(SCH_1):PAGE87_I186@MSTR_SCONN.SCONN288_H44441004(CHIPS)':
 'DQ'<36>: CDS_PINID='DQ(36)';
NODE_NAME     J9L1 240
 '@BASEBOARD_FAB2_LIB.BASEBOARD_FAB2(SCH_1):PAGE88_I111@MSTR_SCONN.SCONN288_H44441003(CHIPS)':
 'DQ'<37>: CDS_PINID='DQ(37)';
NET_NAME
'M_M_DQ<38>'
 '@BASEBOARD_FAB2_LIB.BASEBOARD_FAB2(SCH_1):M_M_DQ'<38>:
 C_SIGNAL='@baseboard_fab2_lib.baseboard_fab2(sch_1):m_m_dq(38)';
NODE_NAME     U2D1 DD39
 '@BASEBOARD_FAB2_LIB.BASEBOARD_FAB2(SCH_1):PAGE62_I172@CHPSET_LIB.SKX_EXT_B(CHIPS)':
 'DDR5_DQ'<38>: CDS_PINID='DDR5_DQ(38)';
NODE_NAME     J1A1 247
 '@BASEBOARD_FAB2_LIB.BASEBOARD_FAB2(SCH_1):PAGE87_I186@MSTR_SCONN.SCONN288_H44441004(CHIPS)':
 'DQ'<39>: CDS_PINID='DQ(39)';
NODE_NAME     J9L1 102
 '@BASEBOARD_FAB2_LIB.BASEBOARD_FAB2(SCH_1):PAGE88_I111@MSTR_SCONN.SCONN288_H44441003(CHIPS)':
 'DQ'<38>: CDS_PINID='DQ(38)';
NET_NAME
'M_M_DQ<39>'
 '@BASEBOARD_FAB2_LIB.BASEBOARD_FAB2(SCH_1):M_M_DQ'<39>:
 C_SIGNAL='@baseboard_fab2_lib.baseboard_fab2(sch_1):m_m_dq(39)';
NODE_NAME     U2D1 DH39
 '@BASEBOARD_FAB2_LIB.BASEBOARD_FAB2(SCH_1):PAGE62_I172@CHPSET_LIB.SKX_EXT_B(CHIPS)':
 'DDR5_DQ'<39>: CDS_PINID='DDR5_DQ(39)';
NODE_NAME     J1A1 102
 '@BASEBOARD_FAB2_LIB.BASEBOARD_FAB2(SCH_1):PAGE87_I186@MSTR_SCONN.SCONN288_H44441004(CHIPS)':
 'DQ'<38>: CDS_PINID='DQ(38)';
NODE_NAME     J9L1 247
 '@BASEBOARD_FAB2_LIB.BASEBOARD_FAB2(SCH_1):PAGE88_I111@MSTR_SCONN.SCONN288_H44441003(CHIPS)':
 'DQ'<39>: CDS_PINID='DQ(39)';
NET_NAME
'M_M_DQ<3>'
 '@BASEBOARD_FAB2_LIB.BASEBOARD_FAB2(SCH_1):M_M_DQ'<3>:
 C_SIGNAL='@baseboard_fab2_lib.baseboard_fab2(sch_1):m_m_dq(3)';
NODE_NAME     U2D1 CV77
 '@BASEBOARD_FAB2_LIB.BASEBOARD_FAB2(SCH_1):PAGE62_I172@CHPSET_LIB.SKX_EXT_B(CHIPS)':
 'DDR5_DQ'<3>: CDS_PINID='DDR5_DQ(3)';
NODE_NAME     J1A1 12
 '@BASEBOARD_FAB2_LIB.BASEBOARD_FAB2(SCH_1):PAGE87_I186@MSTR_SCONN.SCONN288_H44441004(CHIPS)':
 'DQ'<2>: CDS_PINID='DQ(2)';
NODE_NAME     J9L1 157
 '@BASEBOARD_FAB2_LIB.BASEBOARD_FAB2(SCH_1):PAGE88_I111@MSTR_SCONN.SCONN288_H44441003(CHIPS)':
 'DQ'<3>: CDS_PINID='DQ(3)';
NET_NAME
'M_M_DQ<40>'
 '@BASEBOARD_FAB2_LIB.BASEBOARD_FAB2(SCH_1):M_M_DQ'<40>:
 C_SIGNAL='@baseboard_fab2_lib.baseboard_fab2(sch_1):m_m_dq(40)';
NODE_NAME     U2D1 DF33
 '@BASEBOARD_FAB2_LIB.BASEBOARD_FAB2(SCH_1):PAGE62_I172@CHPSET_LIB.SKX_EXT_B(CHIPS)':
 'DDR5_DQ'<40>: CDS_PINID='DDR5_DQ(40)';
NODE_NAME     J1A1 253
 '@BASEBOARD_FAB2_LIB.BASEBOARD_FAB2(SCH_1):PAGE87_I186@MSTR_SCONN.SCONN288_H44441004(CHIPS)':
 'DQ'<41>: CDS_PINID='DQ(41)';
NODE_NAME     J9L1 108
 '@BASEBOARD_FAB2_LIB.BASEBOARD_FAB2(SCH_1):PAGE88_I111@MSTR_SCONN.SCONN288_H44441003(CHIPS)':
 'DQ'<40>: CDS_PINID='DQ(40)';
NET_NAME
'M_M_DQ<41>'
 '@BASEBOARD_FAB2_LIB.BASEBOARD_FAB2(SCH_1):M_M_DQ'<41>:
 C_SIGNAL='@baseboard_fab2_lib.baseboard_fab2(sch_1):m_m_dq(41)';
NODE_NAME     U2D1 DK33
 '@BASEBOARD_FAB2_LIB.BASEBOARD_FAB2(SCH_1):PAGE62_I172@CHPSET_LIB.SKX_EXT_B(CHIPS)':
 'DDR5_DQ'<41>: CDS_PINID='DDR5_DQ(41)';
NODE_NAME     J1A1 108
 '@BASEBOARD_FAB2_LIB.BASEBOARD_FAB2(SCH_1):PAGE87_I186@MSTR_SCONN.SCONN288_H44441004(CHIPS)':
 'DQ'<40>: CDS_PINID='DQ(40)';
NODE_NAME     J9L1 253
 '@BASEBOARD_FAB2_LIB.BASEBOARD_FAB2(SCH_1):PAGE88_I111@MSTR_SCONN.SCONN288_H44441003(CHIPS)':
 'DQ'<41>: CDS_PINID='DQ(41)';
NET_NAME
'M_M_DQ<42>'
 '@BASEBOARD_FAB2_LIB.BASEBOARD_FAB2(SCH_1):M_M_DQ'<42>:
 C_SIGNAL='@baseboard_fab2_lib.baseboard_fab2(sch_1):m_m_dq(42)';
NODE_NAME     U2D1 DG30
 '@BASEBOARD_FAB2_LIB.BASEBOARD_FAB2(SCH_1):PAGE62_I172@CHPSET_LIB.SKX_EXT_B(CHIPS)':
 'DDR5_DQ'<42>: CDS_PINID='DDR5_DQ(42)';
NODE_NAME     J1A1 260
 '@BASEBOARD_FAB2_LIB.BASEBOARD_FAB2(SCH_1):PAGE87_I186@MSTR_SCONN.SCONN288_H44441004(CHIPS)':
 'DQ'<43>: CDS_PINID='DQ(43)';
NODE_NAME     J9L1 115
 '@BASEBOARD_FAB2_LIB.BASEBOARD_FAB2(SCH_1):PAGE88_I111@MSTR_SCONN.SCONN288_H44441003(CHIPS)':
 'DQ'<42>: CDS_PINID='DQ(42)';
NET_NAME
'M_M_DQ<43>'
 '@BASEBOARD_FAB2_LIB.BASEBOARD_FAB2(SCH_1):M_M_DQ'<43>:
 C_SIGNAL='@baseboard_fab2_lib.baseboard_fab2(sch_1):m_m_dq(43)';
NODE_NAME     U2D1 DJ30
 '@BASEBOARD_FAB2_LIB.BASEBOARD_FAB2(SCH_1):PAGE62_I172@CHPSET_LIB.SKX_EXT_B(CHIPS)':
 'DDR5_DQ'<43>: CDS_PINID='DDR5_DQ(43)';
NODE_NAME     J1A1 115
 '@BASEBOARD_FAB2_LIB.BASEBOARD_FAB2(SCH_1):PAGE87_I186@MSTR_SCONN.SCONN288_H44441004(CHIPS)':
 'DQ'<42>: CDS_PINID='DQ(42)';
NODE_NAME     J9L1 260
 '@BASEBOARD_FAB2_LIB.BASEBOARD_FAB2(SCH_1):PAGE88_I111@MSTR_SCONN.SCONN288_H44441003(CHIPS)':
 'DQ'<43>: CDS_PINID='DQ(43)';
NET_NAME
'M_M_DQ<44>'
 '@BASEBOARD_FAB2_LIB.BASEBOARD_FAB2(SCH_1):M_M_DQ'<44>:
 C_SIGNAL='@baseboard_fab2_lib.baseboard_fab2(sch_1):m_m_dq(44)';
NODE_NAME     U2D1 DG34
 '@BASEBOARD_FAB2_LIB.BASEBOARD_FAB2(SCH_1):PAGE62_I172@CHPSET_LIB.SKX_EXT_B(CHIPS)':
 'DDR5_DQ'<44>: CDS_PINID='DDR5_DQ(44)';
NODE_NAME     J1A1 251
 '@BASEBOARD_FAB2_LIB.BASEBOARD_FAB2(SCH_1):PAGE87_I186@MSTR_SCONN.SCONN288_H44441004(CHIPS)':
 'DQ'<45>: CDS_PINID='DQ(45)';
NODE_NAME     J9L1 106
 '@BASEBOARD_FAB2_LIB.BASEBOARD_FAB2(SCH_1):PAGE88_I111@MSTR_SCONN.SCONN288_H44441003(CHIPS)':
 'DQ'<44>: CDS_PINID='DQ(44)';
NET_NAME
'M_M_DQ<45>'
 '@BASEBOARD_FAB2_LIB.BASEBOARD_FAB2(SCH_1):M_M_DQ'<45>:
 C_SIGNAL='@baseboard_fab2_lib.baseboard_fab2(sch_1):m_m_dq(45)';
NODE_NAME     U2D1 DJ34
 '@BASEBOARD_FAB2_LIB.BASEBOARD_FAB2(SCH_1):PAGE62_I172@CHPSET_LIB.SKX_EXT_B(CHIPS)':
 'DDR5_DQ'<45>: CDS_PINID='DDR5_DQ(45)';
NODE_NAME     J1A1 106
 '@BASEBOARD_FAB2_LIB.BASEBOARD_FAB2(SCH_1):PAGE87_I186@MSTR_SCONN.SCONN288_H44441004(CHIPS)':
 'DQ'<44>: CDS_PINID='DQ(44)';
NODE_NAME     J9L1 251
 '@BASEBOARD_FAB2_LIB.BASEBOARD_FAB2(SCH_1):PAGE88_I111@MSTR_SCONN.SCONN288_H44441003(CHIPS)':
 'DQ'<45>: CDS_PINID='DQ(45)';
NET_NAME
'M_M_DQ<46>'
 '@BASEBOARD_FAB2_LIB.BASEBOARD_FAB2(SCH_1):M_M_DQ'<46>:
 C_SIGNAL='@baseboard_fab2_lib.baseboard_fab2(sch_1):m_m_dq(46)';
NODE_NAME     U2D1 DF31
 '@BASEBOARD_FAB2_LIB.BASEBOARD_FAB2(SCH_1):PAGE62_I172@CHPSET_LIB.SKX_EXT_B(CHIPS)':
 'DDR5_DQ'<46>: CDS_PINID='DDR5_DQ(46)';
NODE_NAME     J1A1 258
 '@BASEBOARD_FAB2_LIB.BASEBOARD_FAB2(SCH_1):PAGE87_I186@MSTR_SCONN.SCONN288_H44441004(CHIPS)':
 'DQ'<47>: CDS_PINID='DQ(47)';
NODE_NAME     J9L1 113
 '@BASEBOARD_FAB2_LIB.BASEBOARD_FAB2(SCH_1):PAGE88_I111@MSTR_SCONN.SCONN288_H44441003(CHIPS)':
 'DQ'<46>: CDS_PINID='DQ(46)';
NET_NAME
'M_M_DQ<47>'
 '@BASEBOARD_FAB2_LIB.BASEBOARD_FAB2(SCH_1):M_M_DQ'<47>:
 C_SIGNAL='@baseboard_fab2_lib.baseboard_fab2(sch_1):m_m_dq(47)';
NODE_NAME     U2D1 DK31
 '@BASEBOARD_FAB2_LIB.BASEBOARD_FAB2(SCH_1):PAGE62_I172@CHPSET_LIB.SKX_EXT_B(CHIPS)':
 'DDR5_DQ'<47>: CDS_PINID='DDR5_DQ(47)';
NODE_NAME     J1A1 113
 '@BASEBOARD_FAB2_LIB.BASEBOARD_FAB2(SCH_1):PAGE87_I186@MSTR_SCONN.SCONN288_H44441004(CHIPS)':
 'DQ'<46>: CDS_PINID='DQ(46)';
NODE_NAME     J9L1 258
 '@BASEBOARD_FAB2_LIB.BASEBOARD_FAB2(SCH_1):PAGE88_I111@MSTR_SCONN.SCONN288_H44441003(CHIPS)':
 'DQ'<47>: CDS_PINID='DQ(47)';
NET_NAME
'M_M_DQ<48>'
 '@BASEBOARD_FAB2_LIB.BASEBOARD_FAB2(SCH_1):M_M_DQ'<48>:
 C_SIGNAL='@baseboard_fab2_lib.baseboard_fab2(sch_1):m_m_dq(48)';
NODE_NAME     U2D1 CW36
 '@BASEBOARD_FAB2_LIB.BASEBOARD_FAB2(SCH_1):PAGE62_I172@CHPSET_LIB.SKX_EXT_B(CHIPS)':
 'DDR5_DQ'<48>: CDS_PINID='DDR5_DQ(48)';
NODE_NAME     J1A1 264
 '@BASEBOARD_FAB2_LIB.BASEBOARD_FAB2(SCH_1):PAGE87_I186@MSTR_SCONN.SCONN288_H44441004(CHIPS)':
 'DQ'<49>: CDS_PINID='DQ(49)';
NODE_NAME     J9L1 119
 '@BASEBOARD_FAB2_LIB.BASEBOARD_FAB2(SCH_1):PAGE88_I111@MSTR_SCONN.SCONN288_H44441003(CHIPS)':
 'DQ'<48>: CDS_PINID='DQ(48)';
NET_NAME
'M_M_DQ<49>'
 '@BASEBOARD_FAB2_LIB.BASEBOARD_FAB2(SCH_1):M_M_DQ'<49>:
 C_SIGNAL='@baseboard_fab2_lib.baseboard_fab2(sch_1):m_m_dq(49)';
NODE_NAME     U2D1 DC36
 '@BASEBOARD_FAB2_LIB.BASEBOARD_FAB2(SCH_1):PAGE62_I172@CHPSET_LIB.SKX_EXT_B(CHIPS)':
 'DDR5_DQ'<49>: CDS_PINID='DDR5_DQ(49)';
NODE_NAME     J1A1 119
 '@BASEBOARD_FAB2_LIB.BASEBOARD_FAB2(SCH_1):PAGE87_I186@MSTR_SCONN.SCONN288_H44441004(CHIPS)':
 'DQ'<48>: CDS_PINID='DQ(48)';
NODE_NAME     J9L1 264
 '@BASEBOARD_FAB2_LIB.BASEBOARD_FAB2(SCH_1):PAGE88_I111@MSTR_SCONN.SCONN288_H44441003(CHIPS)':
 'DQ'<49>: CDS_PINID='DQ(49)';
NET_NAME
'M_M_DQ<4>'
 '@BASEBOARD_FAB2_LIB.BASEBOARD_FAB2(SCH_1):M_M_DQ'<4>:
 C_SIGNAL='@baseboard_fab2_lib.baseboard_fab2(sch_1):m_m_dq(4)';
NODE_NAME     U2D1 CN74
 '@BASEBOARD_FAB2_LIB.BASEBOARD_FAB2(SCH_1):PAGE62_I172@CHPSET_LIB.SKX_EXT_B(CHIPS)':
 'DDR5_DQ'<4>: CDS_PINID='DDR5_DQ(4)';
NODE_NAME     J1A1 148
 '@BASEBOARD_FAB2_LIB.BASEBOARD_FAB2(SCH_1):PAGE87_I186@MSTR_SCONN.SCONN288_H44441004(CHIPS)':
 'DQ'<5>: CDS_PINID='DQ(5)';
NODE_NAME     J9L1 3
 '@BASEBOARD_FAB2_LIB.BASEBOARD_FAB2(SCH_1):PAGE88_I111@MSTR_SCONN.SCONN288_H44441003(CHIPS)':
 'DQ'<4>: CDS_PINID='DQ(4)';
NET_NAME
'M_M_DQ<50>'
 '@BASEBOARD_FAB2_LIB.BASEBOARD_FAB2(SCH_1):M_M_DQ'<50>:
 C_SIGNAL='@baseboard_fab2_lib.baseboard_fab2(sch_1):m_m_dq(50)';
NODE_NAME     U2D1 CY33
 '@BASEBOARD_FAB2_LIB.BASEBOARD_FAB2(SCH_1):PAGE62_I172@CHPSET_LIB.SKX_EXT_B(CHIPS)':
 'DDR5_DQ'<50>: CDS_PINID='DDR5_DQ(50)';
NODE_NAME     J1A1 271
 '@BASEBOARD_FAB2_LIB.BASEBOARD_FAB2(SCH_1):PAGE87_I186@MSTR_SCONN.SCONN288_H44441004(CHIPS)':
 'DQ'<51>: CDS_PINID='DQ(51)';
NODE_NAME     J9L1 126
 '@BASEBOARD_FAB2_LIB.BASEBOARD_FAB2(SCH_1):PAGE88_I111@MSTR_SCONN.SCONN288_H44441003(CHIPS)':
 'DQ'<50>: CDS_PINID='DQ(50)';
NET_NAME
'M_M_DQ<51>'
 '@BASEBOARD_FAB2_LIB.BASEBOARD_FAB2(SCH_1):M_M_DQ'<51>:
 C_SIGNAL='@baseboard_fab2_lib.baseboard_fab2(sch_1):m_m_dq(51)';
NODE_NAME     U2D1 DB33
 '@BASEBOARD_FAB2_LIB.BASEBOARD_FAB2(SCH_1):PAGE62_I172@CHPSET_LIB.SKX_EXT_B(CHIPS)':
 'DDR5_DQ'<51>: CDS_PINID='DDR5_DQ(51)';
NODE_NAME     J1A1 126
 '@BASEBOARD_FAB2_LIB.BASEBOARD_FAB2(SCH_1):PAGE87_I186@MSTR_SCONN.SCONN288_H44441004(CHIPS)':
 'DQ'<50>: CDS_PINID='DQ(50)';
NODE_NAME     J9L1 271
 '@BASEBOARD_FAB2_LIB.BASEBOARD_FAB2(SCH_1):PAGE88_I111@MSTR_SCONN.SCONN288_H44441003(CHIPS)':
 'DQ'<51>: CDS_PINID='DQ(51)';
NET_NAME
'M_M_DQ<52>'
 '@BASEBOARD_FAB2_LIB.BASEBOARD_FAB2(SCH_1):M_M_DQ'<52>:
 C_SIGNAL='@baseboard_fab2_lib.baseboard_fab2(sch_1):m_m_dq(52)';
NODE_NAME     U2D1 CY37
 '@BASEBOARD_FAB2_LIB.BASEBOARD_FAB2(SCH_1):PAGE62_I172@CHPSET_LIB.SKX_EXT_B(CHIPS)':
 'DDR5_DQ'<52>: CDS_PINID='DDR5_DQ(52)';
NODE_NAME     J1A1 262
 '@BASEBOARD_FAB2_LIB.BASEBOARD_FAB2(SCH_1):PAGE87_I186@MSTR_SCONN.SCONN288_H44441004(CHIPS)':
 'DQ'<53>: CDS_PINID='DQ(53)';
NODE_NAME     J9L1 117
 '@BASEBOARD_FAB2_LIB.BASEBOARD_FAB2(SCH_1):PAGE88_I111@MSTR_SCONN.SCONN288_H44441003(CHIPS)':
 'DQ'<52>: CDS_PINID='DQ(52)';
NET_NAME
'M_M_DQ<53>'
 '@BASEBOARD_FAB2_LIB.BASEBOARD_FAB2(SCH_1):M_M_DQ'<53>:
 C_SIGNAL='@baseboard_fab2_lib.baseboard_fab2(sch_1):m_m_dq(53)';
NODE_NAME     U2D1 DB37
 '@BASEBOARD_FAB2_LIB.BASEBOARD_FAB2(SCH_1):PAGE62_I172@CHPSET_LIB.SKX_EXT_B(CHIPS)':
 'DDR5_DQ'<53>: CDS_PINID='DDR5_DQ(53)';
NODE_NAME     J1A1 117
 '@BASEBOARD_FAB2_LIB.BASEBOARD_FAB2(SCH_1):PAGE87_I186@MSTR_SCONN.SCONN288_H44441004(CHIPS)':
 'DQ'<52>: CDS_PINID='DQ(52)';
NODE_NAME     J9L1 262
 '@BASEBOARD_FAB2_LIB.BASEBOARD_FAB2(SCH_1):PAGE88_I111@MSTR_SCONN.SCONN288_H44441003(CHIPS)':
 'DQ'<53>: CDS_PINID='DQ(53)';
NET_NAME
'M_M_DQ<54>'
 '@BASEBOARD_FAB2_LIB.BASEBOARD_FAB2(SCH_1):M_M_DQ'<54>:
 C_SIGNAL='@baseboard_fab2_lib.baseboard_fab2(sch_1):m_m_dq(54)';
NODE_NAME     U2D1 CW34
 '@BASEBOARD_FAB2_LIB.BASEBOARD_FAB2(SCH_1):PAGE62_I172@CHPSET_LIB.SKX_EXT_B(CHIPS)':
 'DDR5_DQ'<54>: CDS_PINID='DDR5_DQ(54)';
NODE_NAME     J1A1 269
 '@BASEBOARD_FAB2_LIB.BASEBOARD_FAB2(SCH_1):PAGE87_I186@MSTR_SCONN.SCONN288_H44441004(CHIPS)':
 'DQ'<55>: CDS_PINID='DQ(55)';
NODE_NAME     J9L1 124
 '@BASEBOARD_FAB2_LIB.BASEBOARD_FAB2(SCH_1):PAGE88_I111@MSTR_SCONN.SCONN288_H44441003(CHIPS)':
 'DQ'<54>: CDS_PINID='DQ(54)';
NET_NAME
'M_M_DQ<55>'
 '@BASEBOARD_FAB2_LIB.BASEBOARD_FAB2(SCH_1):M_M_DQ'<55>:
 C_SIGNAL='@baseboard_fab2_lib.baseboard_fab2(sch_1):m_m_dq(55)';
NODE_NAME     U2D1 DC34
 '@BASEBOARD_FAB2_LIB.BASEBOARD_FAB2(SCH_1):PAGE62_I172@CHPSET_LIB.SKX_EXT_B(CHIPS)':
 'DDR5_DQ'<55>: CDS_PINID='DDR5_DQ(55)';
NODE_NAME     J1A1 124
 '@BASEBOARD_FAB2_LIB.BASEBOARD_FAB2(SCH_1):PAGE87_I186@MSTR_SCONN.SCONN288_H44441004(CHIPS)':
 'DQ'<54>: CDS_PINID='DQ(54)';
NODE_NAME     J9L1 269
 '@BASEBOARD_FAB2_LIB.BASEBOARD_FAB2(SCH_1):PAGE88_I111@MSTR_SCONN.SCONN288_H44441003(CHIPS)':
 'DQ'<55>: CDS_PINID='DQ(55)';
NET_NAME
'M_M_DQ<56>'
 '@BASEBOARD_FAB2_LIB.BASEBOARD_FAB2(SCH_1):M_M_DQ'<56>:
 C_SIGNAL='@baseboard_fab2_lib.baseboard_fab2(sch_1):m_m_dq(56)';
NODE_NAME     U2D1 CW30
 '@BASEBOARD_FAB2_LIB.BASEBOARD_FAB2(SCH_1):PAGE62_I172@CHPSET_LIB.SKX_EXT_B(CHIPS)':
 'DDR5_DQ'<56>: CDS_PINID='DDR5_DQ(56)';
NODE_NAME     J1A1 275
 '@BASEBOARD_FAB2_LIB.BASEBOARD_FAB2(SCH_1):PAGE87_I186@MSTR_SCONN.SCONN288_H44441004(CHIPS)':
 'DQ'<57>: CDS_PINID='DQ(57)';
NODE_NAME     J9L1 130
 '@BASEBOARD_FAB2_LIB.BASEBOARD_FAB2(SCH_1):PAGE88_I111@MSTR_SCONN.SCONN288_H44441003(CHIPS)':
 'DQ'<56>: CDS_PINID='DQ(56)';
NET_NAME
'M_M_DQ<57>'
 '@BASEBOARD_FAB2_LIB.BASEBOARD_FAB2(SCH_1):M_M_DQ'<57>:
 C_SIGNAL='@baseboard_fab2_lib.baseboard_fab2(sch_1):m_m_dq(57)';
NODE_NAME     U2D1 DC30
 '@BASEBOARD_FAB2_LIB.BASEBOARD_FAB2(SCH_1):PAGE62_I172@CHPSET_LIB.SKX_EXT_B(CHIPS)':
 'DDR5_DQ'<57>: CDS_PINID='DDR5_DQ(57)';
NODE_NAME     J1A1 130
 '@BASEBOARD_FAB2_LIB.BASEBOARD_FAB2(SCH_1):PAGE87_I186@MSTR_SCONN.SCONN288_H44441004(CHIPS)':
 'DQ'<56>: CDS_PINID='DQ(56)';
NODE_NAME     J9L1 275
 '@BASEBOARD_FAB2_LIB.BASEBOARD_FAB2(SCH_1):PAGE88_I111@MSTR_SCONN.SCONN288_H44441003(CHIPS)':
 'DQ'<57>: CDS_PINID='DQ(57)';
NET_NAME
'M_M_DQ<58>'
 '@BASEBOARD_FAB2_LIB.BASEBOARD_FAB2(SCH_1):M_M_DQ'<58>:
 C_SIGNAL='@baseboard_fab2_lib.baseboard_fab2(sch_1):m_m_dq(58)';
NODE_NAME     U2D1 CY27
 '@BASEBOARD_FAB2_LIB.BASEBOARD_FAB2(SCH_1):PAGE62_I172@CHPSET_LIB.SKX_EXT_B(CHIPS)':
 'DDR5_DQ'<58>: CDS_PINID='DDR5_DQ(58)';
NODE_NAME     J1A1 282
 '@BASEBOARD_FAB2_LIB.BASEBOARD_FAB2(SCH_1):PAGE87_I186@MSTR_SCONN.SCONN288_H44441004(CHIPS)':
 'DQ'<59>: CDS_PINID='DQ(59)';
NODE_NAME     J9L1 137
 '@BASEBOARD_FAB2_LIB.BASEBOARD_FAB2(SCH_1):PAGE88_I111@MSTR_SCONN.SCONN288_H44441003(CHIPS)':
 'DQ'<58>: CDS_PINID='DQ(58)';
NET_NAME
'M_M_DQ<59>'
 '@BASEBOARD_FAB2_LIB.BASEBOARD_FAB2(SCH_1):M_M_DQ'<59>:
 C_SIGNAL='@baseboard_fab2_lib.baseboard_fab2(sch_1):m_m_dq(59)';
NODE_NAME     U2D1 DB27
 '@BASEBOARD_FAB2_LIB.BASEBOARD_FAB2(SCH_1):PAGE62_I172@CHPSET_LIB.SKX_EXT_B(CHIPS)':
 'DDR5_DQ'<59>: CDS_PINID='DDR5_DQ(59)';
NODE_NAME     J1A1 137
 '@BASEBOARD_FAB2_LIB.BASEBOARD_FAB2(SCH_1):PAGE87_I186@MSTR_SCONN.SCONN288_H44441004(CHIPS)':
 'DQ'<58>: CDS_PINID='DQ(58)';
NODE_NAME     J9L1 282
 '@BASEBOARD_FAB2_LIB.BASEBOARD_FAB2(SCH_1):PAGE88_I111@MSTR_SCONN.SCONN288_H44441003(CHIPS)':
 'DQ'<59>: CDS_PINID='DQ(59)';
NET_NAME
'M_M_DQ<5>'
 '@BASEBOARD_FAB2_LIB.BASEBOARD_FAB2(SCH_1):M_M_DQ'<5>:
 C_SIGNAL='@baseboard_fab2_lib.baseboard_fab2(sch_1):m_m_dq(5)';
NODE_NAME     U2D1 CM75
 '@BASEBOARD_FAB2_LIB.BASEBOARD_FAB2(SCH_1):PAGE62_I172@CHPSET_LIB.SKX_EXT_B(CHIPS)':
 'DDR5_DQ'<5>: CDS_PINID='DDR5_DQ(5)';
NODE_NAME     J1A1 3
 '@BASEBOARD_FAB2_LIB.BASEBOARD_FAB2(SCH_1):PAGE87_I186@MSTR_SCONN.SCONN288_H44441004(CHIPS)':
 'DQ'<4>: CDS_PINID='DQ(4)';
NODE_NAME     J9L1 148
 '@BASEBOARD_FAB2_LIB.BASEBOARD_FAB2(SCH_1):PAGE88_I111@MSTR_SCONN.SCONN288_H44441003(CHIPS)':
 'DQ'<5>: CDS_PINID='DQ(5)';
NET_NAME
'M_M_DQ<60>'
 '@BASEBOARD_FAB2_LIB.BASEBOARD_FAB2(SCH_1):M_M_DQ'<60>:
 C_SIGNAL='@baseboard_fab2_lib.baseboard_fab2(sch_1):m_m_dq(60)';
NODE_NAME     U2D1 CY31
 '@BASEBOARD_FAB2_LIB.BASEBOARD_FAB2(SCH_1):PAGE62_I172@CHPSET_LIB.SKX_EXT_B(CHIPS)':
 'DDR5_DQ'<60>: CDS_PINID='DDR5_DQ(60)';
NODE_NAME     J1A1 273
 '@BASEBOARD_FAB2_LIB.BASEBOARD_FAB2(SCH_1):PAGE87_I186@MSTR_SCONN.SCONN288_H44441004(CHIPS)':
 'DQ'<61>: CDS_PINID='DQ(61)';
NODE_NAME     J9L1 128
 '@BASEBOARD_FAB2_LIB.BASEBOARD_FAB2(SCH_1):PAGE88_I111@MSTR_SCONN.SCONN288_H44441003(CHIPS)':
 'DQ'<60>: CDS_PINID='DQ(60)';
NET_NAME
'M_M_DQ<61>'
 '@BASEBOARD_FAB2_LIB.BASEBOARD_FAB2(SCH_1):M_M_DQ'<61>:
 C_SIGNAL='@baseboard_fab2_lib.baseboard_fab2(sch_1):m_m_dq(61)';
NODE_NAME     U2D1 DB31
 '@BASEBOARD_FAB2_LIB.BASEBOARD_FAB2(SCH_1):PAGE62_I172@CHPSET_LIB.SKX_EXT_B(CHIPS)':
 'DDR5_DQ'<61>: CDS_PINID='DDR5_DQ(61)';
NODE_NAME     J1A1 128
 '@BASEBOARD_FAB2_LIB.BASEBOARD_FAB2(SCH_1):PAGE87_I186@MSTR_SCONN.SCONN288_H44441004(CHIPS)':
 'DQ'<60>: CDS_PINID='DQ(60)';
NODE_NAME     J9L1 273
 '@BASEBOARD_FAB2_LIB.BASEBOARD_FAB2(SCH_1):PAGE88_I111@MSTR_SCONN.SCONN288_H44441003(CHIPS)':
 'DQ'<61>: CDS_PINID='DQ(61)';
NET_NAME
'M_M_DQ<62>'
 '@BASEBOARD_FAB2_LIB.BASEBOARD_FAB2(SCH_1):M_M_DQ'<62>:
 C_SIGNAL='@baseboard_fab2_lib.baseboard_fab2(sch_1):m_m_dq(62)';
NODE_NAME     U2D1 CW28
 '@BASEBOARD_FAB2_LIB.BASEBOARD_FAB2(SCH_1):PAGE62_I172@CHPSET_LIB.SKX_EXT_B(CHIPS)':
 'DDR5_DQ'<62>: CDS_PINID='DDR5_DQ(62)';
NODE_NAME     J1A1 280
 '@BASEBOARD_FAB2_LIB.BASEBOARD_FAB2(SCH_1):PAGE87_I186@MSTR_SCONN.SCONN288_H44441004(CHIPS)':
 'DQ'<63>: CDS_PINID='DQ(63)';
NODE_NAME     J9L1 135
 '@BASEBOARD_FAB2_LIB.BASEBOARD_FAB2(SCH_1):PAGE88_I111@MSTR_SCONN.SCONN288_H44441003(CHIPS)':
 'DQ'<62>: CDS_PINID='DQ(62)';
NET_NAME
'M_M_DQ<63>'
 '@BASEBOARD_FAB2_LIB.BASEBOARD_FAB2(SCH_1):M_M_DQ'<63>:
 C_SIGNAL='@baseboard_fab2_lib.baseboard_fab2(sch_1):m_m_dq(63)';
NODE_NAME     U2D1 DC28
 '@BASEBOARD_FAB2_LIB.BASEBOARD_FAB2(SCH_1):PAGE62_I172@CHPSET_LIB.SKX_EXT_B(CHIPS)':
 'DDR5_DQ'<63>: CDS_PINID='DDR5_DQ(63)';
NODE_NAME     J1A1 135
 '@BASEBOARD_FAB2_LIB.BASEBOARD_FAB2(SCH_1):PAGE87_I186@MSTR_SCONN.SCONN288_H44441004(CHIPS)':
 'DQ'<62>: CDS_PINID='DQ(62)';
NODE_NAME     J9L1 280
 '@BASEBOARD_FAB2_LIB.BASEBOARD_FAB2(SCH_1):PAGE88_I111@MSTR_SCONN.SCONN288_H44441003(CHIPS)':
 'DQ'<63>: CDS_PINID='DQ(63)';
NET_NAME
'M_M_DQ<6>'
 '@BASEBOARD_FAB2_LIB.BASEBOARD_FAB2(SCH_1):M_M_DQ'<6>:
 C_SIGNAL='@baseboard_fab2_lib.baseboard_fab2(sch_1):m_m_dq(6)';
NODE_NAME     U2D1 CV75
 '@BASEBOARD_FAB2_LIB.BASEBOARD_FAB2(SCH_1):PAGE62_I172@CHPSET_LIB.SKX_EXT_B(CHIPS)':
 'DDR5_DQ'<6>: CDS_PINID='DDR5_DQ(6)';
NODE_NAME     J1A1 155
 '@BASEBOARD_FAB2_LIB.BASEBOARD_FAB2(SCH_1):PAGE87_I186@MSTR_SCONN.SCONN288_H44441004(CHIPS)':
 'DQ'<7>: CDS_PINID='DQ(7)';
NODE_NAME     J9L1 10
 '@BASEBOARD_FAB2_LIB.BASEBOARD_FAB2(SCH_1):PAGE88_I111@MSTR_SCONN.SCONN288_H44441003(CHIPS)':
 'DQ'<6>: CDS_PINID='DQ(6)';
NET_NAME
'M_M_DQ<7>'
 '@BASEBOARD_FAB2_LIB.BASEBOARD_FAB2(SCH_1):M_M_DQ'<7>:
 C_SIGNAL='@baseboard_fab2_lib.baseboard_fab2(sch_1):m_m_dq(7)';
NODE_NAME     U2D1 CT77
 '@BASEBOARD_FAB2_LIB.BASEBOARD_FAB2(SCH_1):PAGE62_I172@CHPSET_LIB.SKX_EXT_B(CHIPS)':
 'DDR5_DQ'<7>: CDS_PINID='DDR5_DQ(7)';
NODE_NAME     J1A1 10
 '@BASEBOARD_FAB2_LIB.BASEBOARD_FAB2(SCH_1):PAGE87_I186@MSTR_SCONN.SCONN288_H44441004(CHIPS)':
 'DQ'<6>: CDS_PINID='DQ(6)';
NODE_NAME     J9L1 155
 '@BASEBOARD_FAB2_LIB.BASEBOARD_FAB2(SCH_1):PAGE88_I111@MSTR_SCONN.SCONN288_H44441003(CHIPS)':
 'DQ'<7>: CDS_PINID='DQ(7)';
NET_NAME
'M_M_DQ<8>'
 '@BASEBOARD_FAB2_LIB.BASEBOARD_FAB2(SCH_1):M_M_DQ'<8>:
 C_SIGNAL='@baseboard_fab2_lib.baseboard_fab2(sch_1):m_m_dq(8)';
NODE_NAME     U2D1 DE74
 '@BASEBOARD_FAB2_LIB.BASEBOARD_FAB2(SCH_1):PAGE62_I172@CHPSET_LIB.SKX_EXT_B(CHIPS)':
 'DDR5_DQ'<8>: CDS_PINID='DDR5_DQ(8)';
NODE_NAME     J1A1 161
 '@BASEBOARD_FAB2_LIB.BASEBOARD_FAB2(SCH_1):PAGE87_I186@MSTR_SCONN.SCONN288_H44441004(CHIPS)':
 'DQ'<9>: CDS_PINID='DQ(9)';
NODE_NAME     J9L1 16
 '@BASEBOARD_FAB2_LIB.BASEBOARD_FAB2(SCH_1):PAGE88_I111@MSTR_SCONN.SCONN288_H44441003(CHIPS)':
 'DQ'<8>: CDS_PINID='DQ(8)';
NET_NAME
'M_M_DQ<9>'
 '@BASEBOARD_FAB2_LIB.BASEBOARD_FAB2(SCH_1):M_M_DQ'<9>:
 C_SIGNAL='@baseboard_fab2_lib.baseboard_fab2(sch_1):m_m_dq(9)';
NODE_NAME     U2D1 DC76
 '@BASEBOARD_FAB2_LIB.BASEBOARD_FAB2(SCH_1):PAGE62_I172@CHPSET_LIB.SKX_EXT_B(CHIPS)':
 'DDR5_DQ'<9>: CDS_PINID='DDR5_DQ(9)';
NODE_NAME     J1A1 16
 '@BASEBOARD_FAB2_LIB.BASEBOARD_FAB2(SCH_1):PAGE87_I186@MSTR_SCONN.SCONN288_H44441004(CHIPS)':
 'DQ'<8>: CDS_PINID='DQ(8)';
NODE_NAME     J9L1 161
 '@BASEBOARD_FAB2_LIB.BASEBOARD_FAB2(SCH_1):PAGE88_I111@MSTR_SCONN.SCONN288_H44441003(CHIPS)':
 'DQ'<9>: CDS_PINID='DQ(9)';
NET_NAME
'M_M_DQS_DN<0>'
 '@BASEBOARD_FAB2_LIB.BASEBOARD_FAB2(SCH_1):M_M_DQS_DN'<0>:
 C_SIGNAL='@baseboard_fab2_lib.baseboard_fab2(sch_1):m_m_dqs_dn(0)';
NODE_NAME     U2D1 CP77
 '@BASEBOARD_FAB2_LIB.BASEBOARD_FAB2(SCH_1):PAGE62_I172@CHPSET_LIB.SKX_EXT_B(CHIPS)':
 'DDR5_DQS_DN'<0>: CDS_PINID='DDR5_DQS_DN(0)';
NODE_NAME     J1A1 152
 '@BASEBOARD_FAB2_LIB.BASEBOARD_FAB2(SCH_1):PAGE87_I187@MSTR_SCONN.SCONN288_H44441004(CHIPS)':
 'DQS0N': CDS_PINID='DQS0N';
NODE_NAME     J9L1 152
 '@BASEBOARD_FAB2_LIB.BASEBOARD_FAB2(SCH_1):PAGE88_I87@MSTR_SCONN.SCONN288_H44441003(CHIPS)':
 'DQS0N': CDS_PINID='DQS0N';
NET_NAME
'M_M_DQS_DN<10>'
 '@BASEBOARD_FAB2_LIB.BASEBOARD_FAB2(SCH_1):M_M_DQS_DN'<10>:
 C_SIGNAL='@baseboard_fab2_lib.baseboard_fab2(sch_1):m_m_dqs_dn(10)';
NODE_NAME     U2D1 DF75
 '@BASEBOARD_FAB2_LIB.BASEBOARD_FAB2(SCH_1):PAGE62_I172@CHPSET_LIB.SKX_EXT_B(CHIPS)':
 'DDR5_DQS_DN'<10>: CDS_PINID='DDR5_DQS_DN(10)';
NODE_NAME     J1A1 19
 '@BASEBOARD_FAB2_LIB.BASEBOARD_FAB2(SCH_1):PAGE87_I187@MSTR_SCONN.SCONN288_H44441004(CHIPS)':
 'DQS10N': CDS_PINID='DQS10N';
NODE_NAME     J9L1 19
 '@BASEBOARD_FAB2_LIB.BASEBOARD_FAB2(SCH_1):PAGE88_I87@MSTR_SCONN.SCONN288_H44441003(CHIPS)':
 'DQS10N': CDS_PINID='DQS10N';
NET_NAME
'M_M_DQS_DN<11>'
 '@BASEBOARD_FAB2_LIB.BASEBOARD_FAB2(SCH_1):M_M_DQS_DN'<11>:
 C_SIGNAL='@baseboard_fab2_lib.baseboard_fab2(sch_1):m_m_dqs_dn(11)';
NODE_NAME     U2D1 DJ70
 '@BASEBOARD_FAB2_LIB.BASEBOARD_FAB2(SCH_1):PAGE62_I172@CHPSET_LIB.SKX_EXT_B(CHIPS)':
 'DDR5_DQS_DN'<11>: CDS_PINID='DDR5_DQS_DN(11)';
NODE_NAME     J1A1 30
 '@BASEBOARD_FAB2_LIB.BASEBOARD_FAB2(SCH_1):PAGE87_I187@MSTR_SCONN.SCONN288_H44441004(CHIPS)':
 'DQS11N': CDS_PINID='DQS11N';
NODE_NAME     J9L1 30
 '@BASEBOARD_FAB2_LIB.BASEBOARD_FAB2(SCH_1):PAGE88_I87@MSTR_SCONN.SCONN288_H44441003(CHIPS)':
 'DQS11N': CDS_PINID='DQS11N';
NET_NAME
'M_M_DQS_DN<12>'
 '@BASEBOARD_FAB2_LIB.BASEBOARD_FAB2(SCH_1):M_M_DQS_DN'<12>:
 C_SIGNAL='@baseboard_fab2_lib.baseboard_fab2(sch_1):m_m_dqs_dn(12)';
NODE_NAME     U2D1 CP65
 '@BASEBOARD_FAB2_LIB.BASEBOARD_FAB2(SCH_1):PAGE62_I172@CHPSET_LIB.SKX_EXT_B(CHIPS)':
 'DDR5_DQS_DN'<12>: CDS_PINID='DDR5_DQS_DN(12)';
NODE_NAME     J1A1 41
 '@BASEBOARD_FAB2_LIB.BASEBOARD_FAB2(SCH_1):PAGE87_I187@MSTR_SCONN.SCONN288_H44441004(CHIPS)':
 'DQS12N': CDS_PINID='DQS12N';
NODE_NAME     J9L1 41
 '@BASEBOARD_FAB2_LIB.BASEBOARD_FAB2(SCH_1):PAGE88_I87@MSTR_SCONN.SCONN288_H44441003(CHIPS)':
 'DQS12N': CDS_PINID='DQS12N';
NET_NAME
'M_M_DQS_DN<13>'
 '@BASEBOARD_FAB2_LIB.BASEBOARD_FAB2(SCH_1):M_M_DQS_DN'<13>:
 C_SIGNAL='@baseboard_fab2_lib.baseboard_fab2(sch_1):m_m_dqs_dn(13)';
NODE_NAME     U2D1 DE40
 '@BASEBOARD_FAB2_LIB.BASEBOARD_FAB2(SCH_1):PAGE62_I172@CHPSET_LIB.SKX_EXT_B(CHIPS)':
 'DDR5_DQS_DN'<13>: CDS_PINID='DDR5_DQS_DN(13)';
NODE_NAME     J1A1 100
 '@BASEBOARD_FAB2_LIB.BASEBOARD_FAB2(SCH_1):PAGE87_I187@MSTR_SCONN.SCONN288_H44441004(CHIPS)':
 'DQS13N': CDS_PINID='DQS13N';
NODE_NAME     J9L1 100
 '@BASEBOARD_FAB2_LIB.BASEBOARD_FAB2(SCH_1):PAGE88_I87@MSTR_SCONN.SCONN288_H44441003(CHIPS)':
 'DQS13N': CDS_PINID='DQS13N';
NET_NAME
'M_M_DQS_DN<14>'
 '@BASEBOARD_FAB2_LIB.BASEBOARD_FAB2(SCH_1):M_M_DQS_DN'<14>:
 C_SIGNAL='@baseboard_fab2_lib.baseboard_fab2(sch_1):m_m_dqs_dn(14)';
NODE_NAME     U2D1 DG32
 '@BASEBOARD_FAB2_LIB.BASEBOARD_FAB2(SCH_1):PAGE62_I172@CHPSET_LIB.SKX_EXT_B(CHIPS)':
 'DDR5_DQS_DN'<14>: CDS_PINID='DDR5_DQS_DN(14)';
NODE_NAME     J1A1 111
 '@BASEBOARD_FAB2_LIB.BASEBOARD_FAB2(SCH_1):PAGE87_I187@MSTR_SCONN.SCONN288_H44441004(CHIPS)':
 'DQS14N': CDS_PINID='DQS14N';
NODE_NAME     J9L1 111
 '@BASEBOARD_FAB2_LIB.BASEBOARD_FAB2(SCH_1):PAGE88_I87@MSTR_SCONN.SCONN288_H44441003(CHIPS)':
 'DQS14N': CDS_PINID='DQS14N';
NET_NAME
'M_M_DQS_DN<15>'
 '@BASEBOARD_FAB2_LIB.BASEBOARD_FAB2(SCH_1):M_M_DQS_DN'<15>:
 C_SIGNAL='@baseboard_fab2_lib.baseboard_fab2(sch_1):m_m_dqs_dn(15)';
NODE_NAME     U2D1 CY35
 '@BASEBOARD_FAB2_LIB.BASEBOARD_FAB2(SCH_1):PAGE62_I172@CHPSET_LIB.SKX_EXT_B(CHIPS)':
 'DDR5_DQS_DN'<15>: CDS_PINID='DDR5_DQS_DN(15)';
NODE_NAME     J1A1 122
 '@BASEBOARD_FAB2_LIB.BASEBOARD_FAB2(SCH_1):PAGE87_I187@MSTR_SCONN.SCONN288_H44441004(CHIPS)':
 'DQS15N': CDS_PINID='DQS15N';
NODE_NAME     J9L1 122
 '@BASEBOARD_FAB2_LIB.BASEBOARD_FAB2(SCH_1):PAGE88_I87@MSTR_SCONN.SCONN288_H44441003(CHIPS)':
 'DQS15N': CDS_PINID='DQS15N';
NET_NAME
'M_M_DQS_DN<16>'
 '@BASEBOARD_FAB2_LIB.BASEBOARD_FAB2(SCH_1):M_M_DQS_DN'<16>:
 C_SIGNAL='@baseboard_fab2_lib.baseboard_fab2(sch_1):m_m_dqs_dn(16)';
NODE_NAME     U2D1 CY29
 '@BASEBOARD_FAB2_LIB.BASEBOARD_FAB2(SCH_1):PAGE62_I172@CHPSET_LIB.SKX_EXT_B(CHIPS)':
 'DDR5_DQS_DN'<16>: CDS_PINID='DDR5_DQS_DN(16)';
NODE_NAME     J1A1 133
 '@BASEBOARD_FAB2_LIB.BASEBOARD_FAB2(SCH_1):PAGE87_I187@MSTR_SCONN.SCONN288_H44441004(CHIPS)':
 'DQS16N': CDS_PINID='DQS16N';
NODE_NAME     J9L1 133
 '@BASEBOARD_FAB2_LIB.BASEBOARD_FAB2(SCH_1):PAGE88_I87@MSTR_SCONN.SCONN288_H44441003(CHIPS)':
 'DQS16N': CDS_PINID='DQS16N';
NET_NAME
'M_M_DQS_DN<17>'
 '@BASEBOARD_FAB2_LIB.BASEBOARD_FAB2(SCH_1):M_M_DQS_DN'<17>:
 C_SIGNAL='@baseboard_fab2_lib.baseboard_fab2(sch_1):m_m_dqs_dn(17)';
NODE_NAME     U2D1 CJ70
 '@BASEBOARD_FAB2_LIB.BASEBOARD_FAB2(SCH_1):PAGE62_I172@CHPSET_LIB.SKX_EXT_B(CHIPS)':
 'DDR5_DQS_DN'<17>: CDS_PINID='DDR5_DQS_DN(17)';
NODE_NAME     J1A1 52
 '@BASEBOARD_FAB2_LIB.BASEBOARD_FAB2(SCH_1):PAGE87_I187@MSTR_SCONN.SCONN288_H44441004(CHIPS)':
 'DQS17N': CDS_PINID='DQS17N';
NODE_NAME     J9L1 52
 '@BASEBOARD_FAB2_LIB.BASEBOARD_FAB2(SCH_1):PAGE88_I87@MSTR_SCONN.SCONN288_H44441003(CHIPS)':
 'DQS17N': CDS_PINID='DQS17N';
NET_NAME
'M_M_DQS_DN<1>'
 '@BASEBOARD_FAB2_LIB.BASEBOARD_FAB2(SCH_1):M_M_DQS_DN'<1>:
 C_SIGNAL='@baseboard_fab2_lib.baseboard_fab2(sch_1):m_m_dqs_dn(1)';
NODE_NAME     U2D1 DD77
 '@BASEBOARD_FAB2_LIB.BASEBOARD_FAB2(SCH_1):PAGE62_I172@CHPSET_LIB.SKX_EXT_B(CHIPS)':
 'DDR5_DQS_DN'<1>: CDS_PINID='DDR5_DQS_DN(1)';
NODE_NAME     J1A1 163
 '@BASEBOARD_FAB2_LIB.BASEBOARD_FAB2(SCH_1):PAGE87_I187@MSTR_SCONN.SCONN288_H44441004(CHIPS)':
 'DQS1N': CDS_PINID='DQS1N';
NODE_NAME     J9L1 163
 '@BASEBOARD_FAB2_LIB.BASEBOARD_FAB2(SCH_1):PAGE88_I87@MSTR_SCONN.SCONN288_H44441003(CHIPS)':
 'DQS1N': CDS_PINID='DQS1N';
NET_NAME
'M_M_DQS_DN<2>'
 '@BASEBOARD_FAB2_LIB.BASEBOARD_FAB2(SCH_1):M_M_DQS_DN'<2>:
 C_SIGNAL='@baseboard_fab2_lib.baseboard_fab2(sch_1):m_m_dqs_dn(2)';
NODE_NAME     U2D1 DL72
 '@BASEBOARD_FAB2_LIB.BASEBOARD_FAB2(SCH_1):PAGE62_I172@CHPSET_LIB.SKX_EXT_B(CHIPS)':
 'DDR5_DQS_DN'<2>: CDS_PINID='DDR5_DQS_DN(2)';
NODE_NAME     J1A1 174
 '@BASEBOARD_FAB2_LIB.BASEBOARD_FAB2(SCH_1):PAGE87_I187@MSTR_SCONN.SCONN288_H44441004(CHIPS)':
 'DQS2N': CDS_PINID='DQS2N';
NODE_NAME     J9L1 174
 '@BASEBOARD_FAB2_LIB.BASEBOARD_FAB2(SCH_1):PAGE88_I87@MSTR_SCONN.SCONN288_H44441003(CHIPS)':
 'DQS2N': CDS_PINID='DQS2N';
NET_NAME
'M_M_DQS_DN<3>'
 '@BASEBOARD_FAB2_LIB.BASEBOARD_FAB2(SCH_1):M_M_DQS_DN'<3>:
 C_SIGNAL='@baseboard_fab2_lib.baseboard_fab2(sch_1):m_m_dqs_dn(3)';
NODE_NAME     U2D1 CV65
 '@BASEBOARD_FAB2_LIB.BASEBOARD_FAB2(SCH_1):PAGE62_I172@CHPSET_LIB.SKX_EXT_B(CHIPS)':
 'DDR5_DQS_DN'<3>: CDS_PINID='DDR5_DQS_DN(3)';
NODE_NAME     J1A1 185
 '@BASEBOARD_FAB2_LIB.BASEBOARD_FAB2(SCH_1):PAGE87_I187@MSTR_SCONN.SCONN288_H44441004(CHIPS)':
 'DQS3N': CDS_PINID='DQS3N';
NODE_NAME     J9L1 185
 '@BASEBOARD_FAB2_LIB.BASEBOARD_FAB2(SCH_1):PAGE88_I87@MSTR_SCONN.SCONN288_H44441003(CHIPS)':
 'DQS3N': CDS_PINID='DQS3N';
NET_NAME
'M_M_DQS_DN<4>'
 '@BASEBOARD_FAB2_LIB.BASEBOARD_FAB2(SCH_1):M_M_DQS_DN'<4>:
 C_SIGNAL='@baseboard_fab2_lib.baseboard_fab2(sch_1):m_m_dqs_dn(4)';
NODE_NAME     U2D1 DG40
 '@BASEBOARD_FAB2_LIB.BASEBOARD_FAB2(SCH_1):PAGE62_I172@CHPSET_LIB.SKX_EXT_B(CHIPS)':
 'DDR5_DQS_DN'<4>: CDS_PINID='DDR5_DQS_DN(4)';
NODE_NAME     J1A1 244
 '@BASEBOARD_FAB2_LIB.BASEBOARD_FAB2(SCH_1):PAGE87_I187@MSTR_SCONN.SCONN288_H44441004(CHIPS)':
 'DQS4N': CDS_PINID='DQS4N';
NODE_NAME     J9L1 244
 '@BASEBOARD_FAB2_LIB.BASEBOARD_FAB2(SCH_1):PAGE88_I87@MSTR_SCONN.SCONN288_H44441003(CHIPS)':
 'DQS4N': CDS_PINID='DQS4N';
NET_NAME
'M_M_DQS_DN<5>'
 '@BASEBOARD_FAB2_LIB.BASEBOARD_FAB2(SCH_1):M_M_DQS_DN'<5>:
 C_SIGNAL='@baseboard_fab2_lib.baseboard_fab2(sch_1):m_m_dqs_dn(5)';
NODE_NAME     U2D1 DL32
 '@BASEBOARD_FAB2_LIB.BASEBOARD_FAB2(SCH_1):PAGE62_I172@CHPSET_LIB.SKX_EXT_B(CHIPS)':
 'DDR5_DQS_DN'<5>: CDS_PINID='DDR5_DQS_DN(5)';
NODE_NAME     J1A1 255
 '@BASEBOARD_FAB2_LIB.BASEBOARD_FAB2(SCH_1):PAGE87_I187@MSTR_SCONN.SCONN288_H44441004(CHIPS)':
 'DQS5N': CDS_PINID='DQS5N';
NODE_NAME     J9L1 255
 '@BASEBOARD_FAB2_LIB.BASEBOARD_FAB2(SCH_1):PAGE88_I87@MSTR_SCONN.SCONN288_H44441003(CHIPS)':
 'DQS5N': CDS_PINID='DQS5N';
NET_NAME
'M_M_DQS_DN<6>'
 '@BASEBOARD_FAB2_LIB.BASEBOARD_FAB2(SCH_1):M_M_DQS_DN'<6>:
 C_SIGNAL='@baseboard_fab2_lib.baseboard_fab2(sch_1):m_m_dqs_dn(6)';
NODE_NAME     U2D1 DD35
 '@BASEBOARD_FAB2_LIB.BASEBOARD_FAB2(SCH_1):PAGE62_I172@CHPSET_LIB.SKX_EXT_B(CHIPS)':
 'DDR5_DQS_DN'<6>: CDS_PINID='DDR5_DQS_DN(6)';
NODE_NAME     J1A1 266
 '@BASEBOARD_FAB2_LIB.BASEBOARD_FAB2(SCH_1):PAGE87_I187@MSTR_SCONN.SCONN288_H44441004(CHIPS)':
 'DQS6N': CDS_PINID='DQS6N';
NODE_NAME     J9L1 266
 '@BASEBOARD_FAB2_LIB.BASEBOARD_FAB2(SCH_1):PAGE88_I87@MSTR_SCONN.SCONN288_H44441003(CHIPS)':
 'DQS6N': CDS_PINID='DQS6N';
NET_NAME
'M_M_DQS_DN<7>'
 '@BASEBOARD_FAB2_LIB.BASEBOARD_FAB2(SCH_1):M_M_DQS_DN'<7>:
 C_SIGNAL='@baseboard_fab2_lib.baseboard_fab2(sch_1):m_m_dqs_dn(7)';
NODE_NAME     U2D1 DD29
 '@BASEBOARD_FAB2_LIB.BASEBOARD_FAB2(SCH_1):PAGE62_I172@CHPSET_LIB.SKX_EXT_B(CHIPS)':
 'DDR5_DQS_DN'<7>: CDS_PINID='DDR5_DQS_DN(7)';
NODE_NAME     J1A1 277
 '@BASEBOARD_FAB2_LIB.BASEBOARD_FAB2(SCH_1):PAGE87_I187@MSTR_SCONN.SCONN288_H44441004(CHIPS)':
 'DQS7N': CDS_PINID='DQS7N';
NODE_NAME     J9L1 277
 '@BASEBOARD_FAB2_LIB.BASEBOARD_FAB2(SCH_1):PAGE88_I87@MSTR_SCONN.SCONN288_H44441003(CHIPS)':
 'DQS7N': CDS_PINID='DQS7N';
NET_NAME
'M_M_DQS_DN<8>'
 '@BASEBOARD_FAB2_LIB.BASEBOARD_FAB2(SCH_1):M_M_DQS_DN'<8>:
 C_SIGNAL='@baseboard_fab2_lib.baseboard_fab2(sch_1):m_m_dqs_dn(8)';
NODE_NAME     U2D1 CN70
 '@BASEBOARD_FAB2_LIB.BASEBOARD_FAB2(SCH_1):PAGE62_I172@CHPSET_LIB.SKX_EXT_B(CHIPS)':
 'DDR5_DQS_DN'<8>: CDS_PINID='DDR5_DQS_DN(8)';
NODE_NAME     J1A1 196
 '@BASEBOARD_FAB2_LIB.BASEBOARD_FAB2(SCH_1):PAGE87_I187@MSTR_SCONN.SCONN288_H44441004(CHIPS)':
 'DQS8N': CDS_PINID='DQS8N';
NODE_NAME     J9L1 196
 '@BASEBOARD_FAB2_LIB.BASEBOARD_FAB2(SCH_1):PAGE88_I87@MSTR_SCONN.SCONN288_H44441003(CHIPS)':
 'DQS8N': CDS_PINID='DQS8N';
NET_NAME
'M_M_DQS_DN<9>'
 '@BASEBOARD_FAB2_LIB.BASEBOARD_FAB2(SCH_1):M_M_DQS_DN'<9>:
 C_SIGNAL='@baseboard_fab2_lib.baseboard_fab2(sch_1):m_m_dqs_dn(9)';
NODE_NAME     U2D1 CT75
 '@BASEBOARD_FAB2_LIB.BASEBOARD_FAB2(SCH_1):PAGE62_I172@CHPSET_LIB.SKX_EXT_B(CHIPS)':
 'DDR5_DQS_DN'<9>: CDS_PINID='DDR5_DQS_DN(9)';
NODE_NAME     J1A1 8
 '@BASEBOARD_FAB2_LIB.BASEBOARD_FAB2(SCH_1):PAGE87_I187@MSTR_SCONN.SCONN288_H44441004(CHIPS)':
 'DQS9N': CDS_PINID='DQS9N';
NODE_NAME     J9L1 8
 '@BASEBOARD_FAB2_LIB.BASEBOARD_FAB2(SCH_1):PAGE88_I87@MSTR_SCONN.SCONN288_H44441003(CHIPS)':
 'DQS9N': CDS_PINID='DQS9N';
NET_NAME
'M_M_DQS_DP<0>'
 '@BASEBOARD_FAB2_LIB.BASEBOARD_FAB2(SCH_1):M_M_DQS_DP'<0>:
 C_SIGNAL='@baseboard_fab2_lib.baseboard_fab2(sch_1):m_m_dqs_dp(0)';
NODE_NAME     U2D1 CR76
 '@BASEBOARD_FAB2_LIB.BASEBOARD_FAB2(SCH_1):PAGE62_I172@CHPSET_LIB.SKX_EXT_B(CHIPS)':
 'DDR5_DQS_DP'<0>: CDS_PINID='DDR5_DQS_DP(0)';
NODE_NAME     J1A1 153
 '@BASEBOARD_FAB2_LIB.BASEBOARD_FAB2(SCH_1):PAGE87_I187@MSTR_SCONN.SCONN288_H44441004(CHIPS)':
 'DQS0P': CDS_PINID='DQS0P';
NODE_NAME     J9L1 153
 '@BASEBOARD_FAB2_LIB.BASEBOARD_FAB2(SCH_1):PAGE88_I87@MSTR_SCONN.SCONN288_H44441003(CHIPS)':
 'DQS0P': CDS_PINID='DQS0P';
NET_NAME
'M_M_DQS_DP<10>'
 '@BASEBOARD_FAB2_LIB.BASEBOARD_FAB2(SCH_1):M_M_DQS_DP'<10>:
 C_SIGNAL='@baseboard_fab2_lib.baseboard_fab2(sch_1):m_m_dqs_dp(10)';
NODE_NAME     U2D1 DG74
 '@BASEBOARD_FAB2_LIB.BASEBOARD_FAB2(SCH_1):PAGE62_I172@CHPSET_LIB.SKX_EXT_B(CHIPS)':
 'DDR5_DQS_DP'<10>: CDS_PINID='DDR5_DQS_DP(10)';
NODE_NAME     J1A1 18
 '@BASEBOARD_FAB2_LIB.BASEBOARD_FAB2(SCH_1):PAGE87_I187@MSTR_SCONN.SCONN288_H44441004(CHIPS)':
 'DQS10P': CDS_PINID='DQS10P';
NODE_NAME     J9L1 18
 '@BASEBOARD_FAB2_LIB.BASEBOARD_FAB2(SCH_1):PAGE88_I87@MSTR_SCONN.SCONN288_H44441003(CHIPS)':
 'DQS10P': CDS_PINID='DQS10P';
NET_NAME
'M_M_DQS_DP<11>'
 '@BASEBOARD_FAB2_LIB.BASEBOARD_FAB2(SCH_1):M_M_DQS_DP'<11>:
 C_SIGNAL='@baseboard_fab2_lib.baseboard_fab2(sch_1):m_m_dqs_dp(11)';
NODE_NAME     U2D1 DH69
 '@BASEBOARD_FAB2_LIB.BASEBOARD_FAB2(SCH_1):PAGE62_I172@CHPSET_LIB.SKX_EXT_B(CHIPS)':
 'DDR5_DQS_DP'<11>: CDS_PINID='DDR5_DQS_DP(11)';
NODE_NAME     J1A1 29
 '@BASEBOARD_FAB2_LIB.BASEBOARD_FAB2(SCH_1):PAGE87_I187@MSTR_SCONN.SCONN288_H44441004(CHIPS)':
 'DQS11P': CDS_PINID='DQS11P';
NODE_NAME     J9L1 29
 '@BASEBOARD_FAB2_LIB.BASEBOARD_FAB2(SCH_1):PAGE88_I87@MSTR_SCONN.SCONN288_H44441003(CHIPS)':
 'DQS11P': CDS_PINID='DQS11P';
NET_NAME
'M_M_DQS_DP<12>'
 '@BASEBOARD_FAB2_LIB.BASEBOARD_FAB2(SCH_1):M_M_DQS_DP'<12>:
 C_SIGNAL='@baseboard_fab2_lib.baseboard_fab2(sch_1):m_m_dqs_dp(12)';
NODE_NAME     U2D1 CM65
 '@BASEBOARD_FAB2_LIB.BASEBOARD_FAB2(SCH_1):PAGE62_I172@CHPSET_LIB.SKX_EXT_B(CHIPS)':
 'DDR5_DQS_DP'<12>: CDS_PINID='DDR5_DQS_DP(12)';
NODE_NAME     J1A1 40
 '@BASEBOARD_FAB2_LIB.BASEBOARD_FAB2(SCH_1):PAGE87_I187@MSTR_SCONN.SCONN288_H44441004(CHIPS)':
 'DQS12P': CDS_PINID='DQS12P';
NODE_NAME     J9L1 40
 '@BASEBOARD_FAB2_LIB.BASEBOARD_FAB2(SCH_1):PAGE88_I87@MSTR_SCONN.SCONN288_H44441003(CHIPS)':
 'DQS12P': CDS_PINID='DQS12P';
NET_NAME
'M_M_DQS_DP<13>'
 '@BASEBOARD_FAB2_LIB.BASEBOARD_FAB2(SCH_1):M_M_DQS_DP'<13>:
 C_SIGNAL='@baseboard_fab2_lib.baseboard_fab2(sch_1):m_m_dqs_dp(13)';
NODE_NAME     U2D1 DC40
 '@BASEBOARD_FAB2_LIB.BASEBOARD_FAB2(SCH_1):PAGE62_I172@CHPSET_LIB.SKX_EXT_B(CHIPS)':
 'DDR5_DQS_DP'<13>: CDS_PINID='DDR5_DQS_DP(13)';
NODE_NAME     J1A1 99
 '@BASEBOARD_FAB2_LIB.BASEBOARD_FAB2(SCH_1):PAGE87_I187@MSTR_SCONN.SCONN288_H44441004(CHIPS)':
 'DQS13P': CDS_PINID='DQS13P';
NODE_NAME     J9L1 99
 '@BASEBOARD_FAB2_LIB.BASEBOARD_FAB2(SCH_1):PAGE88_I87@MSTR_SCONN.SCONN288_H44441003(CHIPS)':
 'DQS13P': CDS_PINID='DQS13P';
NET_NAME
'M_M_DQS_DP<14>'
 '@BASEBOARD_FAB2_LIB.BASEBOARD_FAB2(SCH_1):M_M_DQS_DP'<14>:
 C_SIGNAL='@baseboard_fab2_lib.baseboard_fab2(sch_1):m_m_dqs_dp(14)';
NODE_NAME     U2D1 DE32
 '@BASEBOARD_FAB2_LIB.BASEBOARD_FAB2(SCH_1):PAGE62_I172@CHPSET_LIB.SKX_EXT_B(CHIPS)':
 'DDR5_DQS_DP'<14>: CDS_PINID='DDR5_DQS_DP(14)';
NODE_NAME     J1A1 110
 '@BASEBOARD_FAB2_LIB.BASEBOARD_FAB2(SCH_1):PAGE87_I187@MSTR_SCONN.SCONN288_H44441004(CHIPS)':
 'DQS14P': CDS_PINID='DQS14P';
NODE_NAME     J9L1 110
 '@BASEBOARD_FAB2_LIB.BASEBOARD_FAB2(SCH_1):PAGE88_I87@MSTR_SCONN.SCONN288_H44441003(CHIPS)':
 'DQS14P': CDS_PINID='DQS14P';
NET_NAME
'M_M_DQS_DP<15>'
 '@BASEBOARD_FAB2_LIB.BASEBOARD_FAB2(SCH_1):M_M_DQS_DP'<15>:
 C_SIGNAL='@baseboard_fab2_lib.baseboard_fab2(sch_1):m_m_dqs_dp(15)';
NODE_NAME     U2D1 CV35
 '@BASEBOARD_FAB2_LIB.BASEBOARD_FAB2(SCH_1):PAGE62_I172@CHPSET_LIB.SKX_EXT_B(CHIPS)':
 'DDR5_DQS_DP'<15>: CDS_PINID='DDR5_DQS_DP(15)';
NODE_NAME     J1A1 121
 '@BASEBOARD_FAB2_LIB.BASEBOARD_FAB2(SCH_1):PAGE87_I187@MSTR_SCONN.SCONN288_H44441004(CHIPS)':
 'DQS15P': CDS_PINID='DQS15P';
NODE_NAME     J9L1 121
 '@BASEBOARD_FAB2_LIB.BASEBOARD_FAB2(SCH_1):PAGE88_I87@MSTR_SCONN.SCONN288_H44441003(CHIPS)':
 'DQS15P': CDS_PINID='DQS15P';
NET_NAME
'M_M_DQS_DP<16>'
 '@BASEBOARD_FAB2_LIB.BASEBOARD_FAB2(SCH_1):M_M_DQS_DP'<16>:
 C_SIGNAL='@baseboard_fab2_lib.baseboard_fab2(sch_1):m_m_dqs_dp(16)';
NODE_NAME     U2D1 CV29
 '@BASEBOARD_FAB2_LIB.BASEBOARD_FAB2(SCH_1):PAGE62_I172@CHPSET_LIB.SKX_EXT_B(CHIPS)':
 'DDR5_DQS_DP'<16>: CDS_PINID='DDR5_DQS_DP(16)';
NODE_NAME     J1A1 132
 '@BASEBOARD_FAB2_LIB.BASEBOARD_FAB2(SCH_1):PAGE87_I187@MSTR_SCONN.SCONN288_H44441004(CHIPS)':
 'DQS16P': CDS_PINID='DQS16P';
NODE_NAME     J9L1 132
 '@BASEBOARD_FAB2_LIB.BASEBOARD_FAB2(SCH_1):PAGE88_I87@MSTR_SCONN.SCONN288_H44441003(CHIPS)':
 'DQS16P': CDS_PINID='DQS16P';
NET_NAME
'M_M_DQS_DP<17>'
 '@BASEBOARD_FAB2_LIB.BASEBOARD_FAB2(SCH_1):M_M_DQS_DP'<17>:
 C_SIGNAL='@baseboard_fab2_lib.baseboard_fab2(sch_1):m_m_dqs_dp(17)';
NODE_NAME     U2D1 CG70
 '@BASEBOARD_FAB2_LIB.BASEBOARD_FAB2(SCH_1):PAGE62_I172@CHPSET_LIB.SKX_EXT_B(CHIPS)':
 'DDR5_DQS_DP'<17>: CDS_PINID='DDR5_DQS_DP(17)';
NODE_NAME     J1A1 51
 '@BASEBOARD_FAB2_LIB.BASEBOARD_FAB2(SCH_1):PAGE87_I187@MSTR_SCONN.SCONN288_H44441004(CHIPS)':
 'DQS17P': CDS_PINID='DQS17P';
NODE_NAME     J9L1 51
 '@BASEBOARD_FAB2_LIB.BASEBOARD_FAB2(SCH_1):PAGE88_I87@MSTR_SCONN.SCONN288_H44441003(CHIPS)':
 'DQS17P': CDS_PINID='DQS17P';
NET_NAME
'M_M_DQS_DP<1>'
 '@BASEBOARD_FAB2_LIB.BASEBOARD_FAB2(SCH_1):M_M_DQS_DP'<1>:
 C_SIGNAL='@baseboard_fab2_lib.baseboard_fab2(sch_1):m_m_dqs_dp(1)';
NODE_NAME     U2D1 DE76
 '@BASEBOARD_FAB2_LIB.BASEBOARD_FAB2(SCH_1):PAGE62_I172@CHPSET_LIB.SKX_EXT_B(CHIPS)':
 'DDR5_DQS_DP'<1>: CDS_PINID='DDR5_DQS_DP(1)';
NODE_NAME     J1A1 164
 '@BASEBOARD_FAB2_LIB.BASEBOARD_FAB2(SCH_1):PAGE87_I187@MSTR_SCONN.SCONN288_H44441004(CHIPS)':
 'DQS1P': CDS_PINID='DQS1P';
NODE_NAME     J9L1 164
 '@BASEBOARD_FAB2_LIB.BASEBOARD_FAB2(SCH_1):PAGE88_I87@MSTR_SCONN.SCONN288_H44441003(CHIPS)':
 'DQS1P': CDS_PINID='DQS1P';
NET_NAME
'M_M_DQS_DP<2>'
 '@BASEBOARD_FAB2_LIB.BASEBOARD_FAB2(SCH_1):M_M_DQS_DP'<2>:
 C_SIGNAL='@baseboard_fab2_lib.baseboard_fab2(sch_1):m_m_dqs_dp(2)';
NODE_NAME     U2D1 DK71
 '@BASEBOARD_FAB2_LIB.BASEBOARD_FAB2(SCH_1):PAGE62_I172@CHPSET_LIB.SKX_EXT_B(CHIPS)':
 'DDR5_DQS_DP'<2>: CDS_PINID='DDR5_DQS_DP(2)';
NODE_NAME     J1A1 175
 '@BASEBOARD_FAB2_LIB.BASEBOARD_FAB2(SCH_1):PAGE87_I187@MSTR_SCONN.SCONN288_H44441004(CHIPS)':
 'DQS2P': CDS_PINID='DQS2P';
NODE_NAME     J9L1 175
 '@BASEBOARD_FAB2_LIB.BASEBOARD_FAB2(SCH_1):PAGE88_I87@MSTR_SCONN.SCONN288_H44441003(CHIPS)':
 'DQS2P': CDS_PINID='DQS2P';
NET_NAME
'M_M_DQS_DP<3>'
 '@BASEBOARD_FAB2_LIB.BASEBOARD_FAB2(SCH_1):M_M_DQS_DP'<3>:
 C_SIGNAL='@baseboard_fab2_lib.baseboard_fab2(sch_1):m_m_dqs_dp(3)';
NODE_NAME     U2D1 CT65
 '@BASEBOARD_FAB2_LIB.BASEBOARD_FAB2(SCH_1):PAGE62_I172@CHPSET_LIB.SKX_EXT_B(CHIPS)':
 'DDR5_DQS_DP'<3>: CDS_PINID='DDR5_DQS_DP(3)';
NODE_NAME     J1A1 186
 '@BASEBOARD_FAB2_LIB.BASEBOARD_FAB2(SCH_1):PAGE87_I187@MSTR_SCONN.SCONN288_H44441004(CHIPS)':
 'DQS3P': CDS_PINID='DQS3P';
NODE_NAME     J9L1 186
 '@BASEBOARD_FAB2_LIB.BASEBOARD_FAB2(SCH_1):PAGE88_I87@MSTR_SCONN.SCONN288_H44441003(CHIPS)':
 'DQS3P': CDS_PINID='DQS3P';
NET_NAME
'M_M_DQS_DP<4>'
 '@BASEBOARD_FAB2_LIB.BASEBOARD_FAB2(SCH_1):M_M_DQS_DP'<4>:
 C_SIGNAL='@baseboard_fab2_lib.baseboard_fab2(sch_1):m_m_dqs_dp(4)';
NODE_NAME     U2D1 DJ40
 '@BASEBOARD_FAB2_LIB.BASEBOARD_FAB2(SCH_1):PAGE62_I172@CHPSET_LIB.SKX_EXT_B(CHIPS)':
 'DDR5_DQS_DP'<4>: CDS_PINID='DDR5_DQS_DP(4)';
NODE_NAME     J1A1 245
 '@BASEBOARD_FAB2_LIB.BASEBOARD_FAB2(SCH_1):PAGE87_I187@MSTR_SCONN.SCONN288_H44441004(CHIPS)':
 'DQS4P': CDS_PINID='DQS4P';
NODE_NAME     J9L1 245
 '@BASEBOARD_FAB2_LIB.BASEBOARD_FAB2(SCH_1):PAGE88_I87@MSTR_SCONN.SCONN288_H44441003(CHIPS)':
 'DQS4P': CDS_PINID='DQS4P';
NET_NAME
'M_M_DQS_DP<5>'
 '@BASEBOARD_FAB2_LIB.BASEBOARD_FAB2(SCH_1):M_M_DQS_DP'<5>:
 C_SIGNAL='@baseboard_fab2_lib.baseboard_fab2(sch_1):m_m_dqs_dp(5)';
NODE_NAME     U2D1 DJ32
 '@BASEBOARD_FAB2_LIB.BASEBOARD_FAB2(SCH_1):PAGE62_I172@CHPSET_LIB.SKX_EXT_B(CHIPS)':
 'DDR5_DQS_DP'<5>: CDS_PINID='DDR5_DQS_DP(5)';
NODE_NAME     J1A1 256
 '@BASEBOARD_FAB2_LIB.BASEBOARD_FAB2(SCH_1):PAGE87_I187@MSTR_SCONN.SCONN288_H44441004(CHIPS)':
 'DQS5P': CDS_PINID='DQS5P';
NODE_NAME     J9L1 256
 '@BASEBOARD_FAB2_LIB.BASEBOARD_FAB2(SCH_1):PAGE88_I87@MSTR_SCONN.SCONN288_H44441003(CHIPS)':
 'DQS5P': CDS_PINID='DQS5P';
NET_NAME
'M_M_DQS_DP<6>'
 '@BASEBOARD_FAB2_LIB.BASEBOARD_FAB2(SCH_1):M_M_DQS_DP'<6>:
 C_SIGNAL='@baseboard_fab2_lib.baseboard_fab2(sch_1):m_m_dqs_dp(6)';
NODE_NAME     U2D1 DB35
 '@BASEBOARD_FAB2_LIB.BASEBOARD_FAB2(SCH_1):PAGE62_I172@CHPSET_LIB.SKX_EXT_B(CHIPS)':
 'DDR5_DQS_DP'<6>: CDS_PINID='DDR5_DQS_DP(6)';
NODE_NAME     J1A1 267
 '@BASEBOARD_FAB2_LIB.BASEBOARD_FAB2(SCH_1):PAGE87_I187@MSTR_SCONN.SCONN288_H44441004(CHIPS)':
 'DQS6P': CDS_PINID='DQS6P';
NODE_NAME     J9L1 267
 '@BASEBOARD_FAB2_LIB.BASEBOARD_FAB2(SCH_1):PAGE88_I87@MSTR_SCONN.SCONN288_H44441003(CHIPS)':
 'DQS6P': CDS_PINID='DQS6P';
NET_NAME
'M_M_DQS_DP<7>'
 '@BASEBOARD_FAB2_LIB.BASEBOARD_FAB2(SCH_1):M_M_DQS_DP'<7>:
 C_SIGNAL='@baseboard_fab2_lib.baseboard_fab2(sch_1):m_m_dqs_dp(7)';
NODE_NAME     U2D1 DB29
 '@BASEBOARD_FAB2_LIB.BASEBOARD_FAB2(SCH_1):PAGE62_I172@CHPSET_LIB.SKX_EXT_B(CHIPS)':
 'DDR5_DQS_DP'<7>: CDS_PINID='DDR5_DQS_DP(7)';
NODE_NAME     J1A1 278
 '@BASEBOARD_FAB2_LIB.BASEBOARD_FAB2(SCH_1):PAGE87_I187@MSTR_SCONN.SCONN288_H44441004(CHIPS)':
 'DQS7P': CDS_PINID='DQS7P';
NODE_NAME     J9L1 278
 '@BASEBOARD_FAB2_LIB.BASEBOARD_FAB2(SCH_1):PAGE88_I87@MSTR_SCONN.SCONN288_H44441003(CHIPS)':
 'DQS7P': CDS_PINID='DQS7P';
NET_NAME
'M_M_DQS_DP<8>'
 '@BASEBOARD_FAB2_LIB.BASEBOARD_FAB2(SCH_1):M_M_DQS_DP'<8>:
 C_SIGNAL='@baseboard_fab2_lib.baseboard_fab2(sch_1):m_m_dqs_dp(8)';
NODE_NAME     U2D1 CL70
 '@BASEBOARD_FAB2_LIB.BASEBOARD_FAB2(SCH_1):PAGE62_I172@CHPSET_LIB.SKX_EXT_B(CHIPS)':
 'DDR5_DQS_DP'<8>: CDS_PINID='DDR5_DQS_DP(8)';
NODE_NAME     J1A1 197
 '@BASEBOARD_FAB2_LIB.BASEBOARD_FAB2(SCH_1):PAGE87_I187@MSTR_SCONN.SCONN288_H44441004(CHIPS)':
 'DQS8P': CDS_PINID='DQS8P';
NODE_NAME     J9L1 197
 '@BASEBOARD_FAB2_LIB.BASEBOARD_FAB2(SCH_1):PAGE88_I87@MSTR_SCONN.SCONN288_H44441003(CHIPS)':
 'DQS8P': CDS_PINID='DQS8P';
NET_NAME
'M_M_DQS_DP<9>'
 '@BASEBOARD_FAB2_LIB.BASEBOARD_FAB2(SCH_1):M_M_DQS_DP'<9>:
 C_SIGNAL='@baseboard_fab2_lib.baseboard_fab2(sch_1):m_m_dqs_dp(9)';
NODE_NAME     U2D1 CU74
 '@BASEBOARD_FAB2_LIB.BASEBOARD_FAB2(SCH_1):PAGE62_I172@CHPSET_LIB.SKX_EXT_B(CHIPS)':
 'DDR5_DQS_DP'<9>: CDS_PINID='DDR5_DQS_DP(9)';
NODE_NAME     J1A1 7
 '@BASEBOARD_FAB2_LIB.BASEBOARD_FAB2(SCH_1):PAGE87_I187@MSTR_SCONN.SCONN288_H44441004(CHIPS)':
 'DQS9P': CDS_PINID='DQS9P';
NODE_NAME     J9L1 7
 '@BASEBOARD_FAB2_LIB.BASEBOARD_FAB2(SCH_1):PAGE88_I87@MSTR_SCONN.SCONN288_H44441003(CHIPS)':
 'DQS9P': CDS_PINID='DQS9P';
NET_NAME
'M_M_ECC<0>'
 '@BASEBOARD_FAB2_LIB.BASEBOARD_FAB2(SCH_1):M_M_ECC'<0>:
 C_SIGNAL='@baseboard_fab2_lib.baseboard_fab2(sch_1):m_m_ecc(0)';
NODE_NAME     U2D1 CH71
 '@BASEBOARD_FAB2_LIB.BASEBOARD_FAB2(SCH_1):PAGE62_I172@CHPSET_LIB.SKX_EXT_B(CHIPS)':
 'DDR5_ECC'<0>: CDS_PINID='DDR5_ECC(0)';
NODE_NAME     J1A1 194
 '@BASEBOARD_FAB2_LIB.BASEBOARD_FAB2(SCH_1):PAGE87_I186@MSTR_SCONN.SCONN288_H44441004(CHIPS)':
 'CB'<1>: CDS_PINID='CB(1)';
NODE_NAME     J9L1 49
 '@BASEBOARD_FAB2_LIB.BASEBOARD_FAB2(SCH_1):PAGE88_I111@MSTR_SCONN.SCONN288_H44441003(CHIPS)':
 'CB'<0>: CDS_PINID='CB(0)';
NET_NAME
'M_M_ECC<1>'
 '@BASEBOARD_FAB2_LIB.BASEBOARD_FAB2(SCH_1):M_M_ECC'<1>:
 C_SIGNAL='@baseboard_fab2_lib.baseboard_fab2(sch_1):m_m_ecc(1)';
NODE_NAME     U2D1 CM71
 '@BASEBOARD_FAB2_LIB.BASEBOARD_FAB2(SCH_1):PAGE62_I172@CHPSET_LIB.SKX_EXT_B(CHIPS)':
 'DDR5_ECC'<1>: CDS_PINID='DDR5_ECC(1)';
NODE_NAME     J1A1 49
 '@BASEBOARD_FAB2_LIB.BASEBOARD_FAB2(SCH_1):PAGE87_I186@MSTR_SCONN.SCONN288_H44441004(CHIPS)':
 'CB'<0>: CDS_PINID='CB(0)';
NODE_NAME     J9L1 194
 '@BASEBOARD_FAB2_LIB.BASEBOARD_FAB2(SCH_1):PAGE88_I111@MSTR_SCONN.SCONN288_H44441003(CHIPS)':
 'CB'<1>: CDS_PINID='CB(1)';
NET_NAME
'M_M_ECC<2>'
 '@BASEBOARD_FAB2_LIB.BASEBOARD_FAB2(SCH_1):M_M_ECC'<2>:
 C_SIGNAL='@baseboard_fab2_lib.baseboard_fab2(sch_1):m_m_ecc(2)';
NODE_NAME     U2D1 CJ68
 '@BASEBOARD_FAB2_LIB.BASEBOARD_FAB2(SCH_1):PAGE62_I172@CHPSET_LIB.SKX_EXT_B(CHIPS)':
 'DDR5_ECC'<2>: CDS_PINID='DDR5_ECC(2)';
NODE_NAME     J1A1 201
 '@BASEBOARD_FAB2_LIB.BASEBOARD_FAB2(SCH_1):PAGE87_I186@MSTR_SCONN.SCONN288_H44441004(CHIPS)':
 'CB'<3>: CDS_PINID='CB(3)';
NODE_NAME     J9L1 56
 '@BASEBOARD_FAB2_LIB.BASEBOARD_FAB2(SCH_1):PAGE88_I111@MSTR_SCONN.SCONN288_H44441003(CHIPS)':
 'CB'<2>: CDS_PINID='CB(2)';
NET_NAME
'M_M_ECC<3>'
 '@BASEBOARD_FAB2_LIB.BASEBOARD_FAB2(SCH_1):M_M_ECC'<3>:
 C_SIGNAL='@baseboard_fab2_lib.baseboard_fab2(sch_1):m_m_ecc(3)';
NODE_NAME     U2D1 CL68
 '@BASEBOARD_FAB2_LIB.BASEBOARD_FAB2(SCH_1):PAGE62_I172@CHPSET_LIB.SKX_EXT_B(CHIPS)':
 'DDR5_ECC'<3>: CDS_PINID='DDR5_ECC(3)';
NODE_NAME     J1A1 56
 '@BASEBOARD_FAB2_LIB.BASEBOARD_FAB2(SCH_1):PAGE87_I186@MSTR_SCONN.SCONN288_H44441004(CHIPS)':
 'CB'<2>: CDS_PINID='CB(2)';
NODE_NAME     J9L1 201
 '@BASEBOARD_FAB2_LIB.BASEBOARD_FAB2(SCH_1):PAGE88_I111@MSTR_SCONN.SCONN288_H44441003(CHIPS)':
 'CB'<3>: CDS_PINID='CB(3)';
NET_NAME
'M_M_ECC<4>'
 '@BASEBOARD_FAB2_LIB.BASEBOARD_FAB2(SCH_1):M_M_ECC'<4>:
 C_SIGNAL='@baseboard_fab2_lib.baseboard_fab2(sch_1):m_m_ecc(4)';
NODE_NAME     U2D1 CJ72
 '@BASEBOARD_FAB2_LIB.BASEBOARD_FAB2(SCH_1):PAGE62_I172@CHPSET_LIB.SKX_EXT_B(CHIPS)':
 'DDR5_ECC'<4>: CDS_PINID='DDR5_ECC(4)';
NODE_NAME     J1A1 192
 '@BASEBOARD_FAB2_LIB.BASEBOARD_FAB2(SCH_1):PAGE87_I186@MSTR_SCONN.SCONN288_H44441004(CHIPS)':
 'CB'<5>: CDS_PINID='CB(5)';
NODE_NAME     J9L1 47
 '@BASEBOARD_FAB2_LIB.BASEBOARD_FAB2(SCH_1):PAGE88_I111@MSTR_SCONN.SCONN288_H44441003(CHIPS)':
 'CB'<4>: CDS_PINID='CB(4)';
NET_NAME
'M_M_ECC<5>'
 '@BASEBOARD_FAB2_LIB.BASEBOARD_FAB2(SCH_1):M_M_ECC'<5>:
 C_SIGNAL='@baseboard_fab2_lib.baseboard_fab2(sch_1):m_m_ecc(5)';
NODE_NAME     U2D1 CL72
 '@BASEBOARD_FAB2_LIB.BASEBOARD_FAB2(SCH_1):PAGE62_I172@CHPSET_LIB.SKX_EXT_B(CHIPS)':
 'DDR5_ECC'<5>: CDS_PINID='DDR5_ECC(5)';
NODE_NAME     J1A1 47
 '@BASEBOARD_FAB2_LIB.BASEBOARD_FAB2(SCH_1):PAGE87_I186@MSTR_SCONN.SCONN288_H44441004(CHIPS)':
 'CB'<4>: CDS_PINID='CB(4)';
NODE_NAME     J9L1 192
 '@BASEBOARD_FAB2_LIB.BASEBOARD_FAB2(SCH_1):PAGE88_I111@MSTR_SCONN.SCONN288_H44441003(CHIPS)':
 'CB'<5>: CDS_PINID='CB(5)';
NET_NAME
'M_M_ECC<6>'
 '@BASEBOARD_FAB2_LIB.BASEBOARD_FAB2(SCH_1):M_M_ECC'<6>:
 C_SIGNAL='@baseboard_fab2_lib.baseboard_fab2(sch_1):m_m_ecc(6)';
NODE_NAME     U2D1 CH69
 '@BASEBOARD_FAB2_LIB.BASEBOARD_FAB2(SCH_1):PAGE62_I172@CHPSET_LIB.SKX_EXT_B(CHIPS)':
 'DDR5_ECC'<6>: CDS_PINID='DDR5_ECC(6)';
NODE_NAME     J1A1 199
 '@BASEBOARD_FAB2_LIB.BASEBOARD_FAB2(SCH_1):PAGE87_I186@MSTR_SCONN.SCONN288_H44441004(CHIPS)':
 'CB'<7>: CDS_PINID='CB(7)';
NODE_NAME     J9L1 54
 '@BASEBOARD_FAB2_LIB.BASEBOARD_FAB2(SCH_1):PAGE88_I111@MSTR_SCONN.SCONN288_H44441003(CHIPS)':
 'CB'<6>: CDS_PINID='CB(6)';
NET_NAME
'M_M_ECC<7>'
 '@BASEBOARD_FAB2_LIB.BASEBOARD_FAB2(SCH_1):M_M_ECC'<7>:
 C_SIGNAL='@baseboard_fab2_lib.baseboard_fab2(sch_1):m_m_ecc(7)';
NODE_NAME     U2D1 CM69
 '@BASEBOARD_FAB2_LIB.BASEBOARD_FAB2(SCH_1):PAGE62_I172@CHPSET_LIB.SKX_EXT_B(CHIPS)':
 'DDR5_ECC'<7>: CDS_PINID='DDR5_ECC(7)';
NODE_NAME     J1A1 54
 '@BASEBOARD_FAB2_LIB.BASEBOARD_FAB2(SCH_1):PAGE87_I186@MSTR_SCONN.SCONN288_H44441004(CHIPS)':
 'CB'<6>: CDS_PINID='CB(6)';
NODE_NAME     J9L1 199
 '@BASEBOARD_FAB2_LIB.BASEBOARD_FAB2(SCH_1):PAGE88_I111@MSTR_SCONN.SCONN288_H44441003(CHIPS)':
 'CB'<7>: CDS_PINID='CB(7)';
NET_NAME
'M_M_MA<0>'
 '@BASEBOARD_FAB2_LIB.BASEBOARD_FAB2(SCH_1):M_M_MA'<0>:
 C_SIGNAL='@baseboard_fab2_lib.baseboard_fab2(sch_1):m_m_ma(0)';
NODE_NAME     U2D1 DF53
 '@BASEBOARD_FAB2_LIB.BASEBOARD_FAB2(SCH_1):PAGE62_I172@CHPSET_LIB.SKX_EXT_B(CHIPS)':
 'DDR5_MA'<0>: CDS_PINID='DDR5_MA(0)';
NODE_NAME     J1A1 79
 '@BASEBOARD_FAB2_LIB.BASEBOARD_FAB2(SCH_1):PAGE87_I186@MSTR_SCONN.SCONN288_H44441004(CHIPS)':
 'A0': CDS_PINID='A0';
NODE_NAME     J9L1 79
 '@BASEBOARD_FAB2_LIB.BASEBOARD_FAB2(SCH_1):PAGE88_I111@MSTR_SCONN.SCONN288_H44441003(CHIPS)':
 'A0': CDS_PINID='A0';
NET_NAME
'M_M_MA<10>'
 '@BASEBOARD_FAB2_LIB.BASEBOARD_FAB2(SCH_1):M_M_MA'<10>:
 C_SIGNAL='@baseboard_fab2_lib.baseboard_fab2(sch_1):m_m_ma(10)';
NODE_NAME     U2D1 DD55
 '@BASEBOARD_FAB2_LIB.BASEBOARD_FAB2(SCH_1):PAGE62_I172@CHPSET_LIB.SKX_EXT_B(CHIPS)':
 'DDR5_MA'<10>: CDS_PINID='DDR5_MA(10)';
NODE_NAME     J1A1 225
 '@BASEBOARD_FAB2_LIB.BASEBOARD_FAB2(SCH_1):PAGE87_I186@MSTR_SCONN.SCONN288_H44441004(CHIPS)':
 'A10': CDS_PINID='A10';
NODE_NAME     J9L1 225
 '@BASEBOARD_FAB2_LIB.BASEBOARD_FAB2(SCH_1):PAGE88_I111@MSTR_SCONN.SCONN288_H44441003(CHIPS)':
 'A10': CDS_PINID='A10';
NET_NAME
'M_M_MA<11>'
 '@BASEBOARD_FAB2_LIB.BASEBOARD_FAB2(SCH_1):M_M_MA'<11>:
 C_SIGNAL='@baseboard_fab2_lib.baseboard_fab2(sch_1):m_m_ma(11)';
NODE_NAME     U2D1 DA60
 '@BASEBOARD_FAB2_LIB.BASEBOARD_FAB2(SCH_1):PAGE62_I172@CHPSET_LIB.SKX_EXT_B(CHIPS)':
 'DDR5_MA'<11>: CDS_PINID='DDR5_MA(11)';
NODE_NAME     J1A1 210
 '@BASEBOARD_FAB2_LIB.BASEBOARD_FAB2(SCH_1):PAGE87_I186@MSTR_SCONN.SCONN288_H44441004(CHIPS)':
 'A11': CDS_PINID='A11';
NODE_NAME     J9L1 210
 '@BASEBOARD_FAB2_LIB.BASEBOARD_FAB2(SCH_1):PAGE88_I111@MSTR_SCONN.SCONN288_H44441003(CHIPS)':
 'A11': CDS_PINID='A11';
NET_NAME
'M_M_MA<12>'
 '@BASEBOARD_FAB2_LIB.BASEBOARD_FAB2(SCH_1):M_M_MA'<12>:
 C_SIGNAL='@baseboard_fab2_lib.baseboard_fab2(sch_1):m_m_ma(12)';
NODE_NAME     U2D1 DG60
 '@BASEBOARD_FAB2_LIB.BASEBOARD_FAB2(SCH_1):PAGE62_I172@CHPSET_LIB.SKX_EXT_B(CHIPS)':
 'DDR5_MA'<12>: CDS_PINID='DDR5_MA(12)';
NODE_NAME     J1A1 65
 '@BASEBOARD_FAB2_LIB.BASEBOARD_FAB2(SCH_1):PAGE87_I186@MSTR_SCONN.SCONN288_H44441004(CHIPS)':
 'A12': CDS_PINID='A12';
NODE_NAME     J9L1 65
 '@BASEBOARD_FAB2_LIB.BASEBOARD_FAB2(SCH_1):PAGE88_I111@MSTR_SCONN.SCONN288_H44441003(CHIPS)':
 'A12': CDS_PINID='A12';
NET_NAME
'M_M_MA<13>'
 '@BASEBOARD_FAB2_LIB.BASEBOARD_FAB2(SCH_1):M_M_MA'<13>:
 C_SIGNAL='@baseboard_fab2_lib.baseboard_fab2(sch_1):m_m_ma(13)';
NODE_NAME     U2D1 DD53
 '@BASEBOARD_FAB2_LIB.BASEBOARD_FAB2(SCH_1):PAGE62_I172@CHPSET_LIB.SKX_EXT_B(CHIPS)':
 'DDR5_MA'<13>: CDS_PINID='DDR5_MA(13)';
NODE_NAME     J1A1 232
 '@BASEBOARD_FAB2_LIB.BASEBOARD_FAB2(SCH_1):PAGE87_I186@MSTR_SCONN.SCONN288_H44441004(CHIPS)':
 'A13': CDS_PINID='A13';
NODE_NAME     J9L1 232
 '@BASEBOARD_FAB2_LIB.BASEBOARD_FAB2(SCH_1):PAGE88_I111@MSTR_SCONN.SCONN288_H44441003(CHIPS)':
 'A13': CDS_PINID='A13';
NET_NAME
'M_M_MA<14>'
 '@BASEBOARD_FAB2_LIB.BASEBOARD_FAB2(SCH_1):M_M_MA'<14>:
 C_SIGNAL='@baseboard_fab2_lib.baseboard_fab2(sch_1):m_m_ma(14)';
NODE_NAME     U2D1 DJ50
 '@BASEBOARD_FAB2_LIB.BASEBOARD_FAB2(SCH_1):PAGE62_I172@CHPSET_LIB.SKX_EXT_B(CHIPS)':
 'DDR5_MA'<14>: CDS_PINID='DDR5_MA(14)';
NODE_NAME     J1A1 228
 '@BASEBOARD_FAB2_LIB.BASEBOARD_FAB2(SCH_1):PAGE87_I186@MSTR_SCONN.SCONN288_H44441004(CHIPS)':
 'A14_WE_N': CDS_PINID='A14_WE_N';
NODE_NAME     J9L1 228
 '@BASEBOARD_FAB2_LIB.BASEBOARD_FAB2(SCH_1):PAGE88_I111@MSTR_SCONN.SCONN288_H44441003(CHIPS)':
 'A14_WE_N': CDS_PINID='A14_WE_N';
NET_NAME
'M_M_MA<15>'
 '@BASEBOARD_FAB2_LIB.BASEBOARD_FAB2(SCH_1):M_M_MA'<15>:
 C_SIGNAL='@baseboard_fab2_lib.baseboard_fab2(sch_1):m_m_ma(15)';
NODE_NAME     U2D1 DC54
 '@BASEBOARD_FAB2_LIB.BASEBOARD_FAB2(SCH_1):PAGE62_I172@CHPSET_LIB.SKX_EXT_B(CHIPS)':
 'DDR5_MA'<15>: CDS_PINID='DDR5_MA(15)';
NODE_NAME     J1A1 86
 '@BASEBOARD_FAB2_LIB.BASEBOARD_FAB2(SCH_1):PAGE87_I186@MSTR_SCONN.SCONN288_H44441004(CHIPS)':
 'A15_CAS_N': CDS_PINID='A15_CAS_N';
NODE_NAME     J9L1 86
 '@BASEBOARD_FAB2_LIB.BASEBOARD_FAB2(SCH_1):PAGE88_I111@MSTR_SCONN.SCONN288_H44441003(CHIPS)':
 'A15_CAS_N': CDS_PINID='A15_CAS_N';
NET_NAME
'M_M_MA<16>'
 '@BASEBOARD_FAB2_LIB.BASEBOARD_FAB2(SCH_1):M_M_MA'<16>:
 C_SIGNAL='@baseboard_fab2_lib.baseboard_fab2(sch_1):m_m_ma(16)';
NODE_NAME     U2D1 DG52
 '@BASEBOARD_FAB2_LIB.BASEBOARD_FAB2(SCH_1):PAGE62_I172@CHPSET_LIB.SKX_EXT_B(CHIPS)':
 'DDR5_MA'<16>: CDS_PINID='DDR5_MA(16)';
NODE_NAME     J1A1 82
 '@BASEBOARD_FAB2_LIB.BASEBOARD_FAB2(SCH_1):PAGE87_I186@MSTR_SCONN.SCONN288_H44441004(CHIPS)':
 'A16_RAS_N': CDS_PINID='A16_RAS_N';
NODE_NAME     J9L1 82
 '@BASEBOARD_FAB2_LIB.BASEBOARD_FAB2(SCH_1):PAGE88_I111@MSTR_SCONN.SCONN288_H44441003(CHIPS)':
 'A16_RAS_N': CDS_PINID='A16_RAS_N';
NET_NAME
'M_M_MA<17>'
 '@BASEBOARD_FAB2_LIB.BASEBOARD_FAB2(SCH_1):M_M_MA'<17>:
 C_SIGNAL='@baseboard_fab2_lib.baseboard_fab2(sch_1):m_m_ma(17)';
NODE_NAME     U2D1 DE46
 '@BASEBOARD_FAB2_LIB.BASEBOARD_FAB2(SCH_1):PAGE62_I172@CHPSET_LIB.SKX_EXT_B(CHIPS)':
 'DDR5_MA'<17>: CDS_PINID='DDR5_MA(17)';
NODE_NAME     J1A1 234
 '@BASEBOARD_FAB2_LIB.BASEBOARD_FAB2(SCH_1):PAGE87_I186@MSTR_SCONN.SCONN288_H44441004(CHIPS)':
 'A17': CDS_PINID='A17';
NODE_NAME     J9L1 234
 '@BASEBOARD_FAB2_LIB.BASEBOARD_FAB2(SCH_1):PAGE88_I111@MSTR_SCONN.SCONN288_H44441003(CHIPS)':
 'A17': CDS_PINID='A17';
NET_NAME
'M_M_MA<1>'
 '@BASEBOARD_FAB2_LIB.BASEBOARD_FAB2(SCH_1):M_M_MA'<1>:
 C_SIGNAL='@baseboard_fab2_lib.baseboard_fab2(sch_1):m_m_ma(1)';
NODE_NAME     U2D1 DC58
 '@BASEBOARD_FAB2_LIB.BASEBOARD_FAB2(SCH_1):PAGE62_I172@CHPSET_LIB.SKX_EXT_B(CHIPS)':
 'DDR5_MA'<1>: CDS_PINID='DDR5_MA(1)';
NODE_NAME     J1A1 72
 '@BASEBOARD_FAB2_LIB.BASEBOARD_FAB2(SCH_1):PAGE87_I186@MSTR_SCONN.SCONN288_H44441004(CHIPS)':
 'A1': CDS_PINID='A1';
NODE_NAME     J9L1 72
 '@BASEBOARD_FAB2_LIB.BASEBOARD_FAB2(SCH_1):PAGE88_I111@MSTR_SCONN.SCONN288_H44441003(CHIPS)':
 'A1': CDS_PINID='A1';
NET_NAME
'M_M_MA<2>'
 '@BASEBOARD_FAB2_LIB.BASEBOARD_FAB2(SCH_1):M_M_MA'<2>:
 C_SIGNAL='@baseboard_fab2_lib.baseboard_fab2(sch_1):m_m_ma(2)';
NODE_NAME     U2D1 DD57
 '@BASEBOARD_FAB2_LIB.BASEBOARD_FAB2(SCH_1):PAGE62_I172@CHPSET_LIB.SKX_EXT_B(CHIPS)':
 'DDR5_MA'<2>: CDS_PINID='DDR5_MA(2)';
NODE_NAME     J1A1 216
 '@BASEBOARD_FAB2_LIB.BASEBOARD_FAB2(SCH_1):PAGE87_I186@MSTR_SCONN.SCONN288_H44441004(CHIPS)':
 'A2': CDS_PINID='A2';
NODE_NAME     J9L1 216
 '@BASEBOARD_FAB2_LIB.BASEBOARD_FAB2(SCH_1):PAGE88_I111@MSTR_SCONN.SCONN288_H44441003(CHIPS)':
 'A2': CDS_PINID='A2';
NET_NAME
'M_M_MA<3>'
 '@BASEBOARD_FAB2_LIB.BASEBOARD_FAB2(SCH_1):M_M_MA'<3>:
 C_SIGNAL='@baseboard_fab2_lib.baseboard_fab2(sch_1):m_m_ma(3)';
NODE_NAME     U2D1 DG58
 '@BASEBOARD_FAB2_LIB.BASEBOARD_FAB2(SCH_1):PAGE62_I172@CHPSET_LIB.SKX_EXT_B(CHIPS)':
 'DDR5_MA'<3>: CDS_PINID='DDR5_MA(3)';
NODE_NAME     J1A1 71
 '@BASEBOARD_FAB2_LIB.BASEBOARD_FAB2(SCH_1):PAGE87_I186@MSTR_SCONN.SCONN288_H44441004(CHIPS)':
 'A3': CDS_PINID='A3';
NODE_NAME     J9L1 71
 '@BASEBOARD_FAB2_LIB.BASEBOARD_FAB2(SCH_1):PAGE88_I111@MSTR_SCONN.SCONN288_H44441003(CHIPS)':
 'A3': CDS_PINID='A3';
NET_NAME
'M_M_MA<4>'
 '@BASEBOARD_FAB2_LIB.BASEBOARD_FAB2(SCH_1):M_M_MA'<4>:
 C_SIGNAL='@baseboard_fab2_lib.baseboard_fab2(sch_1):m_m_ma(4)';
NODE_NAME     U2D1 DJ58
 '@BASEBOARD_FAB2_LIB.BASEBOARD_FAB2(SCH_1):PAGE62_I172@CHPSET_LIB.SKX_EXT_B(CHIPS)':
 'DDR5_MA'<4>: CDS_PINID='DDR5_MA(4)';
NODE_NAME     J1A1 214
 '@BASEBOARD_FAB2_LIB.BASEBOARD_FAB2(SCH_1):PAGE87_I186@MSTR_SCONN.SCONN288_H44441004(CHIPS)':
 'A4': CDS_PINID='A4';
NODE_NAME     J9L1 214
 '@BASEBOARD_FAB2_LIB.BASEBOARD_FAB2(SCH_1):PAGE88_I111@MSTR_SCONN.SCONN288_H44441003(CHIPS)':
 'A4': CDS_PINID='A4';
NET_NAME
'M_M_MA<5>'
 '@BASEBOARD_FAB2_LIB.BASEBOARD_FAB2(SCH_1):M_M_MA'<5>:
 C_SIGNAL='@baseboard_fab2_lib.baseboard_fab2(sch_1):m_m_ma(5)';
NODE_NAME     U2D1 DF59
 '@BASEBOARD_FAB2_LIB.BASEBOARD_FAB2(SCH_1):PAGE62_I172@CHPSET_LIB.SKX_EXT_B(CHIPS)':
 'DDR5_MA'<5>: CDS_PINID='DDR5_MA(5)';
NODE_NAME     J1A1 213
 '@BASEBOARD_FAB2_LIB.BASEBOARD_FAB2(SCH_1):PAGE87_I186@MSTR_SCONN.SCONN288_H44441004(CHIPS)':
 'A5': CDS_PINID='A5';
NODE_NAME     J9L1 213
 '@BASEBOARD_FAB2_LIB.BASEBOARD_FAB2(SCH_1):PAGE88_I111@MSTR_SCONN.SCONN288_H44441003(CHIPS)':
 'A5': CDS_PINID='A5';
NET_NAME
'M_M_MA<6>'
 '@BASEBOARD_FAB2_LIB.BASEBOARD_FAB2(SCH_1):M_M_MA'<6>:
 C_SIGNAL='@baseboard_fab2_lib.baseboard_fab2(sch_1):m_m_ma(6)';
NODE_NAME     U2D1 DK59
 '@BASEBOARD_FAB2_LIB.BASEBOARD_FAB2(SCH_1):PAGE62_I172@CHPSET_LIB.SKX_EXT_B(CHIPS)':
 'DDR5_MA'<6>: CDS_PINID='DDR5_MA(6)';
NODE_NAME     J1A1 69
 '@BASEBOARD_FAB2_LIB.BASEBOARD_FAB2(SCH_1):PAGE87_I186@MSTR_SCONN.SCONN288_H44441004(CHIPS)':
 'A6': CDS_PINID='A6';
NODE_NAME     J9L1 69
 '@BASEBOARD_FAB2_LIB.BASEBOARD_FAB2(SCH_1):PAGE88_I111@MSTR_SCONN.SCONN288_H44441003(CHIPS)':
 'A6': CDS_PINID='A6';
NET_NAME
'M_M_MA<7>'
 '@BASEBOARD_FAB2_LIB.BASEBOARD_FAB2(SCH_1):M_M_MA'<7>:
 C_SIGNAL='@baseboard_fab2_lib.baseboard_fab2(sch_1):m_m_ma(7)';
NODE_NAME     U2D1 DC60
 '@BASEBOARD_FAB2_LIB.BASEBOARD_FAB2(SCH_1):PAGE62_I172@CHPSET_LIB.SKX_EXT_B(CHIPS)':
 'DDR5_MA'<7>: CDS_PINID='DDR5_MA(7)';
NODE_NAME     J1A1 211
 '@BASEBOARD_FAB2_LIB.BASEBOARD_FAB2(SCH_1):PAGE87_I186@MSTR_SCONN.SCONN288_H44441004(CHIPS)':
 'A7': CDS_PINID='A7';
NODE_NAME     J9L1 211
 '@BASEBOARD_FAB2_LIB.BASEBOARD_FAB2(SCH_1):PAGE88_I111@MSTR_SCONN.SCONN288_H44441003(CHIPS)':
 'A7': CDS_PINID='A7';
NET_NAME
'M_M_MA<8>'
 '@BASEBOARD_FAB2_LIB.BASEBOARD_FAB2(SCH_1):M_M_MA'<8>:
 C_SIGNAL='@baseboard_fab2_lib.baseboard_fab2(sch_1):m_m_ma(8)';
NODE_NAME     U2D1 DD59
 '@BASEBOARD_FAB2_LIB.BASEBOARD_FAB2(SCH_1):PAGE62_I172@CHPSET_LIB.SKX_EXT_B(CHIPS)':
 'DDR5_MA'<8>: CDS_PINID='DDR5_MA(8)';
NODE_NAME     J1A1 68
 '@BASEBOARD_FAB2_LIB.BASEBOARD_FAB2(SCH_1):PAGE87_I186@MSTR_SCONN.SCONN288_H44441004(CHIPS)':
 'A8': CDS_PINID='A8';
NODE_NAME     J9L1 68
 '@BASEBOARD_FAB2_LIB.BASEBOARD_FAB2(SCH_1):PAGE88_I111@MSTR_SCONN.SCONN288_H44441003(CHIPS)':
 'A8': CDS_PINID='A8';
NET_NAME
'M_M_MA<9>'
 '@BASEBOARD_FAB2_LIB.BASEBOARD_FAB2(SCH_1):M_M_MA'<9>:
 C_SIGNAL='@baseboard_fab2_lib.baseboard_fab2(sch_1):m_m_ma(9)';
NODE_NAME     U2D1 DA58
 '@BASEBOARD_FAB2_LIB.BASEBOARD_FAB2(SCH_1):PAGE62_I172@CHPSET_LIB.SKX_EXT_B(CHIPS)':
 'DDR5_MA'<9>: CDS_PINID='DDR5_MA(9)';
NODE_NAME     J1A1 66
 '@BASEBOARD_FAB2_LIB.BASEBOARD_FAB2(SCH_1):PAGE87_I186@MSTR_SCONN.SCONN288_H44441004(CHIPS)':
 'A9': CDS_PINID='A9';
NODE_NAME     J9L1 66
 '@BASEBOARD_FAB2_LIB.BASEBOARD_FAB2(SCH_1):PAGE88_I111@MSTR_SCONN.SCONN288_H44441003(CHIPS)':
 'A9': CDS_PINID='A9';
NET_NAME
'M_M_ODT<0>'
 '@BASEBOARD_FAB2_LIB.BASEBOARD_FAB2(SCH_1):M_M_ODT'<0>:
 C_SIGNAL='@baseboard_fab2_lib.baseboard_fab2(sch_1):m_m_odt(0)';
NODE_NAME     U2D1 DG50
 '@BASEBOARD_FAB2_LIB.BASEBOARD_FAB2(SCH_1):PAGE62_I172@CHPSET_LIB.SKX_EXT_B(CHIPS)':
 'DDR5_ODT'<0>: CDS_PINID='DDR5_ODT(0)';
NODE_NAME     J1A1 87
 '@BASEBOARD_FAB2_LIB.BASEBOARD_FAB2(SCH_1):PAGE87_I186@MSTR_SCONN.SCONN288_H44441004(CHIPS)':
 'ODT'<0>: CDS_PINID='ODT(0)';
NET_NAME
'M_M_ODT<1>'
 '@BASEBOARD_FAB2_LIB.BASEBOARD_FAB2(SCH_1):M_M_ODT'<1>:
 C_SIGNAL='@baseboard_fab2_lib.baseboard_fab2(sch_1):m_m_odt(1)';
NODE_NAME     U2D1 DG48
 '@BASEBOARD_FAB2_LIB.BASEBOARD_FAB2(SCH_1):PAGE62_I172@CHPSET_LIB.SKX_EXT_B(CHIPS)':
 'DDR5_ODT'<1>: CDS_PINID='DDR5_ODT(1)';
NODE_NAME     J1A1 91
 '@BASEBOARD_FAB2_LIB.BASEBOARD_FAB2(SCH_1):PAGE87_I186@MSTR_SCONN.SCONN288_H44441004(CHIPS)':
 'ODT'<1>: CDS_PINID='ODT(1)';
NET_NAME
'M_M_ODT<2>'
 '@BASEBOARD_FAB2_LIB.BASEBOARD_FAB2(SCH_1):M_M_ODT'<2>:
 C_SIGNAL='@baseboard_fab2_lib.baseboard_fab2(sch_1):m_m_odt(2)';
NODE_NAME     U2D1 DK49
 '@BASEBOARD_FAB2_LIB.BASEBOARD_FAB2(SCH_1):PAGE62_I172@CHPSET_LIB.SKX_EXT_B(CHIPS)':
 'DDR5_ODT'<2>: CDS_PINID='DDR5_ODT(2)';
NODE_NAME     J9L1 87
 '@BASEBOARD_FAB2_LIB.BASEBOARD_FAB2(SCH_1):PAGE88_I111@MSTR_SCONN.SCONN288_H44441003(CHIPS)':
 'ODT'<0>: CDS_PINID='ODT(0)';
NET_NAME
'M_M_ODT<3>'
 '@BASEBOARD_FAB2_LIB.BASEBOARD_FAB2(SCH_1):M_M_ODT'<3>:
 C_SIGNAL='@baseboard_fab2_lib.baseboard_fab2(sch_1):m_m_odt(3)';
NODE_NAME     U2D1 DF47
 '@BASEBOARD_FAB2_LIB.BASEBOARD_FAB2(SCH_1):PAGE62_I172@CHPSET_LIB.SKX_EXT_B(CHIPS)':
 'DDR5_ODT'<3>: CDS_PINID='DDR5_ODT(3)';
NODE_NAME     J9L1 91
 '@BASEBOARD_FAB2_LIB.BASEBOARD_FAB2(SCH_1):PAGE88_I111@MSTR_SCONN.SCONN288_H44441003(CHIPS)':
 'ODT'<1>: CDS_PINID='ODT(1)';
NET_NAME
'M_M_PAR'
 '@BASEBOARD_FAB2_LIB.BASEBOARD_FAB2(SCH_1):M_M_PAR':
 C_SIGNAL='@baseboard_fab2_lib.baseboard_fab2(sch_1):m_m_par';
NODE_NAME     U2D1 DK53
 '@BASEBOARD_FAB2_LIB.BASEBOARD_FAB2(SCH_1):PAGE62_I172@CHPSET_LIB.SKX_EXT_B(CHIPS)':
 'DDR5_PAR': CDS_PINID='DDR5_PAR';
NODE_NAME     J1A1 222
 '@BASEBOARD_FAB2_LIB.BASEBOARD_FAB2(SCH_1):PAGE87_I186@MSTR_SCONN.SCONN288_H44441004(CHIPS)':
 'PAR': CDS_PINID='PAR';
NODE_NAME     J9L1 222
 '@BASEBOARD_FAB2_LIB.BASEBOARD_FAB2(SCH_1):PAGE88_I111@MSTR_SCONN.SCONN288_H44441003(CHIPS)':
 'PAR': CDS_PINID='PAR';
NET_NAME
'M_M_VREF'
 '@BASEBOARD_FAB2_LIB.BASEBOARD_FAB2(SCH_1):M_M_VREF':
 C_SIGNAL='@baseboard_fab2_lib.baseboard_fab2(sch_1):m_m_vref';
NODE_NAME     C1A5 1
 '@BASEBOARD_FAB2_LIB.BASEBOARD_FAB2(SCH_1):PAGE87_I178@DEV_DISCRETE.CAP_A(CHIPS)':
 'A': CDS_PINID='A';
NODE_NAME     J1A1 146
 '@BASEBOARD_FAB2_LIB.BASEBOARD_FAB2(SCH_1):PAGE87_I186@MSTR_SCONN.SCONN288_H44441004(CHIPS)':
 'VREFCA': CDS_PINID='VREFCA';
NODE_NAME     J9L1 146
 '@BASEBOARD_FAB2_LIB.BASEBOARD_FAB2(SCH_1):PAGE88_I111@MSTR_SCONN.SCONN288_H44441003(CHIPS)':
 'VREFCA': CDS_PINID='VREFCA';
NODE_NAME     C9L1 1
 '@BASEBOARD_FAB2_LIB.BASEBOARD_FAB2(SCH_1):PAGE88_I177@DEV_DISCRETE.CAP_A(CHIPS)':
 'A': CDS_PINID='A';
NODE_NAME     R9L2 2
 '@BASEBOARD_FAB2_LIB.BASEBOARD_FAB2(SCH_1):PAGE100_I38@MSTR_DISCRETE.RES(CHIPS)':
 'B': CDS_PINID='B';
NODE_NAME     R9L1 1
 '@BASEBOARD_FAB2_LIB.BASEBOARD_FAB2(SCH_1):PAGE100_I40@MSTR_DISCRETE.RES(CHIPS)':
 'A': CDS_PINID='A';
NODE_NAME     R9L3 2
 '@BASEBOARD_FAB2_LIB.BASEBOARD_FAB2(SCH_1):PAGE100_I45@MSTR_DISCRETE.RES(CHIPS)':
 'B': CDS_PINID='B';
NET_NAME
'NC'
 'NC':
 C_SIGNAL='NC';
NODE_NAME     EU4D2 3
 '@BASEBOARD_FAB2_LIB.BASEBOARD_FAB2(SCH_1):PAGE102_I1@MSTR_CLOCK.NB3W1200L(CHIPS)':
 'NC'<0>: CDS_PINID='NC(0)';
NODE_NAME     EU4D2 16
 '@BASEBOARD_FAB2_LIB.BASEBOARD_FAB2(SCH_1):PAGE102_I1@MSTR_CLOCK.NB3W1200L(CHIPS)':
 'NC'<1>: CDS_PINID='NC(1)';
NODE_NAME     EU4D2 15
 '@BASEBOARD_FAB2_LIB.BASEBOARD_FAB2(SCH_1):PAGE102_I1@MSTR_CLOCK.NB3W1200L(CHIPS)':
 'NC'<2>: CDS_PINID='NC(2)';
NODE_NAME     U7C1 K24
 '@BASEBOARD_FAB2_LIB.BASEBOARD_FAB2(SCH_1):PAGE114_I40@MSTR_U_PROC.LBG_CORE_QAT_EXT_D(CHIPS)':
 'CLKOUT_SRCN'<12>: CDS_PINID='CLKOUT_SRCN(12)';
NODE_NAME     U7C1 C24
 '@BASEBOARD_FAB2_LIB.BASEBOARD_FAB2(SCH_1):PAGE114_I40@MSTR_U_PROC.LBG_CORE_QAT_EXT_D(CHIPS)':
 'CLKOUT_SRCN'<13>: CDS_PINID='CLKOUT_SRCN(13)';
NODE_NAME     U7C1 H24
 '@BASEBOARD_FAB2_LIB.BASEBOARD_FAB2(SCH_1):PAGE114_I40@MSTR_U_PROC.LBG_CORE_QAT_EXT_D(CHIPS)':
 'CLKOUT_SRCP'<12>: CDS_PINID='CLKOUT_SRCP(12)';
NODE_NAME     U7C1 A24
 '@BASEBOARD_FAB2_LIB.BASEBOARD_FAB2(SCH_1):PAGE114_I40@MSTR_U_PROC.LBG_CORE_QAT_EXT_D(CHIPS)':
 'CLKOUT_SRCP'<13>: CDS_PINID='CLKOUT_SRCP(13)';
NODE_NAME     U7C1 BA65
 '@BASEBOARD_FAB2_LIB.BASEBOARD_FAB2(SCH_1):PAGE116_I220@MSTR_U_PROC.LBG_CORE_QAT_EXT_D(CHIPS)':
 'PCIE8_SSATA2_GBE_RXN': CDS_PINID='PCIE8_SSATA2_GBE_RXN';
NODE_NAME     U7C1 BD65
 '@BASEBOARD_FAB2_LIB.BASEBOARD_FAB2(SCH_1):PAGE116_I220@MSTR_U_PROC.LBG_CORE_QAT_EXT_D(CHIPS)':
 'PCIE8_SSATA2_GBE_RXP': CDS_PINID='PCIE8_SSATA2_GBE_RXP';
NODE_NAME     U7C1 AF70
 '@BASEBOARD_FAB2_LIB.BASEBOARD_FAB2(SCH_1):PAGE116_I220@MSTR_U_PROC.LBG_CORE_QAT_EXT_D(CHIPS)':
 'PCIE8_SSATA2_GBE_TXN': CDS_PINID='PCIE8_SSATA2_GBE_TXN';
NODE_NAME     U7C1 AF72
 '@BASEBOARD_FAB2_LIB.BASEBOARD_FAB2(SCH_1):PAGE116_I220@MSTR_U_PROC.LBG_CORE_QAT_EXT_D(CHIPS)':
 'PCIE8_SSATA2_GBE_TXP': CDS_PINID='PCIE8_SSATA2_GBE_TXP';
NODE_NAME     U7C1 AW65
 '@BASEBOARD_FAB2_LIB.BASEBOARD_FAB2(SCH_1):PAGE116_I220@MSTR_U_PROC.LBG_CORE_QAT_EXT_D(CHIPS)':
 'PCIE9_SSATA3_RXN': CDS_PINID='PCIE9_SSATA3_RXN';
NODE_NAME     U7C1 AY66
 '@BASEBOARD_FAB2_LIB.BASEBOARD_FAB2(SCH_1):PAGE116_I220@MSTR_U_PROC.LBG_CORE_QAT_EXT_D(CHIPS)':
 'PCIE9_SSATA3_RXP': CDS_PINID='PCIE9_SSATA3_RXP';
NODE_NAME     U7C1 AE69
 '@BASEBOARD_FAB2_LIB.BASEBOARD_FAB2(SCH_1):PAGE116_I220@MSTR_U_PROC.LBG_CORE_QAT_EXT_D(CHIPS)':
 'PCIE9_SSATA3_TXN': CDS_PINID='PCIE9_SSATA3_TXN';
NODE_NAME     U7C1 AE71
 '@BASEBOARD_FAB2_LIB.BASEBOARD_FAB2(SCH_1):PAGE116_I220@MSTR_U_PROC.LBG_CORE_QAT_EXT_D(CHIPS)':
 'PCIE9_SSATA3_TXP': CDS_PINID='PCIE9_SSATA3_TXP';
NODE_NAME     U7C1 AV63
 '@BASEBOARD_FAB2_LIB.BASEBOARD_FAB2(SCH_1):PAGE116_I220@MSTR_U_PROC.LBG_CORE_QAT_EXT_D(CHIPS)':
 'PCIE10_SSATA4_RXN': CDS_PINID='PCIE10_SSATA4_RXN';
NODE_NAME     U7C1 AU65
 '@BASEBOARD_FAB2_LIB.BASEBOARD_FAB2(SCH_1):PAGE116_I220@MSTR_U_PROC.LBG_CORE_QAT_EXT_D(CHIPS)':
 'PCIE10_SSATA4_RXP': CDS_PINID='PCIE10_SSATA4_RXP';
NODE_NAME     U7C1 AD70
 '@BASEBOARD_FAB2_LIB.BASEBOARD_FAB2(SCH_1):PAGE116_I220@MSTR_U_PROC.LBG_CORE_QAT_EXT_D(CHIPS)':
 'PCIE10_SSATA4_TXN': CDS_PINID='PCIE10_SSATA4_TXN';
NODE_NAME     U7C1 AD72
 '@BASEBOARD_FAB2_LIB.BASEBOARD_FAB2(SCH_1):PAGE116_I220@MSTR_U_PROC.LBG_CORE_QAT_EXT_D(CHIPS)':
 'PCIE10_SSATA4_TXP': CDS_PINID='PCIE10_SSATA4_TXP';
NODE_NAME     U7C1 AT66
 '@BASEBOARD_FAB2_LIB.BASEBOARD_FAB2(SCH_1):PAGE116_I220@MSTR_U_PROC.LBG_CORE_QAT_EXT_D(CHIPS)':
 'PCIE11_SSATA5_GBE_RXN': CDS_PINID='PCIE11_SSATA5_GBE_RXN';
NODE_NAME     U7C1 AV66
 '@BASEBOARD_FAB2_LIB.BASEBOARD_FAB2(SCH_1):PAGE116_I220@MSTR_U_PROC.LBG_CORE_QAT_EXT_D(CHIPS)':
 'PCIE11_SSATA5_GBE_RXP': CDS_PINID='PCIE11_SSATA5_GBE_RXP';
NODE_NAME     U7C1 AC69
 '@BASEBOARD_FAB2_LIB.BASEBOARD_FAB2(SCH_1):PAGE116_I220@MSTR_U_PROC.LBG_CORE_QAT_EXT_D(CHIPS)':
 'PCIE11_SSATA5_GBE_TXN': CDS_PINID='PCIE11_SSATA5_GBE_TXN';
NODE_NAME     U7C1 AC71
 '@BASEBOARD_FAB2_LIB.BASEBOARD_FAB2(SCH_1):PAGE116_I220@MSTR_U_PROC.LBG_CORE_QAT_EXT_D(CHIPS)':
 'PCIE11_SSATA5_GBE_TXP': CDS_PINID='PCIE11_SSATA5_GBE_TXP';
NODE_NAME     U7C1 BJ37
 '@BASEBOARD_FAB2_LIB.BASEBOARD_FAB2(SCH_1):PAGE118_I73@MSTR_U_PROC.LBG_CORE_QAT_EXT_D(CHIPS)':
 'LAN_RX_P2N': CDS_PINID='LAN_RX_P2N';
NODE_NAME     U7C1 BG37
 '@BASEBOARD_FAB2_LIB.BASEBOARD_FAB2(SCH_1):PAGE118_I73@MSTR_U_PROC.LBG_CORE_QAT_EXT_D(CHIPS)':
 'LAN_RX_P2P': CDS_PINID='LAN_RX_P2P';
NODE_NAME     U7C1 BF35
 '@BASEBOARD_FAB2_LIB.BASEBOARD_FAB2(SCH_1):PAGE118_I73@MSTR_U_PROC.LBG_CORE_QAT_EXT_D(CHIPS)':
 'LAN_RX_P3N': CDS_PINID='LAN_RX_P3N';
NODE_NAME     U7C1 BH35
 '@BASEBOARD_FAB2_LIB.BASEBOARD_FAB2(SCH_1):PAGE118_I73@MSTR_U_PROC.LBG_CORE_QAT_EXT_D(CHIPS)':
 'LAN_RX_P3P': CDS_PINID='LAN_RX_P3P';
NODE_NAME     U7C1 BM35
 '@BASEBOARD_FAB2_LIB.BASEBOARD_FAB2(SCH_1):PAGE118_I73@MSTR_U_PROC.LBG_CORE_QAT_EXT_D(CHIPS)':
 'LAN_TX_P2N': CDS_PINID='LAN_TX_P2N';
NODE_NAME     U7C1 BR35
 '@BASEBOARD_FAB2_LIB.BASEBOARD_FAB2(SCH_1):PAGE118_I73@MSTR_U_PROC.LBG_CORE_QAT_EXT_D(CHIPS)':
 'LAN_TX_P2P': CDS_PINID='LAN_TX_P2P';
NODE_NAME     U7C1 BR31
 '@BASEBOARD_FAB2_LIB.BASEBOARD_FAB2(SCH_1):PAGE118_I73@MSTR_U_PROC.LBG_CORE_QAT_EXT_D(CHIPS)':
 'LAN_TX_P3N': CDS_PINID='LAN_TX_P3N';
NODE_NAME     U7C1 BM31
 '@BASEBOARD_FAB2_LIB.BASEBOARD_FAB2(SCH_1):PAGE118_I73@MSTR_U_PROC.LBG_CORE_QAT_EXT_D(CHIPS)':
 'LAN_TX_P3P': CDS_PINID='LAN_TX_P3P';
NODE_NAME     U7C1 AA4
 '@BASEBOARD_FAB2_LIB.BASEBOARD_FAB2(SCH_1):PAGE119_I115@MSTR_U_PROC.LBG_CORE_QAT_EXT_D(CHIPS)':
 'GPP_A10_CLKOUT_LPC1': CDS_PINID='GPP_A10_CLKOUT_LPC1';
NODE_NAME     U7C1 W4
 '@BASEBOARD_FAB2_LIB.BASEBOARD_FAB2(SCH_1):PAGE119_I115@MSTR_U_PROC.LBG_CORE_QAT_EXT_D(CHIPS)':
 'GPP_A20': CDS_PINID='GPP_A20';
NODE_NAME     U7C1 BV44
 '@BASEBOARD_FAB2_LIB.BASEBOARD_FAB2(SCH_1):PAGE119_I115@MSTR_U_PROC.LBG_CORE_QAT_EXT_D(CHIPS)':
 'GPP_D21_IE_UART_RX': CDS_PINID='GPP_D21_IE_UART_RX';
NODE_NAME     U7C1 BR46
 '@BASEBOARD_FAB2_LIB.BASEBOARD_FAB2(SCH_1):PAGE119_I115@MSTR_U_PROC.LBG_CORE_QAT_EXT_D(CHIPS)':
 'GPP_D22_IE_UART_TX': CDS_PINID='GPP_D22_IE_UART_TX';
NODE_NAME     U7C1 AY11
 '@BASEBOARD_FAB2_LIB.BASEBOARD_FAB2(SCH_1):PAGE120_I147@MSTR_U_PROC.LBG_CORE_QAT_EXT_D(CHIPS)':
 'GPP_G0_FANTACH0_FANTACH0IE': CDS_PINID='GPP_G0_FANTACH0_FANTACH0IE';
NODE_NAME     U7C1 AV15
 '@BASEBOARD_FAB2_LIB.BASEBOARD_FAB2(SCH_1):PAGE120_I147@MSTR_U_PROC.LBG_CORE_QAT_EXT_D(CHIPS)':
 'GPP_G1_FANTACH1_FANTACH1IE': CDS_PINID='GPP_G1_FANTACH1_FANTACH1IE';
NODE_NAME     U7C1 BE22
 '@BASEBOARD_FAB2_LIB.BASEBOARD_FAB2(SCH_1):PAGE120_I147@MSTR_U_PROC.LBG_CORE_QAT_EXT_D(CHIPS)':
 'GPP_G2_FANTACH2_FANTACH2IE': CDS_PINID='GPP_G2_FANTACH2_FANTACH2IE';
NODE_NAME     U7C1 AY7
 '@BASEBOARD_FAB2_LIB.BASEBOARD_FAB2(SCH_1):PAGE120_I147@MSTR_U_PROC.LBG_CORE_QAT_EXT_D(CHIPS)':
 'GPP_G3_FANTACH3_FANTACH3IE': CDS_PINID='GPP_G3_FANTACH3_FANTACH3IE';
NODE_NAME     U7C1 BA9
 '@BASEBOARD_FAB2_LIB.BASEBOARD_FAB2(SCH_1):PAGE120_I147@MSTR_U_PROC.LBG_CORE_QAT_EXT_D(CHIPS)':
 'GPP_G4_FANTACH4_FANTACH4IE': CDS_PINID='GPP_G4_FANTACH4_FANTACH4IE';
NODE_NAME     U7C1 AW20
 '@BASEBOARD_FAB2_LIB.BASEBOARD_FAB2(SCH_1):PAGE120_I147@MSTR_U_PROC.LBG_CORE_QAT_EXT_D(CHIPS)':
 'GPP_G5_FANTACH5_FANTACH5IE': CDS_PINID='GPP_G5_FANTACH5_FANTACH5IE';
NODE_NAME     U7C1 AY15
 '@BASEBOARD_FAB2_LIB.BASEBOARD_FAB2(SCH_1):PAGE120_I147@MSTR_U_PROC.LBG_CORE_QAT_EXT_D(CHIPS)':
 'GPP_G7_FANTACH7_FANTACH7IE': CDS_PINID='GPP_G7_FANTACH7_FANTACH7IE';
NODE_NAME     U7C1 BG11
 '@BASEBOARD_FAB2_LIB.BASEBOARD_FAB2(SCH_1):PAGE120_I147@MSTR_U_PROC.LBG_CORE_QAT_EXT_D(CHIPS)':
 'GPP_G8_FANPWM0_FANPWM0IE': CDS_PINID='GPP_G8_FANPWM0_FANPWM0IE';
NODE_NAME     U7C1 AV11
 '@BASEBOARD_FAB2_LIB.BASEBOARD_FAB2(SCH_1):PAGE120_I147@MSTR_U_PROC.LBG_CORE_QAT_EXT_D(CHIPS)':
 'GPP_G9_FANPWM1_FAMPWM1IE': CDS_PINID='GPP_G9_FANPWM1_FAMPWM1IE';
NODE_NAME     U7C1 BE11
 '@BASEBOARD_FAB2_LIB.BASEBOARD_FAB2(SCH_1):PAGE120_I147@MSTR_U_PROC.LBG_CORE_QAT_EXT_D(CHIPS)':
 'GPP_G10_FANPWM2_FANPWM2IE': CDS_PINID='GPP_G10_FANPWM2_FANPWM2IE';
NODE_NAME     U7C1 BA20
 '@BASEBOARD_FAB2_LIB.BASEBOARD_FAB2(SCH_1):PAGE120_I147@MSTR_U_PROC.LBG_CORE_QAT_EXT_D(CHIPS)':
 'GPP_G11_FANPWM3_FANPMW3IE': CDS_PINID='GPP_G11_FANPWM3_FANPMW3IE';
NODE_NAME     U7C1 AV3
 '@BASEBOARD_FAB2_LIB.BASEBOARD_FAB2(SCH_1):PAGE120_I147@MSTR_U_PROC.LBG_CORE_QAT_EXT_D(CHIPS)':
 'GPP_H2_SRCCLKREQ8_N': CDS_PINID='GPP_H2_SRCCLKREQ8_N';
NODE_NAME     U7C1 AR1
 '@BASEBOARD_FAB2_LIB.BASEBOARD_FAB2(SCH_1):PAGE120_I147@MSTR_U_PROC.LBG_CORE_QAT_EXT_D(CHIPS)':
 'GPP_H3_SRCCLKREQ9_N': CDS_PINID='GPP_H3_SRCCLKREQ9_N';
NODE_NAME     U7C1 AT2
 '@BASEBOARD_FAB2_LIB.BASEBOARD_FAB2(SCH_1):PAGE120_I147@MSTR_U_PROC.LBG_CORE_QAT_EXT_D(CHIPS)':
 'GPP_H4_SRCCLKREQ10_N': CDS_PINID='GPP_H4_SRCCLKREQ10_N';
NODE_NAME     U7C1 AY3
 '@BASEBOARD_FAB2_LIB.BASEBOARD_FAB2(SCH_1):PAGE120_I147@MSTR_U_PROC.LBG_CORE_QAT_EXT_D(CHIPS)':
 'GPP_H5_SRCCLKREQ11_N': CDS_PINID='GPP_H5_SRCCLKREQ11_N';
NODE_NAME     U7C1 AW2
 '@BASEBOARD_FAB2_LIB.BASEBOARD_FAB2(SCH_1):PAGE120_I147@MSTR_U_PROC.LBG_CORE_QAT_EXT_D(CHIPS)':
 'GPP_H6_SRCCLKREQ12_N': CDS_PINID='GPP_H6_SRCCLKREQ12_N';
NODE_NAME     U7C1 AV1
 '@BASEBOARD_FAB2_LIB.BASEBOARD_FAB2(SCH_1):PAGE120_I147@MSTR_U_PROC.LBG_CORE_QAT_EXT_D(CHIPS)':
 'GPP_H7_SRCCLKREQ13_N': CDS_PINID='GPP_H7_SRCCLKREQ13_N';
NODE_NAME     U7C1 AR3
 '@BASEBOARD_FAB2_LIB.BASEBOARD_FAB2(SCH_1):PAGE120_I147@MSTR_U_PROC.LBG_CORE_QAT_EXT_D(CHIPS)':
 'GPP_H8_SRCCLKREQ14_N': CDS_PINID='GPP_H8_SRCCLKREQ14_N';
NODE_NAME     U7C1 BE2
 '@BASEBOARD_FAB2_LIB.BASEBOARD_FAB2(SCH_1):PAGE120_I147@MSTR_U_PROC.LBG_CORE_QAT_EXT_D(CHIPS)':
 'GPP_H9_SRCCLKREQ15_N': CDS_PINID='GPP_H9_SRCCLKREQ15_N';
NODE_NAME     U7C1 AY1
 '@BASEBOARD_FAB2_LIB.BASEBOARD_FAB2(SCH_1):PAGE120_I147@MSTR_U_PROC.LBG_CORE_QAT_EXT_D(CHIPS)':
 'GPP_H13_SML3CLK_IE': CDS_PINID='GPP_H13_SML3CLK_IE';
NODE_NAME     U7C1 BC2
 '@BASEBOARD_FAB2_LIB.BASEBOARD_FAB2(SCH_1):PAGE120_I147@MSTR_U_PROC.LBG_CORE_QAT_EXT_D(CHIPS)':
 'GPP_H14_SML3DATA_IE': CDS_PINID='GPP_H14_SML3DATA_IE';
NODE_NAME     EU9E1 22
 '@BASEBOARD_FAB2_LIB.BASEBOARD_FAB2(SCH_1):PAGE139_I72@MSTR_INTEL.SPRINGVILLE(CHIPS)':
 'NC': CDS_PINID='NC';
NODE_NAME     J8E4 5
 '@BASEBOARD_FAB2_LIB.BASEBOARD_FAB2(SCH_1):PAGE188_I27@MSTR_SCONN.SCONN64_H87568002_A(CHIPS)':
 'IO5': CDS_PINID='IO5';
NODE_NAME     J8E4 6
 '@BASEBOARD_FAB2_LIB.BASEBOARD_FAB2(SCH_1):PAGE188_I27@MSTR_SCONN.SCONN64_H87568002_A(CHIPS)':
 'IO6': CDS_PINID='IO6';
NODE_NAME     J8E4 11
 '@BASEBOARD_FAB2_LIB.BASEBOARD_FAB2(SCH_1):PAGE188_I27@MSTR_SCONN.SCONN64_H87568002_A(CHIPS)':
 'IO11': CDS_PINID='IO11';
NODE_NAME     J8E4 12
 '@BASEBOARD_FAB2_LIB.BASEBOARD_FAB2(SCH_1):PAGE188_I27@MSTR_SCONN.SCONN64_H87568002_A(CHIPS)':
 'IO12': CDS_PINID='IO12';
NODE_NAME     J8E4 17
 '@BASEBOARD_FAB2_LIB.BASEBOARD_FAB2(SCH_1):PAGE188_I27@MSTR_SCONN.SCONN64_H87568002_A(CHIPS)':
 'IO17': CDS_PINID='IO17';
NODE_NAME     J8E4 18
 '@BASEBOARD_FAB2_LIB.BASEBOARD_FAB2(SCH_1):PAGE188_I27@MSTR_SCONN.SCONN64_H87568002_A(CHIPS)':
 'IO18': CDS_PINID='IO18';
NODE_NAME     J8E4 23
 '@BASEBOARD_FAB2_LIB.BASEBOARD_FAB2(SCH_1):PAGE188_I27@MSTR_SCONN.SCONN64_H87568002_A(CHIPS)':
 'IO23': CDS_PINID='IO23';
NODE_NAME     J8E4 24
 '@BASEBOARD_FAB2_LIB.BASEBOARD_FAB2(SCH_1):PAGE188_I27@MSTR_SCONN.SCONN64_H87568002_A(CHIPS)':
 'IO24': CDS_PINID='IO24';
NODE_NAME     U8D7 H5
 '@BASEBOARD_FAB2_LIB.BASEBOARD_FAB2(SCH_1):PAGE190_I179@MSTR_MEMORY.LCMXO2_A(CHIPS)':
 'PL9C': CDS_PINID='PL9C';
NODE_NAME     U8D7 J4
 '@BASEBOARD_FAB2_LIB.BASEBOARD_FAB2(SCH_1):PAGE190_I179@MSTR_MEMORY.LCMXO2_A(CHIPS)':
 'PL9D': CDS_PINID='PL9D';
NODE_NAME     U8D7 A2
 '@BASEBOARD_FAB2_LIB.BASEBOARD_FAB2(SCH_1):PAGE192_I14@MSTR_MEMORY.LCMXO2_A(CHIPS)':
 'NC'<0>: CDS_PINID='NC(0)';
NODE_NAME     EU4D4 33
 '@BASEBOARD_FAB2_LIB.BASEBOARD_FAB2(SCH_1):PAGE201_I155@MSTR_CONTROLLER.PXE1610B(CHIPS)':
 'AIREF6': CDS_PINID='AIREF6';
NODE_NAME     EU4D4 34
 '@BASEBOARD_FAB2_LIB.BASEBOARD_FAB2(SCH_1):PAGE201_I155@MSTR_CONTROLLER.PXE1610B(CHIPS)':
 'AISEN6': CDS_PINID='AISEN6';
NODE_NAME     EU4D4 2
 '@BASEBOARD_FAB2_LIB.BASEBOARD_FAB2(SCH_1):PAGE201_I155@MSTR_CONTROLLER.PXE1610B(CHIPS)':
 'APWM6': CDS_PINID='APWM6';
NODE_NAME     EU4D4 46
 '@BASEBOARD_FAB2_LIB.BASEBOARD_FAB2(SCH_1):PAGE201_I155@MSTR_CONTROLLER.PXE1610B(CHIPS)':
 'IINSEN': CDS_PINID='IINSEN';
NODE_NAME     EU4D4 16
 '@BASEBOARD_FAB2_LIB.BASEBOARD_FAB2(SCH_1):PAGE201_I155@MSTR_CONTROLLER.PXE1610B(CHIPS)':
 'MP1': CDS_PINID='MP1';
NODE_NAME     EU4D4 40
 '@BASEBOARD_FAB2_LIB.BASEBOARD_FAB2(SCH_1):PAGE201_I155@MSTR_CONTROLLER.PXE1610B(CHIPS)':
 'MP4': CDS_PINID='MP4';
NODE_NAME     EU4D4 10
 '@BASEBOARD_FAB2_LIB.BASEBOARD_FAB2(SCH_1):PAGE201_I155@MSTR_CONTROLLER.PXE1610B(CHIPS)':
 'RESET_N': CDS_PINID='RESET_N';
NODE_NAME     EU4E1 31
 '@BASEBOARD_FAB2_LIB.BASEBOARD_FAB2(SCH_1):PAGE202_I63@MSTR_DISCRETE.IR354XX(CHIPS)':
 'NC': CDS_PINID='NC';
NODE_NAME     EU4D6 31
 '@BASEBOARD_FAB2_LIB.BASEBOARD_FAB2(SCH_1):PAGE202_I64@MSTR_DISCRETE.IR354XX(CHIPS)':
 'NC': CDS_PINID='NC';
NODE_NAME     EU4D3 31
 '@BASEBOARD_FAB2_LIB.BASEBOARD_FAB2(SCH_1):PAGE203_I70@MSTR_DISCRETE.IR354XX(CHIPS)':
 'NC': CDS_PINID='NC';
NODE_NAME     EU4D1 31
 '@BASEBOARD_FAB2_LIB.BASEBOARD_FAB2(SCH_1):PAGE203_I71@MSTR_DISCRETE.IR354XX(CHIPS)':
 'NC': CDS_PINID='NC';
NODE_NAME     EU4C2 31
 '@BASEBOARD_FAB2_LIB.BASEBOARD_FAB2(SCH_1):PAGE204_I71@MSTR_DISCRETE.IR354XX(CHIPS)':
 'NC': CDS_PINID='NC';
NODE_NAME     EU4C1 31
 '@BASEBOARD_FAB2_LIB.BASEBOARD_FAB2(SCH_1):PAGE205_I46@MSTR_DISCRETE.IR354XX(CHIPS)':
 'NC': CDS_PINID='NC';
NODE_NAME     EU1C2 33
 '@BASEBOARD_FAB2_LIB.BASEBOARD_FAB2(SCH_1):PAGE206_I130@MSTR_CONTROLLER.PXE1610B(CHIPS)':
 'AIREF6': CDS_PINID='AIREF6';
NODE_NAME     EU1C2 34
 '@BASEBOARD_FAB2_LIB.BASEBOARD_FAB2(SCH_1):PAGE206_I130@MSTR_CONTROLLER.PXE1610B(CHIPS)':
 'AISEN6': CDS_PINID='AISEN6';
NODE_NAME     EU1C2 2
 '@BASEBOARD_FAB2_LIB.BASEBOARD_FAB2(SCH_1):PAGE206_I130@MSTR_CONTROLLER.PXE1610B(CHIPS)':
 'APWM6': CDS_PINID='APWM6';
NODE_NAME     EU1C2 46
 '@BASEBOARD_FAB2_LIB.BASEBOARD_FAB2(SCH_1):PAGE206_I130@MSTR_CONTROLLER.PXE1610B(CHIPS)':
 'IINSEN': CDS_PINID='IINSEN';
NODE_NAME     EU1C2 16
 '@BASEBOARD_FAB2_LIB.BASEBOARD_FAB2(SCH_1):PAGE206_I130@MSTR_CONTROLLER.PXE1610B(CHIPS)':
 'MP1': CDS_PINID='MP1';
NODE_NAME     EU1C2 40
 '@BASEBOARD_FAB2_LIB.BASEBOARD_FAB2(SCH_1):PAGE206_I130@MSTR_CONTROLLER.PXE1610B(CHIPS)':
 'MP4': CDS_PINID='MP4';
NODE_NAME     EU1C2 10
 '@BASEBOARD_FAB2_LIB.BASEBOARD_FAB2(SCH_1):PAGE206_I130@MSTR_CONTROLLER.PXE1610B(CHIPS)':
 'RESET_N': CDS_PINID='RESET_N';
NODE_NAME     EU1E2 31
 '@BASEBOARD_FAB2_LIB.BASEBOARD_FAB2(SCH_1):PAGE207_I20@MSTR_DISCRETE.IR354XX(CHIPS)':
 'NC': CDS_PINID='NC';
NODE_NAME     EU1D3 31
 '@BASEBOARD_FAB2_LIB.BASEBOARD_FAB2(SCH_1):PAGE208_I27@MSTR_DISCRETE.IR354XX(CHIPS)':
 'NC': CDS_PINID='NC';
NODE_NAME     EU1D1 31
 '@BASEBOARD_FAB2_LIB.BASEBOARD_FAB2(SCH_1):PAGE208_I71@MSTR_DISCRETE.IR354XX(CHIPS)':
 'NC': CDS_PINID='NC';
NODE_NAME     EU1C3 31
 '@BASEBOARD_FAB2_LIB.BASEBOARD_FAB2(SCH_1):PAGE209_I56@MSTR_DISCRETE.IR354XX(CHIPS)':
 'NC': CDS_PINID='NC';
NODE_NAME     EU1C1 31
 '@BASEBOARD_FAB2_LIB.BASEBOARD_FAB2(SCH_1):PAGE210_I51@MSTR_DISCRETE.IR354XX(CHIPS)':
 'NC': CDS_PINID='NC';
NODE_NAME     EU3P1 25
 '@BASEBOARD_FAB2_LIB.BASEBOARD_FAB2(SCH_1):PAGE211_I93@MSTR_CONTROLLER.PXE1110B(CHIPS)':
 'BIREF1': CDS_PINID='BIREF1';
NODE_NAME     EU3P1 3
 '@BASEBOARD_FAB2_LIB.BASEBOARD_FAB2(SCH_1):PAGE211_I93@MSTR_CONTROLLER.PXE1110B(CHIPS)':
 'BPWM1': CDS_PINID='BPWM1';
NODE_NAME     EU3P1 34
 '@BASEBOARD_FAB2_LIB.BASEBOARD_FAB2(SCH_1):PAGE211_I93@MSTR_CONTROLLER.PXE1110B(CHIPS)':
 'BTSEN': CDS_PINID='BTSEN';
NODE_NAME     EU3P1 30
 '@BASEBOARD_FAB2_LIB.BASEBOARD_FAB2(SCH_1):PAGE211_I93@MSTR_CONTROLLER.PXE1110B(CHIPS)':
 'BVREF': CDS_PINID='BVREF';
NODE_NAME     EU3P1 29
 '@BASEBOARD_FAB2_LIB.BASEBOARD_FAB2(SCH_1):PAGE211_I93@MSTR_CONTROLLER.PXE1110B(CHIPS)':
 'BVSEN': CDS_PINID='BVSEN';
NODE_NAME     EU3P1 1
 '@BASEBOARD_FAB2_LIB.BASEBOARD_FAB2(SCH_1):PAGE211_I93@MSTR_CONTROLLER.PXE1110B(CHIPS)':
 'DNC'<0>: CDS_PINID='DNC(0)';
NODE_NAME     EU3P1 2
 '@BASEBOARD_FAB2_LIB.BASEBOARD_FAB2(SCH_1):PAGE211_I93@MSTR_CONTROLLER.PXE1110B(CHIPS)':
 'DNC'<1>: CDS_PINID='DNC(1)';
NODE_NAME     EU3P1 4
 '@BASEBOARD_FAB2_LIB.BASEBOARD_FAB2(SCH_1):PAGE211_I93@MSTR_CONTROLLER.PXE1110B(CHIPS)':
 'DNC'<2>: CDS_PINID='DNC(2)';
NODE_NAME     EU3P1 24
 '@BASEBOARD_FAB2_LIB.BASEBOARD_FAB2(SCH_1):PAGE211_I93@MSTR_CONTROLLER.PXE1110B(CHIPS)':
 'DNC'<3>: CDS_PINID='DNC(3)';
NODE_NAME     EU3P1 28
 '@BASEBOARD_FAB2_LIB.BASEBOARD_FAB2(SCH_1):PAGE211_I93@MSTR_CONTROLLER.PXE1110B(CHIPS)':
 'DNC'<4>: CDS_PINID='DNC(4)';
NODE_NAME     EU3P1 38
 '@BASEBOARD_FAB2_LIB.BASEBOARD_FAB2(SCH_1):PAGE211_I93@MSTR_CONTROLLER.PXE1110B(CHIPS)':
 'IINSEN': CDS_PINID='IINSEN';
NODE_NAME     EU3P1 13
 '@BASEBOARD_FAB2_LIB.BASEBOARD_FAB2(SCH_1):PAGE211_I93@MSTR_CONTROLLER.PXE1110B(CHIPS)':
 'MP0': CDS_PINID='MP0';
NODE_NAME     EU3P1 14
 '@BASEBOARD_FAB2_LIB.BASEBOARD_FAB2(SCH_1):PAGE211_I93@MSTR_CONTROLLER.PXE1110B(CHIPS)':
 'MP1': CDS_PINID='MP1';
NODE_NAME     EU3P1 18
 '@BASEBOARD_FAB2_LIB.BASEBOARD_FAB2(SCH_1):PAGE211_I93@MSTR_CONTROLLER.PXE1110B(CHIPS)':
 'MP2': CDS_PINID='MP2';
NODE_NAME     EU3P1 31
 '@BASEBOARD_FAB2_LIB.BASEBOARD_FAB2(SCH_1):PAGE211_I93@MSTR_CONTROLLER.PXE1110B(CHIPS)':
 'MP3': CDS_PINID='MP3';
NODE_NAME     EU3P1 12
 '@BASEBOARD_FAB2_LIB.BASEBOARD_FAB2(SCH_1):PAGE211_I93@MSTR_CONTROLLER.PXE1110B(CHIPS)':
 'PINALRT_N': CDS_PINID='PINALRT_N';
NODE_NAME     EU3P1 8
 '@BASEBOARD_FAB2_LIB.BASEBOARD_FAB2(SCH_1):PAGE211_I93@MSTR_CONTROLLER.PXE1110B(CHIPS)':
 'RESET_N': CDS_PINID='RESET_N';
NODE_NAME     EU7C1 31
 '@BASEBOARD_FAB2_LIB.BASEBOARD_FAB2(SCH_1):PAGE212_I101@MSTR_DISCRETE.IR354XX(CHIPS)':
 'NC': CDS_PINID='NC';
NODE_NAME     EU4D5 25
 '@BASEBOARD_FAB2_LIB.BASEBOARD_FAB2(SCH_1):PAGE213_I96@MSTR_CONTROLLER.PXE1110B(CHIPS)':
 'BIREF1': CDS_PINID='BIREF1';
NODE_NAME     EU4D5 3
 '@BASEBOARD_FAB2_LIB.BASEBOARD_FAB2(SCH_1):PAGE213_I96@MSTR_CONTROLLER.PXE1110B(CHIPS)':
 'BPWM1': CDS_PINID='BPWM1';
NODE_NAME     EU4D5 34
 '@BASEBOARD_FAB2_LIB.BASEBOARD_FAB2(SCH_1):PAGE213_I96@MSTR_CONTROLLER.PXE1110B(CHIPS)':
 'BTSEN': CDS_PINID='BTSEN';
NODE_NAME     EU4D5 30
 '@BASEBOARD_FAB2_LIB.BASEBOARD_FAB2(SCH_1):PAGE213_I96@MSTR_CONTROLLER.PXE1110B(CHIPS)':
 'BVREF': CDS_PINID='BVREF';
NODE_NAME     EU4D5 29
 '@BASEBOARD_FAB2_LIB.BASEBOARD_FAB2(SCH_1):PAGE213_I96@MSTR_CONTROLLER.PXE1110B(CHIPS)':
 'BVSEN': CDS_PINID='BVSEN';
NODE_NAME     EU4D5 1
 '@BASEBOARD_FAB2_LIB.BASEBOARD_FAB2(SCH_1):PAGE213_I96@MSTR_CONTROLLER.PXE1110B(CHIPS)':
 'DNC'<0>: CDS_PINID='DNC(0)';
NODE_NAME     EU4D5 2
 '@BASEBOARD_FAB2_LIB.BASEBOARD_FAB2(SCH_1):PAGE213_I96@MSTR_CONTROLLER.PXE1110B(CHIPS)':
 'DNC'<1>: CDS_PINID='DNC(1)';
NODE_NAME     EU4D5 4
 '@BASEBOARD_FAB2_LIB.BASEBOARD_FAB2(SCH_1):PAGE213_I96@MSTR_CONTROLLER.PXE1110B(CHIPS)':
 'DNC'<2>: CDS_PINID='DNC(2)';
NODE_NAME     EU4D5 24
 '@BASEBOARD_FAB2_LIB.BASEBOARD_FAB2(SCH_1):PAGE213_I96@MSTR_CONTROLLER.PXE1110B(CHIPS)':
 'DNC'<3>: CDS_PINID='DNC(3)';
NODE_NAME     EU4D5 28
 '@BASEBOARD_FAB2_LIB.BASEBOARD_FAB2(SCH_1):PAGE213_I96@MSTR_CONTROLLER.PXE1110B(CHIPS)':
 'DNC'<4>: CDS_PINID='DNC(4)';
NODE_NAME     EU4D5 38
 '@BASEBOARD_FAB2_LIB.BASEBOARD_FAB2(SCH_1):PAGE213_I96@MSTR_CONTROLLER.PXE1110B(CHIPS)':
 'IINSEN': CDS_PINID='IINSEN';
NODE_NAME     EU4D5 13
 '@BASEBOARD_FAB2_LIB.BASEBOARD_FAB2(SCH_1):PAGE213_I96@MSTR_CONTROLLER.PXE1110B(CHIPS)':
 'MP0': CDS_PINID='MP0';
NODE_NAME     EU4D5 14
 '@BASEBOARD_FAB2_LIB.BASEBOARD_FAB2(SCH_1):PAGE213_I96@MSTR_CONTROLLER.PXE1110B(CHIPS)':
 'MP1': CDS_PINID='MP1';
NODE_NAME     EU4D5 18
 '@BASEBOARD_FAB2_LIB.BASEBOARD_FAB2(SCH_1):PAGE213_I96@MSTR_CONTROLLER.PXE1110B(CHIPS)':
 'MP2': CDS_PINID='MP2';
NODE_NAME     EU4D5 31
 '@BASEBOARD_FAB2_LIB.BASEBOARD_FAB2(SCH_1):PAGE213_I96@MSTR_CONTROLLER.PXE1110B(CHIPS)':
 'MP3': CDS_PINID='MP3';
NODE_NAME     EU4D5 12
 '@BASEBOARD_FAB2_LIB.BASEBOARD_FAB2(SCH_1):PAGE213_I96@MSTR_CONTROLLER.PXE1110B(CHIPS)':
 'PINALRT_N': CDS_PINID='PINALRT_N';
NODE_NAME     EU4D5 8
 '@BASEBOARD_FAB2_LIB.BASEBOARD_FAB2(SCH_1):PAGE213_I96@MSTR_CONTROLLER.PXE1110B(CHIPS)':
 'RESET_N': CDS_PINID='RESET_N';
NODE_NAME     EU4E2 31
 '@BASEBOARD_FAB2_LIB.BASEBOARD_FAB2(SCH_1):PAGE214_I126@MSTR_DISCRETE.IR354XX(CHIPS)':
 'NC': CDS_PINID='NC';
NODE_NAME     EU7G2 31
 '@BASEBOARD_FAB2_LIB.BASEBOARD_FAB2(SCH_1):PAGE216_I102@MSTR_DISCRETE.IR354XX(CHIPS)':
 'NC': CDS_PINID='NC';
NODE_NAME     EU7G3 31
 '@BASEBOARD_FAB2_LIB.BASEBOARD_FAB2(SCH_1):PAGE216_I103@MSTR_DISCRETE.IR354XX(CHIPS)':
 'NC': CDS_PINID='NC';
NODE_NAME     EU7A1 31
 '@BASEBOARD_FAB2_LIB.BASEBOARD_FAB2(SCH_1):PAGE219_I106@MSTR_DISCRETE.IR354XX(CHIPS)':
 'NC': CDS_PINID='NC';
NODE_NAME     EU7A4 31
 '@BASEBOARD_FAB2_LIB.BASEBOARD_FAB2(SCH_1):PAGE219_I107@MSTR_DISCRETE.IR354XX(CHIPS)':
 'NC': CDS_PINID='NC';
NODE_NAME     EU1G1 31
 '@BASEBOARD_FAB2_LIB.BASEBOARD_FAB2(SCH_1):PAGE224_I110@MSTR_DISCRETE.IR354XX(CHIPS)':
 'NC': CDS_PINID='NC';
NODE_NAME     EU1F1 31
 '@BASEBOARD_FAB2_LIB.BASEBOARD_FAB2(SCH_1):PAGE224_I111@MSTR_DISCRETE.IR354XX(CHIPS)':
 'NC': CDS_PINID='NC';
NODE_NAME     EU1A2 31
 '@BASEBOARD_FAB2_LIB.BASEBOARD_FAB2(SCH_1):PAGE227_I101@MSTR_DISCRETE.IR354XX(CHIPS)':
 'NC': CDS_PINID='NC';
NODE_NAME     EU1A1 31
 '@BASEBOARD_FAB2_LIB.BASEBOARD_FAB2(SCH_1):PAGE227_I102@MSTR_DISCRETE.IR354XX(CHIPS)':
 'NC': CDS_PINID='NC';
NODE_NAME     EU8A1 1
 '@BASEBOARD_FAB2_LIB.BASEBOARD_FAB2(SCH_1):PAGE235_I229@MSTR_CONTROLLER.PXE1110B(CHIPS)':
 'DNC'<0>: CDS_PINID='DNC(0)';
NODE_NAME     EU8A1 2
 '@BASEBOARD_FAB2_LIB.BASEBOARD_FAB2(SCH_1):PAGE235_I229@MSTR_CONTROLLER.PXE1110B(CHIPS)':
 'DNC'<1>: CDS_PINID='DNC(1)';
NODE_NAME     EU8A1 4
 '@BASEBOARD_FAB2_LIB.BASEBOARD_FAB2(SCH_1):PAGE235_I229@MSTR_CONTROLLER.PXE1110B(CHIPS)':
 'DNC'<2>: CDS_PINID='DNC(2)';
NODE_NAME     EU8A1 24
 '@BASEBOARD_FAB2_LIB.BASEBOARD_FAB2(SCH_1):PAGE235_I229@MSTR_CONTROLLER.PXE1110B(CHIPS)':
 'DNC'<3>: CDS_PINID='DNC(3)';
NODE_NAME     EU8A1 28
 '@BASEBOARD_FAB2_LIB.BASEBOARD_FAB2(SCH_1):PAGE235_I229@MSTR_CONTROLLER.PXE1110B(CHIPS)':
 'DNC'<4>: CDS_PINID='DNC(4)';
NODE_NAME     EU8A1 38
 '@BASEBOARD_FAB2_LIB.BASEBOARD_FAB2(SCH_1):PAGE235_I229@MSTR_CONTROLLER.PXE1110B(CHIPS)':
 'IINSEN': CDS_PINID='IINSEN';
NODE_NAME     EU8A1 18
 '@BASEBOARD_FAB2_LIB.BASEBOARD_FAB2(SCH_1):PAGE235_I229@MSTR_CONTROLLER.PXE1110B(CHIPS)':
 'MP2': CDS_PINID='MP2';
NODE_NAME     EU8A1 31
 '@BASEBOARD_FAB2_LIB.BASEBOARD_FAB2(SCH_1):PAGE235_I229@MSTR_CONTROLLER.PXE1110B(CHIPS)':
 'MP3': CDS_PINID='MP3';
NODE_NAME     EU8A1 8
 '@BASEBOARD_FAB2_LIB.BASEBOARD_FAB2(SCH_1):PAGE235_I229@MSTR_CONTROLLER.PXE1110B(CHIPS)':
 'RESET_N': CDS_PINID='RESET_N';
NODE_NAME     EU8A1 17
 '@BASEBOARD_FAB2_LIB.BASEBOARD_FAB2(SCH_1):PAGE235_I229@MSTR_CONTROLLER.PXE1110B(CHIPS)':
 'VALRT_N': CDS_PINID='VALRT_N';
NODE_NAME     EU7A3 31
 '@BASEBOARD_FAB2_LIB.BASEBOARD_FAB2(SCH_1):PAGE236_I116@MSTR_DISCRETE.IR354XX(CHIPS)':
 'NC': CDS_PINID='NC';
NODE_NAME     EU7A2 31
 '@BASEBOARD_FAB2_LIB.BASEBOARD_FAB2(SCH_1):PAGE236_I117@MSTR_DISCRETE.IR354XX(CHIPS)':
 'NC': CDS_PINID='NC';
NODE_NAME     CONX8 2
 '@BASEBOARD_FAB2_LIB.BASEBOARD_FAB2(SCH_1):PAGE245_I48@W_HDL.SMC-CONN60A-22-GP(CHIPS)':
 '2': CDS_PINID='\2\';
NODE_NAME     CONX8 NP1
 '@BASEBOARD_FAB2_LIB.BASEBOARD_FAB2(SCH_1):PAGE245_I48@W_HDL.SMC-CONN60A-22-GP(CHIPS)':
 'NP1': CDS_PINID='NP1';
NODE_NAME     CONX8 NP2
 '@BASEBOARD_FAB2_LIB.BASEBOARD_FAB2(SCH_1):PAGE245_I48@W_HDL.SMC-CONN60A-22-GP(CHIPS)':
 'NP2': CDS_PINID='NP2';
NODE_NAME     U25W4 W20
 '@BASEBOARD_FAB2_LIB.BASEBOARD_FAB2(SCH_1):PAGE146_I104@W_HDL.AST2520A1-GP-GP(CHIPS)':
 'GPIOS5_VPOB7': CDS_PINID='GPIOS5_VPOB7';
NODE_NAME     U25W4 R20
 '@BASEBOARD_FAB2_LIB.BASEBOARD_FAB2(SCH_1):PAGE146_I105@W_HDL.AST2520A1-GP-GP(CHIPS)':
 'GPIOAB3_VPOCLK_WDTRST2': CDS_PINID='GPIOAB3_VPOCLK_WDTRST2';
NODE_NAME     U25W4 B5
 '@BASEBOARD_FAB2_LIB.BASEBOARD_FAB2(SCH_1):PAGE147_I106@W_HDL.AST2520A1-GP-GP(CHIPS)':
 'RGMII1TXCK_RMII1RCLKO_GPIOT0': CDS_PINID='RGMII1TXCK_RMII1RCLKO_GPIOT0';
NODE_NAME     U25W4 B2
 '@BASEBOARD_FAB2_LIB.BASEBOARD_FAB2(SCH_1):PAGE147_I106@W_HDL.AST2520A1-GP-GP(CHIPS)':
 'RGMII2TXCK_RMII2RCLKO_GPIOT6': CDS_PINID='RGMII2TXCK_RMII2RCLKO_GPIOT6';
NODE_NAME     U25W4 D3
 '@BASEBOARD_FAB2_LIB.BASEBOARD_FAB2(SCH_1):PAGE147_I106@W_HDL.AST2520A1-GP-GP(CHIPS)':
 'RGMIICK': CDS_PINID='RGMIICK';
NODE_NAME     U25W5 T7
 '@BASEBOARD_FAB2_LIB.BASEBOARD_FAB2(SCH_1):PAGE151_I49@W_HDL.H5AN4G6NAFR-TFC-GP(CHIPS)':
 'NC#T7': CDS_PINID='\nc#t7\';
NODE_NAME     CR25W1 5
 '@BASEBOARD_FAB2_LIB.BASEBOARD_FAB2(SCH_1):PAGE255_I129@MSTR_DISCRETE.DIODEAC_DUAL_ARRAY(CHIPS)':
 'AC3': CDS_PINID='AC3';
NODE_NAME     CR25W1 6
 '@BASEBOARD_FAB2_LIB.BASEBOARD_FAB2(SCH_1):PAGE255_I129@MSTR_DISCRETE.DIODEAC_DUAL_ARRAY(CHIPS)':
 'OUT3': CDS_PINID='OUT3';
NODE_NAME     J2W1 NP1
 '@BASEBOARD_FAB2_LIB.BASEBOARD_FAB2(SCH_1):PAGE172_I67@W_HDL.SKT-SATA7P-6P-165-GP-U1(CHIPS)':
 'NP1': CDS_PINID='NP1';
NODE_NAME     J2W1 NP2
 '@BASEBOARD_FAB2_LIB.BASEBOARD_FAB2(SCH_1):PAGE172_I67@W_HDL.SKT-SATA7P-6P-165-GP-U1(CHIPS)':
 'NP2': CDS_PINID='NP2';
NODE_NAME     J2W2 NP1
 '@BASEBOARD_FAB2_LIB.BASEBOARD_FAB2(SCH_1):PAGE172_I68@W_HDL.SKT-SATA7P-6P-165-GP-U1(CHIPS)':
 'NP1': CDS_PINID='NP1';
NODE_NAME     J2W2 NP2
 '@BASEBOARD_FAB2_LIB.BASEBOARD_FAB2(SCH_1):PAGE172_I68@W_HDL.SKT-SATA7P-6P-165-GP-U1(CHIPS)':
 'NP2': CDS_PINID='NP2';
NODE_NAME     J8F1 20
 '@BASEBOARD_FAB2_LIB.BASEBOARD_FAB2(SCH_1):PAGE185_I143@W_HDL.SKT-MINI67P-41-GP(CHIPS)':
 '20': CDS_PINID='\20\';
NODE_NAME     J8F1 22
 '@BASEBOARD_FAB2_LIB.BASEBOARD_FAB2(SCH_1):PAGE185_I143@W_HDL.SKT-MINI67P-41-GP(CHIPS)':
 '22': CDS_PINID='\22\';
NODE_NAME     J8F1 24
 '@BASEBOARD_FAB2_LIB.BASEBOARD_FAB2(SCH_1):PAGE185_I143@W_HDL.SKT-MINI67P-41-GP(CHIPS)':
 '24': CDS_PINID='\24\';
NODE_NAME     J8F1 26
 '@BASEBOARD_FAB2_LIB.BASEBOARD_FAB2(SCH_1):PAGE185_I143@W_HDL.SKT-MINI67P-41-GP(CHIPS)':
 '26': CDS_PINID='\26\';
NODE_NAME     J8F1 28
 '@BASEBOARD_FAB2_LIB.BASEBOARD_FAB2(SCH_1):PAGE185_I143@W_HDL.SKT-MINI67P-41-GP(CHIPS)':
 '28': CDS_PINID='\28\';
NODE_NAME     J8F1 30
 '@BASEBOARD_FAB2_LIB.BASEBOARD_FAB2(SCH_1):PAGE185_I143@W_HDL.SKT-MINI67P-41-GP(CHIPS)':
 '30': CDS_PINID='\30\';
NODE_NAME     J8F1 32
 '@BASEBOARD_FAB2_LIB.BASEBOARD_FAB2(SCH_1):PAGE185_I143@W_HDL.SKT-MINI67P-41-GP(CHIPS)':
 '32': CDS_PINID='\32\';
NODE_NAME     J8F1 34
 '@BASEBOARD_FAB2_LIB.BASEBOARD_FAB2(SCH_1):PAGE185_I143@W_HDL.SKT-MINI67P-41-GP(CHIPS)':
 '34': CDS_PINID='\34\';
NODE_NAME     J8F1 36
 '@BASEBOARD_FAB2_LIB.BASEBOARD_FAB2(SCH_1):PAGE185_I143@W_HDL.SKT-MINI67P-41-GP(CHIPS)':
 '36': CDS_PINID='\36\';
NODE_NAME     J8F1 46
 '@BASEBOARD_FAB2_LIB.BASEBOARD_FAB2(SCH_1):PAGE185_I143@W_HDL.SKT-MINI67P-41-GP(CHIPS)':
 '46': CDS_PINID='\46\';
NODE_NAME     J8F1 48
 '@BASEBOARD_FAB2_LIB.BASEBOARD_FAB2(SCH_1):PAGE185_I143@W_HDL.SKT-MINI67P-41-GP(CHIPS)':
 '48': CDS_PINID='\48\';
NODE_NAME     J8F1 56
 '@BASEBOARD_FAB2_LIB.BASEBOARD_FAB2(SCH_1):PAGE185_I143@W_HDL.SKT-MINI67P-41-GP(CHIPS)':
 '56': CDS_PINID='\56\';
NODE_NAME     J8F1 58
 '@BASEBOARD_FAB2_LIB.BASEBOARD_FAB2(SCH_1):PAGE185_I143@W_HDL.SKT-MINI67P-41-GP(CHIPS)':
 '58': CDS_PINID='\58\';
NODE_NAME     J8F1 67
 '@BASEBOARD_FAB2_LIB.BASEBOARD_FAB2(SCH_1):PAGE185_I143@W_HDL.SKT-MINI67P-41-GP(CHIPS)':
 '67': CDS_PINID='\67\';
NODE_NAME     J8F1 NP1
 '@BASEBOARD_FAB2_LIB.BASEBOARD_FAB2(SCH_1):PAGE185_I143@W_HDL.SKT-MINI67P-41-GP(CHIPS)':
 'NP1': CDS_PINID='NP1';
NODE_NAME     J8F1 NP2
 '@BASEBOARD_FAB2_LIB.BASEBOARD_FAB2(SCH_1):PAGE185_I143@W_HDL.SKT-MINI67P-41-GP(CHIPS)':
 'NP2': CDS_PINID='NP2';
NODE_NAME     J1E1 NP1
 '@BASEBOARD_FAB2_LIB.BASEBOARD_FAB2(SCH_1):PAGE195_I114@W_HDL.FCI-CONN12-2R-GP(CHIPS)':
 'NP1': CDS_PINID='NP1';
NODE_NAME     J1D1 NP1
 '@BASEBOARD_FAB2_LIB.BASEBOARD_FAB2(SCH_1):PAGE195_I115@W_HDL.FCI-CONN12-2R-GP(CHIPS)':
 'NP1': CDS_PINID='NP1';
NODE_NAME     J30W1 A5
 '@BASEBOARD_FAB2_LIB.BASEBOARD_FAB2(SCH_1):PAGE253_I26@W_HDL.SKT-USB32-8-GP(CHIPS)':
 'CC1': CDS_PINID='CC1';
NODE_NAME     J30W1 B5
 '@BASEBOARD_FAB2_LIB.BASEBOARD_FAB2(SCH_1):PAGE253_I26@W_HDL.SKT-USB32-8-GP(CHIPS)':
 'CC2': CDS_PINID='CC2';
NODE_NAME     J30W1 A7
 '@BASEBOARD_FAB2_LIB.BASEBOARD_FAB2(SCH_1):PAGE253_I26@W_HDL.SKT-USB32-8-GP(CHIPS)':
 'DN1': CDS_PINID='DN1';
NODE_NAME     J30W1 B7
 '@BASEBOARD_FAB2_LIB.BASEBOARD_FAB2(SCH_1):PAGE253_I26@W_HDL.SKT-USB32-8-GP(CHIPS)':
 'DN2': CDS_PINID='DN2';
NODE_NAME     J30W1 A6
 '@BASEBOARD_FAB2_LIB.BASEBOARD_FAB2(SCH_1):PAGE253_I26@W_HDL.SKT-USB32-8-GP(CHIPS)':
 'DP1': CDS_PINID='DP1';
NODE_NAME     J30W1 B6
 '@BASEBOARD_FAB2_LIB.BASEBOARD_FAB2(SCH_1):PAGE253_I26@W_HDL.SKT-USB32-8-GP(CHIPS)':
 'DP2': CDS_PINID='DP2';
NODE_NAME     J30W1 NP1
 '@BASEBOARD_FAB2_LIB.BASEBOARD_FAB2(SCH_1):PAGE253_I26@W_HDL.SKT-USB32-8-GP(CHIPS)':
 'NP1': CDS_PINID='NP1';
NODE_NAME     J30W1 NP2
 '@BASEBOARD_FAB2_LIB.BASEBOARD_FAB2(SCH_1):PAGE253_I26@W_HDL.SKT-USB32-8-GP(CHIPS)':
 'NP2': CDS_PINID='NP2';
NODE_NAME     J30W1 A8
 '@BASEBOARD_FAB2_LIB.BASEBOARD_FAB2(SCH_1):PAGE253_I26@W_HDL.SKT-USB32-8-GP(CHIPS)':
 'SBU1': CDS_PINID='SBU1';
NODE_NAME     J30W1 B8
 '@BASEBOARD_FAB2_LIB.BASEBOARD_FAB2(SCH_1):PAGE253_I26@W_HDL.SKT-USB32-8-GP(CHIPS)':
 'SBU2': CDS_PINID='SBU2';
NODE_NAME     J30W1 A10
 '@BASEBOARD_FAB2_LIB.BASEBOARD_FAB2(SCH_1):PAGE253_I26@W_HDL.SKT-USB32-8-GP(CHIPS)':
 'SSRXN2': CDS_PINID='SSRXN2';
NODE_NAME     J30W1 A11
 '@BASEBOARD_FAB2_LIB.BASEBOARD_FAB2(SCH_1):PAGE253_I26@W_HDL.SKT-USB32-8-GP(CHIPS)':
 'SSRXP2': CDS_PINID='SSRXP2';
NODE_NAME     J30W1 B3
 '@BASEBOARD_FAB2_LIB.BASEBOARD_FAB2(SCH_1):PAGE253_I26@W_HDL.SKT-USB32-8-GP(CHIPS)':
 'SSTXN2': CDS_PINID='SSTXN2';
NODE_NAME     J30W1 B2
 '@BASEBOARD_FAB2_LIB.BASEBOARD_FAB2(SCH_1):PAGE253_I26@W_HDL.SKT-USB32-8-GP(CHIPS)':
 'SSTXP2': CDS_PINID='SSTXP2';
NODE_NAME     EU7G1 25
 '@BASEBOARD_FAB2_LIB.BASEBOARD_FAB2(SCH_1):PAGE215_I69@MSTR_CONTROLLER.PXM1310B(CHIPS)':
 'AIREF3': CDS_PINID='AIREF3';
NODE_NAME     EU7G1 26
 '@BASEBOARD_FAB2_LIB.BASEBOARD_FAB2(SCH_1):PAGE215_I69@MSTR_CONTROLLER.PXM1310B(CHIPS)':
 'AISEN3': CDS_PINID='AISEN3';
NODE_NAME     EU7G1 3
 '@BASEBOARD_FAB2_LIB.BASEBOARD_FAB2(SCH_1):PAGE215_I69@MSTR_CONTROLLER.PXM1310B(CHIPS)':
 'APWM3': CDS_PINID='APWM3';
NODE_NAME     EU7G1 31
 '@BASEBOARD_FAB2_LIB.BASEBOARD_FAB2(SCH_1):PAGE215_I69@MSTR_CONTROLLER.PXM1310B(CHIPS)':
 'BIREF1': CDS_PINID='BIREF1';
NODE_NAME     EU7G1 1
 '@BASEBOARD_FAB2_LIB.BASEBOARD_FAB2(SCH_1):PAGE215_I69@MSTR_CONTROLLER.PXM1310B(CHIPS)':
 'BPWM1': CDS_PINID='BPWM1';
NODE_NAME     EU7G1 34
 '@BASEBOARD_FAB2_LIB.BASEBOARD_FAB2(SCH_1):PAGE215_I69@MSTR_CONTROLLER.PXM1310B(CHIPS)':
 'BTSEN': CDS_PINID='BTSEN';
NODE_NAME     EU7G1 30
 '@BASEBOARD_FAB2_LIB.BASEBOARD_FAB2(SCH_1):PAGE215_I69@MSTR_CONTROLLER.PXM1310B(CHIPS)':
 'BVREF': CDS_PINID='BVREF';
NODE_NAME     EU7G1 29
 '@BASEBOARD_FAB2_LIB.BASEBOARD_FAB2(SCH_1):PAGE215_I69@MSTR_CONTROLLER.PXM1310B(CHIPS)':
 'BVSEN': CDS_PINID='BVSEN';
NODE_NAME     EU7G1 2
 '@BASEBOARD_FAB2_LIB.BASEBOARD_FAB2(SCH_1):PAGE215_I69@MSTR_CONTROLLER.PXM1310B(CHIPS)':
 'DNC'<0>: CDS_PINID='DNC(0)';
NODE_NAME     EU7G1 28
 '@BASEBOARD_FAB2_LIB.BASEBOARD_FAB2(SCH_1):PAGE215_I69@MSTR_CONTROLLER.PXM1310B(CHIPS)':
 'DNC'<1>: CDS_PINID='DNC(1)';
NODE_NAME     EU7G1 12
 '@BASEBOARD_FAB2_LIB.BASEBOARD_FAB2(SCH_1):PAGE215_I69@MSTR_CONTROLLER.PXM1310B(CHIPS)':
 'PINALRT_N': CDS_PINID='PINALRT_N';
NODE_NAME     EU7G1 8
 '@BASEBOARD_FAB2_LIB.BASEBOARD_FAB2(SCH_1):PAGE215_I69@MSTR_CONTROLLER.PXM1310B(CHIPS)':
 'RESET_N': CDS_PINID='RESET_N';
NODE_NAME     EU7A5 25
 '@BASEBOARD_FAB2_LIB.BASEBOARD_FAB2(SCH_1):PAGE218_I69@MSTR_CONTROLLER.PXM1310B(CHIPS)':
 'AIREF3': CDS_PINID='AIREF3';
NODE_NAME     EU7A5 26
 '@BASEBOARD_FAB2_LIB.BASEBOARD_FAB2(SCH_1):PAGE218_I69@MSTR_CONTROLLER.PXM1310B(CHIPS)':
 'AISEN3': CDS_PINID='AISEN3';
NODE_NAME     EU7A5 3
 '@BASEBOARD_FAB2_LIB.BASEBOARD_FAB2(SCH_1):PAGE218_I69@MSTR_CONTROLLER.PXM1310B(CHIPS)':
 'APWM3': CDS_PINID='APWM3';
NODE_NAME     EU7A5 31
 '@BASEBOARD_FAB2_LIB.BASEBOARD_FAB2(SCH_1):PAGE218_I69@MSTR_CONTROLLER.PXM1310B(CHIPS)':
 'BIREF1': CDS_PINID='BIREF1';
NODE_NAME     EU7A5 1
 '@BASEBOARD_FAB2_LIB.BASEBOARD_FAB2(SCH_1):PAGE218_I69@MSTR_CONTROLLER.PXM1310B(CHIPS)':
 'BPWM1': CDS_PINID='BPWM1';
NODE_NAME     EU7A5 34
 '@BASEBOARD_FAB2_LIB.BASEBOARD_FAB2(SCH_1):PAGE218_I69@MSTR_CONTROLLER.PXM1310B(CHIPS)':
 'BTSEN': CDS_PINID='BTSEN';
NODE_NAME     EU7A5 30
 '@BASEBOARD_FAB2_LIB.BASEBOARD_FAB2(SCH_1):PAGE218_I69@MSTR_CONTROLLER.PXM1310B(CHIPS)':
 'BVREF': CDS_PINID='BVREF';
NODE_NAME     EU7A5 29
 '@BASEBOARD_FAB2_LIB.BASEBOARD_FAB2(SCH_1):PAGE218_I69@MSTR_CONTROLLER.PXM1310B(CHIPS)':
 'BVSEN': CDS_PINID='BVSEN';
NODE_NAME     EU7A5 2
 '@BASEBOARD_FAB2_LIB.BASEBOARD_FAB2(SCH_1):PAGE218_I69@MSTR_CONTROLLER.PXM1310B(CHIPS)':
 'DNC'<0>: CDS_PINID='DNC(0)';
NODE_NAME     EU7A5 28
 '@BASEBOARD_FAB2_LIB.BASEBOARD_FAB2(SCH_1):PAGE218_I69@MSTR_CONTROLLER.PXM1310B(CHIPS)':
 'DNC'<1>: CDS_PINID='DNC(1)';
NODE_NAME     EU7A5 12
 '@BASEBOARD_FAB2_LIB.BASEBOARD_FAB2(SCH_1):PAGE218_I69@MSTR_CONTROLLER.PXM1310B(CHIPS)':
 'PINALRT_N': CDS_PINID='PINALRT_N';
NODE_NAME     EU7A5 8
 '@BASEBOARD_FAB2_LIB.BASEBOARD_FAB2(SCH_1):PAGE218_I69@MSTR_CONTROLLER.PXM1310B(CHIPS)':
 'RESET_N': CDS_PINID='RESET_N';
NODE_NAME     EU1G2 25
 '@BASEBOARD_FAB2_LIB.BASEBOARD_FAB2(SCH_1):PAGE223_I69@MSTR_CONTROLLER.PXM1310B(CHIPS)':
 'AIREF3': CDS_PINID='AIREF3';
NODE_NAME     EU1G2 26
 '@BASEBOARD_FAB2_LIB.BASEBOARD_FAB2(SCH_1):PAGE223_I69@MSTR_CONTROLLER.PXM1310B(CHIPS)':
 'AISEN3': CDS_PINID='AISEN3';
NODE_NAME     EU1G2 3
 '@BASEBOARD_FAB2_LIB.BASEBOARD_FAB2(SCH_1):PAGE223_I69@MSTR_CONTROLLER.PXM1310B(CHIPS)':
 'APWM3': CDS_PINID='APWM3';
NODE_NAME     EU1G2 31
 '@BASEBOARD_FAB2_LIB.BASEBOARD_FAB2(SCH_1):PAGE223_I69@MSTR_CONTROLLER.PXM1310B(CHIPS)':
 'BIREF1': CDS_PINID='BIREF1';
NODE_NAME     EU1G2 1
 '@BASEBOARD_FAB2_LIB.BASEBOARD_FAB2(SCH_1):PAGE223_I69@MSTR_CONTROLLER.PXM1310B(CHIPS)':
 'BPWM1': CDS_PINID='BPWM1';
NODE_NAME     EU1G2 34
 '@BASEBOARD_FAB2_LIB.BASEBOARD_FAB2(SCH_1):PAGE223_I69@MSTR_CONTROLLER.PXM1310B(CHIPS)':
 'BTSEN': CDS_PINID='BTSEN';
NODE_NAME     EU1G2 30
 '@BASEBOARD_FAB2_LIB.BASEBOARD_FAB2(SCH_1):PAGE223_I69@MSTR_CONTROLLER.PXM1310B(CHIPS)':
 'BVREF': CDS_PINID='BVREF';
NODE_NAME     EU1G2 29
 '@BASEBOARD_FAB2_LIB.BASEBOARD_FAB2(SCH_1):PAGE223_I69@MSTR_CONTROLLER.PXM1310B(CHIPS)':
 'BVSEN': CDS_PINID='BVSEN';
NODE_NAME     EU1G2 2
 '@BASEBOARD_FAB2_LIB.BASEBOARD_FAB2(SCH_1):PAGE223_I69@MSTR_CONTROLLER.PXM1310B(CHIPS)':
 'DNC'<0>: CDS_PINID='DNC(0)';
NODE_NAME     EU1G2 28
 '@BASEBOARD_FAB2_LIB.BASEBOARD_FAB2(SCH_1):PAGE223_I69@MSTR_CONTROLLER.PXM1310B(CHIPS)':
 'DNC'<1>: CDS_PINID='DNC(1)';
NODE_NAME     EU1G2 12
 '@BASEBOARD_FAB2_LIB.BASEBOARD_FAB2(SCH_1):PAGE223_I69@MSTR_CONTROLLER.PXM1310B(CHIPS)':
 'PINALRT_N': CDS_PINID='PINALRT_N';
NODE_NAME     EU1G2 8
 '@BASEBOARD_FAB2_LIB.BASEBOARD_FAB2(SCH_1):PAGE223_I69@MSTR_CONTROLLER.PXM1310B(CHIPS)':
 'RESET_N': CDS_PINID='RESET_N';
NODE_NAME     EU1B1 25
 '@BASEBOARD_FAB2_LIB.BASEBOARD_FAB2(SCH_1):PAGE226_I69@MSTR_CONTROLLER.PXM1310B(CHIPS)':
 'AIREF3': CDS_PINID='AIREF3';
NODE_NAME     EU1B1 26
 '@BASEBOARD_FAB2_LIB.BASEBOARD_FAB2(SCH_1):PAGE226_I69@MSTR_CONTROLLER.PXM1310B(CHIPS)':
 'AISEN3': CDS_PINID='AISEN3';
NODE_NAME     EU1B1 3
 '@BASEBOARD_FAB2_LIB.BASEBOARD_FAB2(SCH_1):PAGE226_I69@MSTR_CONTROLLER.PXM1310B(CHIPS)':
 'APWM3': CDS_PINID='APWM3';
NODE_NAME     EU1B1 31
 '@BASEBOARD_FAB2_LIB.BASEBOARD_FAB2(SCH_1):PAGE226_I69@MSTR_CONTROLLER.PXM1310B(CHIPS)':
 'BIREF1': CDS_PINID='BIREF1';
NODE_NAME     EU1B1 1
 '@BASEBOARD_FAB2_LIB.BASEBOARD_FAB2(SCH_1):PAGE226_I69@MSTR_CONTROLLER.PXM1310B(CHIPS)':
 'BPWM1': CDS_PINID='BPWM1';
NODE_NAME     EU1B1 34
 '@BASEBOARD_FAB2_LIB.BASEBOARD_FAB2(SCH_1):PAGE226_I69@MSTR_CONTROLLER.PXM1310B(CHIPS)':
 'BTSEN': CDS_PINID='BTSEN';
NODE_NAME     EU1B1 30
 '@BASEBOARD_FAB2_LIB.BASEBOARD_FAB2(SCH_1):PAGE226_I69@MSTR_CONTROLLER.PXM1310B(CHIPS)':
 'BVREF': CDS_PINID='BVREF';
NODE_NAME     EU1B1 29
 '@BASEBOARD_FAB2_LIB.BASEBOARD_FAB2(SCH_1):PAGE226_I69@MSTR_CONTROLLER.PXM1310B(CHIPS)':
 'BVSEN': CDS_PINID='BVSEN';
NODE_NAME     EU1B1 2
 '@BASEBOARD_FAB2_LIB.BASEBOARD_FAB2(SCH_1):PAGE226_I69@MSTR_CONTROLLER.PXM1310B(CHIPS)':
 'DNC'<0>: CDS_PINID='DNC(0)';
NODE_NAME     EU1B1 28
 '@BASEBOARD_FAB2_LIB.BASEBOARD_FAB2(SCH_1):PAGE226_I69@MSTR_CONTROLLER.PXM1310B(CHIPS)':
 'DNC'<1>: CDS_PINID='DNC(1)';
NODE_NAME     EU1B1 12
 '@BASEBOARD_FAB2_LIB.BASEBOARD_FAB2(SCH_1):PAGE226_I69@MSTR_CONTROLLER.PXM1310B(CHIPS)':
 'PINALRT_N': CDS_PINID='PINALRT_N';
NODE_NAME     EU1B1 8
 '@BASEBOARD_FAB2_LIB.BASEBOARD_FAB2(SCH_1):PAGE226_I69@MSTR_CONTROLLER.PXM1310B(CHIPS)':
 'RESET_N': CDS_PINID='RESET_N';
NODE_NAME     J1F2 NP1
 '@BASEBOARD_FAB2_LIB.BASEBOARD_FAB2(SCH_1):PAGE161_I139@W_HDL.LOTES-CON4-S1-GP(CHIPS)':
 'NP1': CDS_PINID='NP1';
NODE_NAME     J10W1 NP1
 '@BASEBOARD_FAB2_LIB.BASEBOARD_FAB2(SCH_1):PAGE161_I140@W_HDL.LOTES-CON4-S1-GP(CHIPS)':
 'NP1': CDS_PINID='NP1';
NODE_NAME     U32W2 3
 '@BASEBOARD_FAB2_LIB.BASEBOARD_FAB2(SCH_1):PAGE185_I204@W_HDL.TCA9517DGKR-GP(CHIPS)':
 'SDAA': CDS_PINID='SDAA';
NODE_NAME     U32W2 6
 '@BASEBOARD_FAB2_LIB.BASEBOARD_FAB2(SCH_1):PAGE185_I204@W_HDL.TCA9517DGKR-GP(CHIPS)':
 'SDAB': CDS_PINID='SDAB';
NODE_NAME     U6W11 9
 '@BASEBOARD_FAB2_LIB.BASEBOARD_FAB2(SCH_1):PAGE164_I97@W_HDL.PCA9554PWR-GP(CHIPS)':
 'P4': CDS_PINID='P4';
NODE_NAME     U6W11 10
 '@BASEBOARD_FAB2_LIB.BASEBOARD_FAB2(SCH_1):PAGE164_I97@W_HDL.PCA9554PWR-GP(CHIPS)':
 'P5': CDS_PINID='P5';
NODE_NAME     U6W11 11
 '@BASEBOARD_FAB2_LIB.BASEBOARD_FAB2(SCH_1):PAGE164_I97@W_HDL.PCA9554PWR-GP(CHIPS)':
 'P6': CDS_PINID='P6';
NODE_NAME     U6W11 12
 '@BASEBOARD_FAB2_LIB.BASEBOARD_FAB2(SCH_1):PAGE164_I97@W_HDL.PCA9554PWR-GP(CHIPS)':
 'P7': CDS_PINID='P7';
NODE_NAME     EU1D4 31
 '@BASEBOARD_FAB2_LIB.BASEBOARD_FAB2(SCH_1):PAGE207_I113@MSTR_DISCRETE.IR354XX(CHIPS)':
 'NC': CDS_PINID='NC';
NODE_NAME     S9W1 1
 '@BASEBOARD_FAB2_LIB.BASEBOARD_FAB2(SCH_1):PAGE268_I63@W_HDL.SW-SLIDE75-GP(CHIPS)':
 '1': CDS_PINID='\1\';
NODE_NAME     S9W1 NP1
 '@BASEBOARD_FAB2_LIB.BASEBOARD_FAB2(SCH_1):PAGE268_I63@W_HDL.SW-SLIDE75-GP(CHIPS)':
 'NP1': CDS_PINID='NP1';
NODE_NAME     S9W1 NP2
 '@BASEBOARD_FAB2_LIB.BASEBOARD_FAB2(SCH_1):PAGE268_I63@W_HDL.SW-SLIDE75-GP(CHIPS)':
 'NP2': CDS_PINID='NP2';
NET_NAME
'NC_CLK_156M_CPU0_OSC'
 '@BASEBOARD_FAB2_LIB.BASEBOARD_FAB2(SCH_1):NC_CLK_156M_CPU0_OSC':
 C_SIGNAL='@baseboard_fab2_lib.baseboard_fab2(sch_1):nc_clk_156m_cpu0_osc';
NODE_NAME     Y6F1 2
 '@BASEBOARD_FAB2_LIB.BASEBOARD_FAB2(SCH_1):PAGE104_I71@MSTR_DISCRETE.OSC_C(CHIPS)':
 'NC_GND': CDS_PINID='NC_GND';
NET_NAME
'NC_CLK_156M_CPU1_OSC'
 '@BASEBOARD_FAB2_LIB.BASEBOARD_FAB2(SCH_1):NC_CLK_156M_CPU1_OSC':
 C_SIGNAL='@baseboard_fab2_lib.baseboard_fab2(sch_1):nc_clk_156m_cpu1_osc';
NODE_NAME     Y3F1 2
 '@BASEBOARD_FAB2_LIB.BASEBOARD_FAB2(SCH_1):PAGE104_I72@MSTR_DISCRETE.OSC_C(CHIPS)':
 'NC_GND': CDS_PINID='NC_GND';
NET_NAME
'NC_M2<0>'
 '@BASEBOARD_FAB2_LIB.BASEBOARD_FAB2(SCH_1):NC_M2'<0>:
 C_SIGNAL='@baseboard_fab2_lib.baseboard_fab2(sch_1):nc_m2(0)';
NODE_NAME     J8F1 6
 '@BASEBOARD_FAB2_LIB.BASEBOARD_FAB2(SCH_1):PAGE185_I143@W_HDL.SKT-MINI67P-41-GP(CHIPS)':
 '6': CDS_PINID='\6\';
NET_NAME
'NC_M2<1>'
 '@BASEBOARD_FAB2_LIB.BASEBOARD_FAB2(SCH_1):NC_M2'<1>:
 C_SIGNAL='@baseboard_fab2_lib.baseboard_fab2(sch_1):nc_m2(1)';
NODE_NAME     J8F1 8
 '@BASEBOARD_FAB2_LIB.BASEBOARD_FAB2(SCH_1):PAGE185_I143@W_HDL.SKT-MINI67P-41-GP(CHIPS)':
 '8': CDS_PINID='\8\';
NET_NAME
'NC_PVDDQ_KLM_GP0'
 '@BASEBOARD_FAB2_LIB.BASEBOARD_FAB2(SCH_1):NC_PVDDQ_KLM_GP0':
 C_SIGNAL='@baseboard_fab2_lib.baseboard_fab2(sch_1):nc_pvddq_klm_gp0';
NODE_NAME     R12W36 1
 '@BASEBOARD_FAB2_LIB.BASEBOARD_FAB2(SCH_1):PAGE226_I53@MSTR_DISCRETE.RES(CHIPS)':
 'A': CDS_PINID='A';
NODE_NAME     EU1B1 18
 '@BASEBOARD_FAB2_LIB.BASEBOARD_FAB2(SCH_1):PAGE226_I69@MSTR_CONTROLLER.PXM1310B(CHIPS)':
 'MP2': CDS_PINID='MP2';
NET_NAME
'NC_PVDDQ_KLM_GP1'
 '@BASEBOARD_FAB2_LIB.BASEBOARD_FAB2(SCH_1):NC_PVDDQ_KLM_GP1':
 C_SIGNAL='@baseboard_fab2_lib.baseboard_fab2(sch_1):nc_pvddq_klm_gp1';
NODE_NAME     R12W35 1
 '@BASEBOARD_FAB2_LIB.BASEBOARD_FAB2(SCH_1):PAGE226_I46@MSTR_DISCRETE.RES(CHIPS)':
 'A': CDS_PINID='A';
NODE_NAME     EU1B1 14
 '@BASEBOARD_FAB2_LIB.BASEBOARD_FAB2(SCH_1):PAGE226_I69@MSTR_CONTROLLER.PXM1310B(CHIPS)':
 'MP1': CDS_PINID='MP1';
NET_NAME
'NIC_LED_ACT_ANODE_R'
 '@BASEBOARD_FAB2_LIB.BASEBOARD_FAB2(SCH_1):NIC_LED_ACT_ANODE_R':
 C_SIGNAL='@baseboard_fab2_lib.baseboard_fab2(sch_1):nic_led_act_anode_r';
NODE_NAME     JA9G1 L4
 '@BASEBOARD_FAB2_LIB.BASEBOARD_FAB2(SCH_1):PAGE141_I129@W_HDL.SKT-RJ45-LED-XFOR-1-GP(CHIPS)':
 'L4': CDS_PINID='L4';
NODE_NAME     R9G4 1
 '@BASEBOARD_FAB2_LIB.BASEBOARD_FAB2(SCH_1):PAGE141_I156@MSTR_DISCRETE.RES(CHIPS)':
 'A': CDS_PINID='A';
NET_NAME
'NIC_MDI_MNG_RX_DN'
 '@BASEBOARD_FAB2_LIB.BASEBOARD_FAB2(SCH_1):NIC_MDI_MNG_RX_DN':
 C_SIGNAL='@baseboard_fab2_lib.baseboard_fab2(sch_1):nic_mdi_mng_rx_dn';
NODE_NAME     C9G12 2
 '@BASEBOARD_FAB2_LIB.BASEBOARD_FAB2(SCH_1):PAGE141_I100@MSTR_DISCRETE.CAP(CHIPS)':
 'B': CDS_PINID='B';
NODE_NAME     J1F1 E5
 '@BASEBOARD_FAB2_LIB.BASEBOARD_FAB2(SCH_1):PAGE181_I134@W_HDL.DM-FCI-CONN76-8R-GP-U-01(CHIPS)':
 'MNG_RX_DN': CDS_PINID='MNG_RX_DN';
NET_NAME
'NIC_MDI_MNG_RX_DP'
 '@BASEBOARD_FAB2_LIB.BASEBOARD_FAB2(SCH_1):NIC_MDI_MNG_RX_DP':
 C_SIGNAL='@baseboard_fab2_lib.baseboard_fab2(sch_1):nic_mdi_mng_rx_dp';
NODE_NAME     C9G9 2
 '@BASEBOARD_FAB2_LIB.BASEBOARD_FAB2(SCH_1):PAGE141_I99@MSTR_DISCRETE.CAP(CHIPS)':
 'B': CDS_PINID='B';
NODE_NAME     J1F1 D5
 '@BASEBOARD_FAB2_LIB.BASEBOARD_FAB2(SCH_1):PAGE181_I134@W_HDL.DM-FCI-CONN76-8R-GP-U-01(CHIPS)':
 'MNG_RX_DP': CDS_PINID='MNG_RX_DP';
NET_NAME
'NIC_MDI_MNG_TX_DN'
 '@BASEBOARD_FAB2_LIB.BASEBOARD_FAB2(SCH_1):NIC_MDI_MNG_TX_DN':
 C_SIGNAL='@baseboard_fab2_lib.baseboard_fab2(sch_1):nic_mdi_mng_tx_dn';
NODE_NAME     C9G13 2
 '@BASEBOARD_FAB2_LIB.BASEBOARD_FAB2(SCH_1):PAGE141_I102@MSTR_DISCRETE.CAP(CHIPS)':
 'B': CDS_PINID='B';
NODE_NAME     J1F1 B5
 '@BASEBOARD_FAB2_LIB.BASEBOARD_FAB2(SCH_1):PAGE181_I134@W_HDL.DM-FCI-CONN76-8R-GP-U-01(CHIPS)':
 'MNG_TX_DN': CDS_PINID='MNG_TX_DN';
NET_NAME
'NIC_MDI_MNG_TX_DP'
 '@BASEBOARD_FAB2_LIB.BASEBOARD_FAB2(SCH_1):NIC_MDI_MNG_TX_DP':
 C_SIGNAL='@baseboard_fab2_lib.baseboard_fab2(sch_1):nic_mdi_mng_tx_dp';
NODE_NAME     C9G16 2
 '@BASEBOARD_FAB2_LIB.BASEBOARD_FAB2(SCH_1):PAGE141_I101@MSTR_DISCRETE.CAP(CHIPS)':
 'B': CDS_PINID='B';
NODE_NAME     J1F1 A5
 '@BASEBOARD_FAB2_LIB.BASEBOARD_FAB2(SCH_1):PAGE181_I134@W_HDL.DM-FCI-CONN76-8R-GP-U-01(CHIPS)':
 'MNG_TX_DP': CDS_PINID='MNG_TX_DP';
NET_NAME
'NIC_MDI_SPRV_RJ45_0_DN'
 '@BASEBOARD_FAB2_LIB.BASEBOARD_FAB2(SCH_1):NIC_MDI_SPRV_RJ45_0_DN':
 C_SIGNAL='@baseboard_fab2_lib.baseboard_fab2(sch_1):nic_mdi_sprv_rj45_0_dn';
NODE_NAME     EU9E1 57
 '@BASEBOARD_FAB2_LIB.BASEBOARD_FAB2(SCH_1):PAGE139_I72@MSTR_INTEL.SPRINGVILLE(CHIPS)':
 'MDI_MINUS0_SFP_I2C_DATA': CDS_PINID='MDI_MINUS0_SFP_I2C_DATA';
NODE_NAME     R9G22 1
 '@BASEBOARD_FAB2_LIB.BASEBOARD_FAB2(SCH_1):PAGE141_I82@MSTR_DISCRETE.RES(CHIPS)':
 'A': CDS_PINID='A';
NET_NAME
'NIC_MDI_SPRV_RJ45_0_DP'
 '@BASEBOARD_FAB2_LIB.BASEBOARD_FAB2(SCH_1):NIC_MDI_SPRV_RJ45_0_DP':
 C_SIGNAL='@baseboard_fab2_lib.baseboard_fab2(sch_1):nic_mdi_sprv_rj45_0_dp';
NODE_NAME     EU9E1 58
 '@BASEBOARD_FAB2_LIB.BASEBOARD_FAB2(SCH_1):PAGE139_I72@MSTR_INTEL.SPRINGVILLE(CHIPS)':
 'MDI_PLUS0_NC': CDS_PINID='MDI_PLUS0_NC';
NODE_NAME     R9G24 1
 '@BASEBOARD_FAB2_LIB.BASEBOARD_FAB2(SCH_1):PAGE141_I81@MSTR_DISCRETE.RES(CHIPS)':
 'A': CDS_PINID='A';
NET_NAME
'NIC_MDI_SPRV_RJ45_0_R_DN'
 '@BASEBOARD_FAB2_LIB.BASEBOARD_FAB2(SCH_1):NIC_MDI_SPRV_RJ45_0_R_DN':
 C_SIGNAL='@baseboard_fab2_lib.baseboard_fab2(sch_1):nic_mdi_sprv_rj45_0_r_dn';
NODE_NAME     R9G22 2
 '@BASEBOARD_FAB2_LIB.BASEBOARD_FAB2(SCH_1):PAGE141_I82@MSTR_DISCRETE.RES(CHIPS)':
 'B': CDS_PINID='B';
NODE_NAME     JA9G1 R3
 '@BASEBOARD_FAB2_LIB.BASEBOARD_FAB2(SCH_1):PAGE141_I129@W_HDL.SKT-RJ45-LED-XFOR-1-GP(CHIPS)':
 'R3': CDS_PINID='R3';
NET_NAME
'NIC_MDI_SPRV_RJ45_0_R_DP'
 '@BASEBOARD_FAB2_LIB.BASEBOARD_FAB2(SCH_1):NIC_MDI_SPRV_RJ45_0_R_DP':
 C_SIGNAL='@baseboard_fab2_lib.baseboard_fab2(sch_1):nic_mdi_sprv_rj45_0_r_dp';
NODE_NAME     R9G24 2
 '@BASEBOARD_FAB2_LIB.BASEBOARD_FAB2(SCH_1):PAGE141_I81@MSTR_DISCRETE.RES(CHIPS)':
 'B': CDS_PINID='B';
NODE_NAME     JA9G1 R2
 '@BASEBOARD_FAB2_LIB.BASEBOARD_FAB2(SCH_1):PAGE141_I129@W_HDL.SKT-RJ45-LED-XFOR-1-GP(CHIPS)':
 'R2': CDS_PINID='R2';
NET_NAME
'NIC_MDI_SPRV_RJ45_1_DN'
 '@BASEBOARD_FAB2_LIB.BASEBOARD_FAB2(SCH_1):NIC_MDI_SPRV_RJ45_1_DN':
 C_SIGNAL='@baseboard_fab2_lib.baseboard_fab2(sch_1):nic_mdi_sprv_rj45_1_dn';
NODE_NAME     EU9E1 54
 '@BASEBOARD_FAB2_LIB.BASEBOARD_FAB2(SCH_1):PAGE139_I72@MSTR_INTEL.SPRINGVILLE(CHIPS)':
 'MDI_MINUS1_SRDS_SIG_DET': CDS_PINID='MDI_MINUS1_SRDS_SIG_DET';
NODE_NAME     R9G20 1
 '@BASEBOARD_FAB2_LIB.BASEBOARD_FAB2(SCH_1):PAGE141_I80@MSTR_DISCRETE.RES(CHIPS)':
 'A': CDS_PINID='A';
NET_NAME
'NIC_MDI_SPRV_RJ45_1_DP'
 '@BASEBOARD_FAB2_LIB.BASEBOARD_FAB2(SCH_1):NIC_MDI_SPRV_RJ45_1_DP':
 C_SIGNAL='@baseboard_fab2_lib.baseboard_fab2(sch_1):nic_mdi_sprv_rj45_1_dp';
NODE_NAME     EU9E1 55
 '@BASEBOARD_FAB2_LIB.BASEBOARD_FAB2(SCH_1):PAGE139_I72@MSTR_INTEL.SPRINGVILLE(CHIPS)':
 'MDI_PLUS1_SFP_I2C_CLK': CDS_PINID='MDI_PLUS1_SFP_I2C_CLK';
NODE_NAME     R9G19 1
 '@BASEBOARD_FAB2_LIB.BASEBOARD_FAB2(SCH_1):PAGE141_I79@MSTR_DISCRETE.RES(CHIPS)':
 'A': CDS_PINID='A';
NET_NAME
'NIC_MDI_SPRV_RJ45_1_R_DN'
 '@BASEBOARD_FAB2_LIB.BASEBOARD_FAB2(SCH_1):NIC_MDI_SPRV_RJ45_1_R_DN':
 C_SIGNAL='@baseboard_fab2_lib.baseboard_fab2(sch_1):nic_mdi_sprv_rj45_1_r_dn';
NODE_NAME     R9G20 2
 '@BASEBOARD_FAB2_LIB.BASEBOARD_FAB2(SCH_1):PAGE141_I80@MSTR_DISCRETE.RES(CHIPS)':
 'B': CDS_PINID='B';
NODE_NAME     JA9G1 R5
 '@BASEBOARD_FAB2_LIB.BASEBOARD_FAB2(SCH_1):PAGE141_I129@W_HDL.SKT-RJ45-LED-XFOR-1-GP(CHIPS)':
 'R5': CDS_PINID='R5';
NET_NAME
'NIC_MDI_SPRV_RJ45_1_R_DP'
 '@BASEBOARD_FAB2_LIB.BASEBOARD_FAB2(SCH_1):NIC_MDI_SPRV_RJ45_1_R_DP':
 C_SIGNAL='@baseboard_fab2_lib.baseboard_fab2(sch_1):nic_mdi_sprv_rj45_1_r_dp';
NODE_NAME     R9G19 2
 '@BASEBOARD_FAB2_LIB.BASEBOARD_FAB2(SCH_1):PAGE141_I79@MSTR_DISCRETE.RES(CHIPS)':
 'B': CDS_PINID='B';
NODE_NAME     JA9G1 R4
 '@BASEBOARD_FAB2_LIB.BASEBOARD_FAB2(SCH_1):PAGE141_I129@W_HDL.SKT-RJ45-LED-XFOR-1-GP(CHIPS)':
 'R4': CDS_PINID='R4';
NET_NAME
'NIC_MDI_SPRV_RJ45_2_R_DN'
 '@BASEBOARD_FAB2_LIB.BASEBOARD_FAB2(SCH_1):NIC_MDI_SPRV_RJ45_2_R_DN':
 C_SIGNAL='@baseboard_fab2_lib.baseboard_fab2(sch_1):nic_mdi_sprv_rj45_2_r_dn';
NODE_NAME     R9G17 2
 '@BASEBOARD_FAB2_LIB.BASEBOARD_FAB2(SCH_1):PAGE141_I78@MSTR_DISCRETE.RES(CHIPS)':
 'B': CDS_PINID='B';
NODE_NAME     JA9G1 R8
 '@BASEBOARD_FAB2_LIB.BASEBOARD_FAB2(SCH_1):PAGE141_I129@W_HDL.SKT-RJ45-LED-XFOR-1-GP(CHIPS)':
 'R8': CDS_PINID='R8';
NET_NAME
'NIC_MDI_SPRV_RJ45_2_R_DP'
 '@BASEBOARD_FAB2_LIB.BASEBOARD_FAB2(SCH_1):NIC_MDI_SPRV_RJ45_2_R_DP':
 C_SIGNAL='@baseboard_fab2_lib.baseboard_fab2(sch_1):nic_mdi_sprv_rj45_2_r_dp';
NODE_NAME     R9G18 2
 '@BASEBOARD_FAB2_LIB.BASEBOARD_FAB2(SCH_1):PAGE141_I77@MSTR_DISCRETE.RES(CHIPS)':
 'B': CDS_PINID='B';
NODE_NAME     JA9G1 R7
 '@BASEBOARD_FAB2_LIB.BASEBOARD_FAB2(SCH_1):PAGE141_I129@W_HDL.SKT-RJ45-LED-XFOR-1-GP(CHIPS)':
 'R7': CDS_PINID='R7';
NET_NAME
'NIC_MDI_SPRV_RJ45_3_R_DN'
 '@BASEBOARD_FAB2_LIB.BASEBOARD_FAB2(SCH_1):NIC_MDI_SPRV_RJ45_3_R_DN':
 C_SIGNAL='@baseboard_fab2_lib.baseboard_fab2(sch_1):nic_mdi_sprv_rj45_3_r_dn';
NODE_NAME     R9G11 2
 '@BASEBOARD_FAB2_LIB.BASEBOARD_FAB2(SCH_1):PAGE141_I76@MSTR_DISCRETE.RES(CHIPS)':
 'B': CDS_PINID='B';
NODE_NAME     JA9G1 R10
 '@BASEBOARD_FAB2_LIB.BASEBOARD_FAB2(SCH_1):PAGE141_I129@W_HDL.SKT-RJ45-LED-XFOR-1-GP(CHIPS)':
 'R10': CDS_PINID='R10';
NET_NAME
'NIC_MDI_SPRV_RJ45_3_R_DP'
 '@BASEBOARD_FAB2_LIB.BASEBOARD_FAB2(SCH_1):NIC_MDI_SPRV_RJ45_3_R_DP':
 C_SIGNAL='@baseboard_fab2_lib.baseboard_fab2(sch_1):nic_mdi_sprv_rj45_3_r_dp';
NODE_NAME     R9G9 2
 '@BASEBOARD_FAB2_LIB.BASEBOARD_FAB2(SCH_1):PAGE141_I75@MSTR_DISCRETE.RES(CHIPS)':
 'B': CDS_PINID='B';
NODE_NAME     JA9G1 R9
 '@BASEBOARD_FAB2_LIB.BASEBOARD_FAB2(SCH_1):PAGE141_I129@W_HDL.SKT-RJ45-LED-XFOR-1-GP(CHIPS)':
 'R9': CDS_PINID='R9';
NET_NAME
'NIC_SER_N_MDI_3_DN'
 '@BASEBOARD_FAB2_LIB.BASEBOARD_FAB2(SCH_1):NIC_SER_N_MDI_3_DN':
 C_SIGNAL='@baseboard_fab2_lib.baseboard_fab2(sch_1):nic_ser_n_mdi_3_dn';
NODE_NAME     EU9E1 49
 '@BASEBOARD_FAB2_LIB.BASEBOARD_FAB2(SCH_1):PAGE139_I72@MSTR_INTEL.SPRINGVILLE(CHIPS)':
 'MDI_MINUS3_SERN': CDS_PINID='MDI_MINUS3_SERN';
NODE_NAME     R9G11 1
 '@BASEBOARD_FAB2_LIB.BASEBOARD_FAB2(SCH_1):PAGE141_I76@MSTR_DISCRETE.RES(CHIPS)':
 'A': CDS_PINID='A';
NODE_NAME     C9G12 1
 '@BASEBOARD_FAB2_LIB.BASEBOARD_FAB2(SCH_1):PAGE141_I100@MSTR_DISCRETE.CAP(CHIPS)':
 'A': CDS_PINID='A';
NET_NAME
'NIC_SER_P_MDI_3_DP'
 '@BASEBOARD_FAB2_LIB.BASEBOARD_FAB2(SCH_1):NIC_SER_P_MDI_3_DP':
 C_SIGNAL='@baseboard_fab2_lib.baseboard_fab2(sch_1):nic_ser_p_mdi_3_dp';
NODE_NAME     EU9E1 50
 '@BASEBOARD_FAB2_LIB.BASEBOARD_FAB2(SCH_1):PAGE139_I72@MSTR_INTEL.SPRINGVILLE(CHIPS)':
 'MDI_PLUS3_SERP': CDS_PINID='MDI_PLUS3_SERP';
NODE_NAME     R9G9 1
 '@BASEBOARD_FAB2_LIB.BASEBOARD_FAB2(SCH_1):PAGE141_I75@MSTR_DISCRETE.RES(CHIPS)':
 'A': CDS_PINID='A';
NODE_NAME     C9G9 1
 '@BASEBOARD_FAB2_LIB.BASEBOARD_FAB2(SCH_1):PAGE141_I99@MSTR_DISCRETE.CAP(CHIPS)':
 'A': CDS_PINID='A';
NET_NAME
'NIC_SET_N_MDI_2_DN'
 '@BASEBOARD_FAB2_LIB.BASEBOARD_FAB2(SCH_1):NIC_SET_N_MDI_2_DN':
 C_SIGNAL='@baseboard_fab2_lib.baseboard_fab2(sch_1):nic_set_n_mdi_2_dn';
NODE_NAME     EU9E1 52
 '@BASEBOARD_FAB2_LIB.BASEBOARD_FAB2(SCH_1):PAGE139_I72@MSTR_INTEL.SPRINGVILLE(CHIPS)':
 'MDI_MINUS2_SETN': CDS_PINID='MDI_MINUS2_SETN';
NODE_NAME     R9G17 1
 '@BASEBOARD_FAB2_LIB.BASEBOARD_FAB2(SCH_1):PAGE141_I78@MSTR_DISCRETE.RES(CHIPS)':
 'A': CDS_PINID='A';
NODE_NAME     C9G13 1
 '@BASEBOARD_FAB2_LIB.BASEBOARD_FAB2(SCH_1):PAGE141_I102@MSTR_DISCRETE.CAP(CHIPS)':
 'A': CDS_PINID='A';
NET_NAME
'NIC_SET_P_MDI_2_DP'
 '@BASEBOARD_FAB2_LIB.BASEBOARD_FAB2(SCH_1):NIC_SET_P_MDI_2_DP':
 C_SIGNAL='@baseboard_fab2_lib.baseboard_fab2(sch_1):nic_set_p_mdi_2_dp';
NODE_NAME     EU9E1 53
 '@BASEBOARD_FAB2_LIB.BASEBOARD_FAB2(SCH_1):PAGE139_I72@MSTR_INTEL.SPRINGVILLE(CHIPS)':
 'MDI_PLUS2_SETP': CDS_PINID='MDI_PLUS2_SETP';
NODE_NAME     R9G18 1
 '@BASEBOARD_FAB2_LIB.BASEBOARD_FAB2(SCH_1):PAGE141_I77@MSTR_DISCRETE.RES(CHIPS)':
 'A': CDS_PINID='A';
NODE_NAME     C9G16 1
 '@BASEBOARD_FAB2_LIB.BASEBOARD_FAB2(SCH_1):PAGE141_I101@MSTR_DISCRETE.CAP(CHIPS)':
 'A': CDS_PINID='A';
NET_NAME
'P0V7_GTL2014_2'
 '@BASEBOARD_FAB2_LIB.BASEBOARD_FAB2(SCH_1):P0V7_GTL2014_2':
 C_SIGNAL='@baseboard_fab2_lib.baseboard_fab2(sch_1):p0v7_gtl2014_2';
NODE_NAME     U9G1 4
 '@BASEBOARD_FAB2_LIB.BASEBOARD_FAB2(SCH_1):PAGE152_I1@MSTR_DIGITAL.GTL2014(CHIPS)':
 'VREF': CDS_PINID='VREF';
NODE_NAME     R1U37 1
 '@BASEBOARD_FAB2_LIB.BASEBOARD_FAB2(SCH_1):PAGE152_I26@MSTR_DISCRETE.RES(CHIPS)':
 'A': CDS_PINID='A';
NODE_NAME     C1U22 1
 '@BASEBOARD_FAB2_LIB.BASEBOARD_FAB2(SCH_1):PAGE152_I27@DEV_DISCRETE.CAP_A(CHIPS)':
 'A': CDS_PINID='A';
NODE_NAME     R1W35 2
 '@BASEBOARD_FAB2_LIB.BASEBOARD_FAB2(SCH_1):PAGE152_I105@MSTR_DISCRETE.RES(CHIPS)':
 'B': CDS_PINID='B';
NODE_NAME     R1U43 2
 '@BASEBOARD_FAB2_LIB.BASEBOARD_FAB2(SCH_1):PAGE152_I106@W_HDL.374R2F-1-GP(CHIPS)':
 '2': CDS_PINID='\2\';
NET_NAME
'P0V7_GTL2014_VREF_6'
 '@BASEBOARD_FAB2_LIB.BASEBOARD_FAB2(SCH_1):P0V7_GTL2014_VREF_6':
 C_SIGNAL='@baseboard_fab2_lib.baseboard_fab2(sch_1):p0v7_gtl2014_vref_6';
NODE_NAME     C25W93 1
 '@BASEBOARD_FAB2_LIB.BASEBOARD_FAB2(SCH_1):PAGE268_I27@DEV_DISCRETE.CAP_A(CHIPS)':
 'A': CDS_PINID='A';
NODE_NAME     R25W165 1
 '@BASEBOARD_FAB2_LIB.BASEBOARD_FAB2(SCH_1):PAGE268_I28@MSTR_DISCRETE.RES(CHIPS)':
 'A': CDS_PINID='A';
NODE_NAME     R25W164 2
 '@BASEBOARD_FAB2_LIB.BASEBOARD_FAB2(SCH_1):PAGE268_I29@MSTR_DISCRETE.RES(CHIPS)':
 'B': CDS_PINID='B';
NODE_NAME     U25W11 4
 '@BASEBOARD_FAB2_LIB.BASEBOARD_FAB2(SCH_1):PAGE268_I33@MSTR_DIGITAL.GTL2014(CHIPS)':
 'VREF': CDS_PINID='VREF';
NODE_NAME     R25W183 2
 '@BASEBOARD_FAB2_LIB.BASEBOARD_FAB2(SCH_1):PAGE268_I36@W_HDL.374R2F-1-GP(CHIPS)':
 '2': CDS_PINID='\2\';
NET_NAME
'P0V7_GTL2104_5_VREF'
 '@BASEBOARD_FAB2_LIB.BASEBOARD_FAB2(SCH_1):P0V7_GTL2104_5_VREF':
 C_SIGNAL='@baseboard_fab2_lib.baseboard_fab2(sch_1):p0v7_gtl2104_5_vref';
NODE_NAME     U2T4 4
 '@BASEBOARD_FAB2_LIB.BASEBOARD_FAB2(SCH_1):PAGE93_I30@MSTR_DIGITAL.GTL2014(CHIPS)':
 'VREF': CDS_PINID='VREF';
NODE_NAME     C2T32 1
 '@BASEBOARD_FAB2_LIB.BASEBOARD_FAB2(SCH_1):PAGE93_I95@DEV_DISCRETE.CAP_A(CHIPS)':
 'A': CDS_PINID='A';
NODE_NAME     R2T39 1
 '@BASEBOARD_FAB2_LIB.BASEBOARD_FAB2(SCH_1):PAGE93_I98@MSTR_DISCRETE.RES(CHIPS)':
 'A': CDS_PINID='A';
NODE_NAME     R2W2 2
 '@BASEBOARD_FAB2_LIB.BASEBOARD_FAB2(SCH_1):PAGE93_I147@MSTR_DISCRETE.RES(CHIPS)':
 'B': CDS_PINID='B';
NODE_NAME     R2T36 2
 '@BASEBOARD_FAB2_LIB.BASEBOARD_FAB2(SCH_1):PAGE93_I148@W_HDL.374R2F-1-GP(CHIPS)':
 '2': CDS_PINID='\2\';
NET_NAME
'P0V7_GTL2104_VREF_0'
 '@BASEBOARD_FAB2_LIB.BASEBOARD_FAB2(SCH_1):P0V7_GTL2104_VREF_0':
 C_SIGNAL='@baseboard_fab2_lib.baseboard_fab2(sch_1):p0v7_gtl2104_vref_0';
NODE_NAME     U7D2 4
 '@BASEBOARD_FAB2_LIB.BASEBOARD_FAB2(SCH_1):PAGE92_I32@MSTR_DIGITAL.GTL2014(CHIPS)':
 'VREF': CDS_PINID='VREF';
NODE_NAME     R7D32 1
 '@BASEBOARD_FAB2_LIB.BASEBOARD_FAB2(SCH_1):PAGE92_I48@MSTR_DISCRETE.RES(CHIPS)':
 'A': CDS_PINID='A';
NODE_NAME     C7D5 1
 '@BASEBOARD_FAB2_LIB.BASEBOARD_FAB2(SCH_1):PAGE92_I52@DEV_DISCRETE.CAP_A(CHIPS)':
 'A': CDS_PINID='A';
NODE_NAME     R7W4 2
 '@BASEBOARD_FAB2_LIB.BASEBOARD_FAB2(SCH_1):PAGE92_I106@MSTR_DISCRETE.RES(CHIPS)':
 'B': CDS_PINID='B';
NODE_NAME     R7D33 2
 '@BASEBOARD_FAB2_LIB.BASEBOARD_FAB2(SCH_1):PAGE92_I111@W_HDL.374R2F-1-GP(CHIPS)':
 '2': CDS_PINID='\2\';
NET_NAME
'P0V7_GTL2104_VREF_1'
 '@BASEBOARD_FAB2_LIB.BASEBOARD_FAB2(SCH_1):P0V7_GTL2104_VREF_1':
 C_SIGNAL='@baseboard_fab2_lib.baseboard_fab2(sch_1):p0v7_gtl2104_vref_1';
NODE_NAME     U3P2 4
 '@BASEBOARD_FAB2_LIB.BASEBOARD_FAB2(SCH_1):PAGE92_I1@MSTR_DIGITAL.GTL2014(CHIPS)':
 'VREF': CDS_PINID='VREF';
NODE_NAME     C3P49 1
 '@BASEBOARD_FAB2_LIB.BASEBOARD_FAB2(SCH_1):PAGE92_I37@DEV_DISCRETE.CAP_A(CHIPS)':
 'A': CDS_PINID='A';
NODE_NAME     R3P49 1
 '@BASEBOARD_FAB2_LIB.BASEBOARD_FAB2(SCH_1):PAGE92_I38@MSTR_DISCRETE.RES(CHIPS)':
 'A': CDS_PINID='A';
NODE_NAME     R3W10 2
 '@BASEBOARD_FAB2_LIB.BASEBOARD_FAB2(SCH_1):PAGE92_I108@MSTR_DISCRETE.RES(CHIPS)':
 'B': CDS_PINID='B';
NODE_NAME     R3P45 2
 '@BASEBOARD_FAB2_LIB.BASEBOARD_FAB2(SCH_1):PAGE92_I110@W_HDL.374R2F-1-GP(CHIPS)':
 '2': CDS_PINID='\2\';
NET_NAME
'P0V9_LAN'
 '@BASEBOARD_FAB2_LIB.BASEBOARD_FAB2(SCH_1):P0V9_LAN':
 C_SIGNAL='@baseboard_fab2_lib.baseboard_fab2(sch_1):p0v9_lan';
NODE_NAME     EU9E1 59
 '@BASEBOARD_FAB2_LIB.BASEBOARD_FAB2(SCH_1):PAGE139_I72@MSTR_INTEL.SPRINGVILLE(CHIPS)':
 'VDD0P9'<0>: CDS_PINID='VDD0P9(0)';
NODE_NAME     EU9E1 32
 '@BASEBOARD_FAB2_LIB.BASEBOARD_FAB2(SCH_1):PAGE139_I72@MSTR_INTEL.SPRINGVILLE(CHIPS)':
 'VDD0P9'<1>: CDS_PINID='VDD0P9(1)';
NODE_NAME     EU9E1 11
 '@BASEBOARD_FAB2_LIB.BASEBOARD_FAB2(SCH_1):PAGE139_I72@MSTR_INTEL.SPRINGVILLE(CHIPS)':
 'VDD0P9'<2>: CDS_PINID='VDD0P9(2)';
NODE_NAME     EU9E1 42
 '@BASEBOARD_FAB2_LIB.BASEBOARD_FAB2(SCH_1):PAGE139_I72@MSTR_INTEL.SPRINGVILLE(CHIPS)':
 'VDD0P9'<3>: CDS_PINID='VDD0P9(3)';
NODE_NAME     C1T4 1
 '@BASEBOARD_FAB2_LIB.BASEBOARD_FAB2(SCH_1):PAGE139_I134@MSTR_DISCRETE.CAP(CHIPS)':
 'A': CDS_PINID='A';
NODE_NAME     C1R18 1
 '@BASEBOARD_FAB2_LIB.BASEBOARD_FAB2(SCH_1):PAGE139_I157@DEV_DISCRETE.CAP_A(CHIPS)':
 'A': CDS_PINID='A';
NODE_NAME     C1T5 1
 '@BASEBOARD_FAB2_LIB.BASEBOARD_FAB2(SCH_1):PAGE139_I158@DEV_DISCRETE.CAP_A(CHIPS)':
 'A': CDS_PINID='A';
NODE_NAME     C1R24 1
 '@BASEBOARD_FAB2_LIB.BASEBOARD_FAB2(SCH_1):PAGE139_I159@DEV_DISCRETE.CAP_A(CHIPS)':
 'A': CDS_PINID='A';
NODE_NAME     C1R15 1
 '@BASEBOARD_FAB2_LIB.BASEBOARD_FAB2(SCH_1):PAGE139_I160@DEV_DISCRETE.CAP_A(CHIPS)':
 'A': CDS_PINID='A';
NODE_NAME     C1R16 1
 '@BASEBOARD_FAB2_LIB.BASEBOARD_FAB2(SCH_1):PAGE139_I161@MSTR_DISCRETE.CAP(CHIPS)':
 'A': CDS_PINID='A';
NODE_NAME     C9E1 1
 '@BASEBOARD_FAB2_LIB.BASEBOARD_FAB2(SCH_1):PAGE139_I163@DEV_DISCRETE.CAP_A(CHIPS)':
 'A': CDS_PINID='A';
NODE_NAME     R1R15 1
 '@BASEBOARD_FAB2_LIB.BASEBOARD_FAB2(SCH_1):PAGE139_I237@MSTR_DISCRETE.RES(CHIPS)':
 'A': CDS_PINID='A';
NODE_NAME     C9E12 1
 '@BASEBOARD_FAB2_LIB.BASEBOARD_FAB2(SCH_1):PAGE139_I241@DEV_DISCRETE.CAP_A(CHIPS)':
 'A': CDS_PINID='A';
NET_NAME
'P0V9_LAN_I210'
 '@BASEBOARD_FAB2_LIB.BASEBOARD_FAB2(SCH_1):P0V9_LAN_I210':
 C_SIGNAL='@baseboard_fab2_lib.baseboard_fab2(sch_1):p0v9_lan_i210';
NODE_NAME     EU9E1 38
 '@BASEBOARD_FAB2_LIB.BASEBOARD_FAB2(SCH_1):PAGE139_I72@MSTR_INTEL.SPRINGVILLE(CHIPS)':
 'VDD0P9_OUT': CDS_PINID='VDD0P9_OUT';
NODE_NAME     R1R15 2
 '@BASEBOARD_FAB2_LIB.BASEBOARD_FAB2(SCH_1):PAGE139_I237@MSTR_DISCRETE.RES(CHIPS)':
 'B': CDS_PINID='B';
NET_NAME
'P12V'
 '@BASEBOARD_FAB2_LIB.BASEBOARD_FAB2(SCH_1):P12V':
 C_SIGNAL='@baseboard_fab2_lib.baseboard_fab2(sch_1):p12v';
NODE_NAME     C2U20 1
 '@BASEBOARD_FAB2_LIB.BASEBOARD_FAB2(SCH_1):PAGE108_I1@DEV_DISCRETE.CAP_A(CHIPS)':
 'A': CDS_PINID='A';
NODE_NAME     C2U24 1
 '@BASEBOARD_FAB2_LIB.BASEBOARD_FAB2(SCH_1):PAGE108_I2@DEV_DISCRETE.CAP_A(CHIPS)':
 'A': CDS_PINID='A';
NODE_NAME     J8G1 1
 '@BASEBOARD_FAB2_LIB.BASEBOARD_FAB2(SCH_1):PAGE108_I258@MSTR_SCONN.SCONN200_H68296001(CHIPS)':
 'IO1': CDS_PINID='IO1';
NODE_NAME     J8G1 2
 '@BASEBOARD_FAB2_LIB.BASEBOARD_FAB2(SCH_1):PAGE108_I258@MSTR_SCONN.SCONN200_H68296001(CHIPS)':
 'IO2': CDS_PINID='IO2';
NODE_NAME     J8G1 3
 '@BASEBOARD_FAB2_LIB.BASEBOARD_FAB2(SCH_1):PAGE108_I258@MSTR_SCONN.SCONN200_H68296001(CHIPS)':
 'IO3': CDS_PINID='IO3';
NODE_NAME     J8G1 4
 '@BASEBOARD_FAB2_LIB.BASEBOARD_FAB2(SCH_1):PAGE108_I258@MSTR_SCONN.SCONN200_H68296001(CHIPS)':
 'IO4': CDS_PINID='IO4';
NODE_NAME     J8G1 5
 '@BASEBOARD_FAB2_LIB.BASEBOARD_FAB2(SCH_1):PAGE108_I258@MSTR_SCONN.SCONN200_H68296001(CHIPS)':
 'IO5': CDS_PINID='IO5';
NODE_NAME     J8G1 6
 '@BASEBOARD_FAB2_LIB.BASEBOARD_FAB2(SCH_1):PAGE108_I258@MSTR_SCONN.SCONN200_H68296001(CHIPS)':
 'IO6': CDS_PINID='IO6';
NODE_NAME     J8G1 7
 '@BASEBOARD_FAB2_LIB.BASEBOARD_FAB2(SCH_1):PAGE108_I258@MSTR_SCONN.SCONN200_H68296001(CHIPS)':
 'IO7': CDS_PINID='IO7';
NODE_NAME     J8G1 8
 '@BASEBOARD_FAB2_LIB.BASEBOARD_FAB2(SCH_1):PAGE108_I258@MSTR_SCONN.SCONN200_H68296001(CHIPS)':
 'IO8': CDS_PINID='IO8';
NODE_NAME     J8G1 9
 '@BASEBOARD_FAB2_LIB.BASEBOARD_FAB2(SCH_1):PAGE108_I258@MSTR_SCONN.SCONN200_H68296001(CHIPS)':
 'IO9': CDS_PINID='IO9';
NODE_NAME     J8G1 10
 '@BASEBOARD_FAB2_LIB.BASEBOARD_FAB2(SCH_1):PAGE108_I258@MSTR_SCONN.SCONN200_H68296001(CHIPS)':
 'IO10': CDS_PINID='IO10';
NODE_NAME     J8G1 11
 '@BASEBOARD_FAB2_LIB.BASEBOARD_FAB2(SCH_1):PAGE108_I258@MSTR_SCONN.SCONN200_H68296001(CHIPS)':
 'IO11': CDS_PINID='IO11';
NODE_NAME     J8G1 12
 '@BASEBOARD_FAB2_LIB.BASEBOARD_FAB2(SCH_1):PAGE108_I258@MSTR_SCONN.SCONN200_H68296001(CHIPS)':
 'IO12': CDS_PINID='IO12';
NODE_NAME     R8D38 1
 '@BASEBOARD_FAB2_LIB.BASEBOARD_FAB2(SCH_1):PAGE196_I112@MSTR_DISCRETE.RES(CHIPS)':
 'A': CDS_PINID='A';
NODE_NAME     EU7E1 6
 '@BASEBOARD_FAB2_LIB.BASEBOARD_FAB2(SCH_1):PAGE198_I19@MSTR_VREG.SLG55021(CHIPS)':
 'S': CDS_PINID='S';
NODE_NAME     C7E9 1
 '@BASEBOARD_FAB2_LIB.BASEBOARD_FAB2(SCH_1):PAGE198_I49@DEV_DISCRETE.CAP_A(CHIPS)':
 'A': CDS_PINID='A';
NODE_NAME     C7E8 1
 '@BASEBOARD_FAB2_LIB.BASEBOARD_FAB2(SCH_1):PAGE198_I50@MSTR_DISCRETE.CAP(CHIPS)':
 'A': CDS_PINID='A';
NODE_NAME     Q7E7 1
 '@BASEBOARD_FAB2_LIB.BASEBOARD_FAB2(SCH_1):PAGE198_I88@MSTR_DISCRETE.MOSFET_N(CHIPS)':
 'SRC': CDS_PINID='SRC';
NODE_NAME     F9B1 1
 '@BASEBOARD_FAB2_LIB.BASEBOARD_FAB2(SCH_1):PAGE172_I66@MSTR_DISCRETE.FUSE(CHIPS)':
 'A'<0>: CDS_PINID='A(0)';
NET_NAME
'P12V_FAN'
 '@BASEBOARD_FAB2_LIB.BASEBOARD_FAB2(SCH_1):P12V_FAN':
 C_SIGNAL='@baseboard_fab2_lib.baseboard_fab2(sch_1):p12v_fan';
NODE_NAME     C1E21 1
 '@BASEBOARD_FAB2_LIB.BASEBOARD_FAB2(SCH_1):PAGE161_I3@MSTR_DISCRETE.CAP(CHIPS)':
 'A': CDS_PINID='A';
NODE_NAME     C1E20 1
 '@BASEBOARD_FAB2_LIB.BASEBOARD_FAB2(SCH_1):PAGE161_I4@DEV_DISCRETE.CAP_A(CHIPS)':
 'A': CDS_PINID='A';
NODE_NAME     C9M5 1
 '@BASEBOARD_FAB2_LIB.BASEBOARD_FAB2(SCH_1):PAGE161_I26@DEV_DISCRETE.CAP_A(CHIPS)':
 'A': CDS_PINID='A';
NODE_NAME     C9M4 1
 '@BASEBOARD_FAB2_LIB.BASEBOARD_FAB2(SCH_1):PAGE161_I27@MSTR_DISCRETE.CAP(CHIPS)':
 'A': CDS_PINID='A';
NODE_NAME     C1B18 1
 '@BASEBOARD_FAB2_LIB.BASEBOARD_FAB2(SCH_1):PAGE198_I61@MSTR_DISCRETE.CAP(CHIPS)':
 'A': CDS_PINID='A';
NODE_NAME     C1B19 1
 '@BASEBOARD_FAB2_LIB.BASEBOARD_FAB2(SCH_1):PAGE198_I64@DEV_DISCRETE.CAP_A(CHIPS)':
 'A': CDS_PINID='A';
NODE_NAME     EU9M1 6
 '@BASEBOARD_FAB2_LIB.BASEBOARD_FAB2(SCH_1):PAGE198_I69@MSTR_VREG.SLG55021(CHIPS)':
 'S': CDS_PINID='S';
NODE_NAME     Q1B1 1
 '@BASEBOARD_FAB2_LIB.BASEBOARD_FAB2(SCH_1):PAGE198_I86@MSTR_DISCRETE.MOSFET_N(CHIPS)':
 'SRC': CDS_PINID='SRC';
NODE_NAME     R10W5 1
 '@BASEBOARD_FAB2_LIB.BASEBOARD_FAB2(SCH_1):PAGE251_I5@MSTR_DISCRETE.RES(CHIPS)':
 'A': CDS_PINID='A';
NODE_NAME     J1F2 2
 '@BASEBOARD_FAB2_LIB.BASEBOARD_FAB2(SCH_1):PAGE161_I139@W_HDL.LOTES-CON4-S1-GP(CHIPS)':
 '2': CDS_PINID='\2\';
NODE_NAME     J10W1 2
 '@BASEBOARD_FAB2_LIB.BASEBOARD_FAB2(SCH_1):PAGE161_I140@W_HDL.LOTES-CON4-S1-GP(CHIPS)':
 '2': CDS_PINID='\2\';
NET_NAME
'P12V_FAN_SWITCH_G'
 '@BASEBOARD_FAB2_LIB.BASEBOARD_FAB2(SCH_1):P12V_FAN_SWITCH_G':
 C_SIGNAL='@baseboard_fab2_lib.baseboard_fab2(sch_1):p12v_fan_switch_g';
NODE_NAME     EU9M1 7
 '@BASEBOARD_FAB2_LIB.BASEBOARD_FAB2(SCH_1):PAGE198_I69@MSTR_VREG.SLG55021(CHIPS)':
 'G': CDS_PINID='G';
NODE_NAME     Q1B1 4
 '@BASEBOARD_FAB2_LIB.BASEBOARD_FAB2(SCH_1):PAGE198_I86@MSTR_DISCRETE.MOSFET_N(CHIPS)':
 'GATE': CDS_PINID='GATE';
NET_NAME
'P12V_HDD_SATA'
 '@BASEBOARD_FAB2_LIB.BASEBOARD_FAB2(SCH_1):P12V_HDD_SATA':
 C_SIGNAL='@baseboard_fab2_lib.baseboard_fab2(sch_1):p12v_hdd_sata';
NODE_NAME     C9B2 1
 '@BASEBOARD_FAB2_LIB.BASEBOARD_FAB2(SCH_1):PAGE172_I36@MSTR_DISCRETE.CAP(CHIPS)':
 'A': CDS_PINID='A';
NODE_NAME     F9B1 2
 '@BASEBOARD_FAB2_LIB.BASEBOARD_FAB2(SCH_1):PAGE172_I66@MSTR_DISCRETE.FUSE(CHIPS)':
 'B'<0>: CDS_PINID='B(0)';
NODE_NAME     J2W1 P5
 '@BASEBOARD_FAB2_LIB.BASEBOARD_FAB2(SCH_1):PAGE172_I67@W_HDL.SKT-SATA7P-6P-165-GP-U1(CHIPS)':
 'P5': CDS_PINID='P5';
NODE_NAME     J2W1 P6
 '@BASEBOARD_FAB2_LIB.BASEBOARD_FAB2(SCH_1):PAGE172_I67@W_HDL.SKT-SATA7P-6P-165-GP-U1(CHIPS)':
 'P6': CDS_PINID='P6';
NODE_NAME     J2W2 P5
 '@BASEBOARD_FAB2_LIB.BASEBOARD_FAB2(SCH_1):PAGE172_I68@W_HDL.SKT-SATA7P-6P-165-GP-U1(CHIPS)':
 'P5': CDS_PINID='P5';
NODE_NAME     J2W2 P6
 '@BASEBOARD_FAB2_LIB.BASEBOARD_FAB2(SCH_1):PAGE172_I68@W_HDL.SKT-SATA7P-6P-165-GP-U1(CHIPS)':
 'P6': CDS_PINID='P6';
NET_NAME
'P12V_HSC_SENN0'
 '@BASEBOARD_FAB2_LIB.BASEBOARD_FAB2(SCH_1):P12V_HSC_SENN0':
 C_SIGNAL='@baseboard_fab2_lib.baseboard_fab2(sch_1):p12v_hsc_senn0';
NODE_NAME     R1D49 4
 '@BASEBOARD_FAB2_LIB.BASEBOARD_FAB2(SCH_1):PAGE200_I50@MSTR_DISCRETE.RES_PWR(CHIPS)':
 '4': CDS_PINID='\4\';
NODE_NAME     R1D47 1
 '@BASEBOARD_FAB2_LIB.BASEBOARD_FAB2(SCH_1):PAGE200_I52@MSTR_DISCRETE.RES(CHIPS)':
 'A': CDS_PINID='A';
NET_NAME
'P12V_HSC_SENN1'
 '@BASEBOARD_FAB2_LIB.BASEBOARD_FAB2(SCH_1):P12V_HSC_SENN1':
 C_SIGNAL='@baseboard_fab2_lib.baseboard_fab2(sch_1):p12v_hsc_senn1';
NODE_NAME     R9R1 4
 '@BASEBOARD_FAB2_LIB.BASEBOARD_FAB2(SCH_1):PAGE200_I49@MSTR_DISCRETE.RES_PWR(CHIPS)':
 '4': CDS_PINID='\4\';
NODE_NAME     R9P26 1
 '@BASEBOARD_FAB2_LIB.BASEBOARD_FAB2(SCH_1):PAGE200_I51@MSTR_DISCRETE.RES(CHIPS)':
 'A': CDS_PINID='A';
NET_NAME
'P12V_HSC_SENP0'
 '@BASEBOARD_FAB2_LIB.BASEBOARD_FAB2(SCH_1):P12V_HSC_SENP0':
 C_SIGNAL='@baseboard_fab2_lib.baseboard_fab2(sch_1):p12v_hsc_senp0';
NODE_NAME     R1D46 1
 '@BASEBOARD_FAB2_LIB.BASEBOARD_FAB2(SCH_1):PAGE200_I48@MSTR_DISCRETE.RES(CHIPS)':
 'A': CDS_PINID='A';
NODE_NAME     R1D49 3
 '@BASEBOARD_FAB2_LIB.BASEBOARD_FAB2(SCH_1):PAGE200_I50@MSTR_DISCRETE.RES_PWR(CHIPS)':
 '3': CDS_PINID='\3\';
NET_NAME
'P12V_HSC_SENP1'
 '@BASEBOARD_FAB2_LIB.BASEBOARD_FAB2(SCH_1):P12V_HSC_SENP1':
 C_SIGNAL='@baseboard_fab2_lib.baseboard_fab2(sch_1):p12v_hsc_senp1';
NODE_NAME     R9P27 1
 '@BASEBOARD_FAB2_LIB.BASEBOARD_FAB2(SCH_1):PAGE200_I47@MSTR_DISCRETE.RES(CHIPS)':
 'A': CDS_PINID='A';
NODE_NAME     R9R1 3
 '@BASEBOARD_FAB2_LIB.BASEBOARD_FAB2(SCH_1):PAGE200_I49@MSTR_DISCRETE.RES_PWR(CHIPS)':
 '3': CDS_PINID='\3\';
NET_NAME
'P12V_HSC_VCC'
 '@BASEBOARD_FAB2_LIB.BASEBOARD_FAB2(SCH_1):P12V_HSC_VCC':
 C_SIGNAL='@baseboard_fab2_lib.baseboard_fab2(sch_1):p12v_hsc_vcc';
NODE_NAME     R9P30 2
 '@BASEBOARD_FAB2_LIB.BASEBOARD_FAB2(SCH_1):PAGE199_I2@MSTR_DISCRETE.RES(CHIPS)':
 'B': CDS_PINID='B';
NODE_NAME     C1D25 1
 '@BASEBOARD_FAB2_LIB.BASEBOARD_FAB2(SCH_1):PAGE199_I3@MSTR_DISCRETE.CAP(CHIPS)':
 'A': CDS_PINID='A';
NODE_NAME     EU1D2 30
 '@BASEBOARD_FAB2_LIB.BASEBOARD_FAB2(SCH_1):PAGE199_I10@MSTR_CONTROLLER.ADM1278(CHIPS)':
 'VCC': CDS_PINID='VCC';
NET_NAME
'P12V_MB0_SW'
 '@BASEBOARD_FAB2_LIB.BASEBOARD_FAB2(SCH_1):P12V_MB0_SW':
 C_SIGNAL='@baseboard_fab2_lib.baseboard_fab2(sch_1):p12v_mb0_sw';
NODE_NAME     R9R1 2
 '@BASEBOARD_FAB2_LIB.BASEBOARD_FAB2(SCH_1):PAGE200_I49@MSTR_DISCRETE.RES_PWR(CHIPS)':
 '2': CDS_PINID='\2\';
NODE_NAME     R9R1 6
 '@BASEBOARD_FAB2_LIB.BASEBOARD_FAB2(SCH_1):PAGE200_I49@MSTR_DISCRETE.RES_PWR(CHIPS)':
 '6': CDS_PINID='\6\';
NODE_NAME     R1D49 2
 '@BASEBOARD_FAB2_LIB.BASEBOARD_FAB2(SCH_1):PAGE200_I50@MSTR_DISCRETE.RES_PWR(CHIPS)':
 '2': CDS_PINID='\2\';
NODE_NAME     R1D49 6
 '@BASEBOARD_FAB2_LIB.BASEBOARD_FAB2(SCH_1):PAGE200_I50@MSTR_DISCRETE.RES_PWR(CHIPS)':
 '6': CDS_PINID='\6\';
NODE_NAME     EU1E3 5
 '@BASEBOARD_FAB2_LIB.BASEBOARD_FAB2(SCH_1):PAGE200_I54@MSTR_DISCRETE.MOSFETN_1D3S(CHIPS)':
 'D': CDS_PINID='D';
NODE_NAME     EU9R1 5
 '@BASEBOARD_FAB2_LIB.BASEBOARD_FAB2(SCH_1):PAGE200_I57@MSTR_DISCRETE.MOSFETN_1D3S(CHIPS)':
 'D': CDS_PINID='D';
NODE_NAME     EU1E1 5
 '@BASEBOARD_FAB2_LIB.BASEBOARD_FAB2(SCH_1):PAGE200_I59@MSTR_DISCRETE.MOSFETN_1D3S(CHIPS)':
 'D': CDS_PINID='D';
NET_NAME
'P12V_NVDIMM_ABC'
 '@BASEBOARD_FAB2_LIB.BASEBOARD_FAB2(SCH_1):P12V_NVDIMM_ABC':
 C_SIGNAL='@baseboard_fab2_lib.baseboard_fab2(sch_1):p12v_nvdimm_abc';
NODE_NAME     J4G1 145
 '@BASEBOARD_FAB2_LIB.BASEBOARD_FAB2(SCH_1):PAGE43_I260@MSTR_SCONN.SCONN288_H44441004(CHIPS)':
 '12V'<0>: CDS_PINID='\12v\(0)';
NODE_NAME     J4G1 1
 '@BASEBOARD_FAB2_LIB.BASEBOARD_FAB2(SCH_1):PAGE43_I260@MSTR_SCONN.SCONN288_H44441004(CHIPS)':
 '12V'<1>: CDS_PINID='\12v\(1)';
NODE_NAME     J6T1 145
 '@BASEBOARD_FAB2_LIB.BASEBOARD_FAB2(SCH_1):PAGE44_I75@MSTR_SCONN.SCONN288_H44441003(CHIPS)':
 '12V'<0>: CDS_PINID='\12v\(0)';
NODE_NAME     J6T1 1
 '@BASEBOARD_FAB2_LIB.BASEBOARD_FAB2(SCH_1):PAGE44_I75@MSTR_SCONN.SCONN288_H44441003(CHIPS)':
 '12V'<1>: CDS_PINID='\12v\(1)';
NODE_NAME     J4G2 145
 '@BASEBOARD_FAB2_LIB.BASEBOARD_FAB2(SCH_1):PAGE45_I169@MSTR_SCONN.SCONN288_H44441004(CHIPS)':
 '12V'<0>: CDS_PINID='\12v\(0)';
NODE_NAME     J4G2 1
 '@BASEBOARD_FAB2_LIB.BASEBOARD_FAB2(SCH_1):PAGE45_I169@MSTR_SCONN.SCONN288_H44441004(CHIPS)':
 '12V'<1>: CDS_PINID='\12v\(1)';
NODE_NAME     J6U1 145
 '@BASEBOARD_FAB2_LIB.BASEBOARD_FAB2(SCH_1):PAGE46_I67@MSTR_SCONN.SCONN288_H44441003(CHIPS)':
 '12V'<0>: CDS_PINID='\12v\(0)';
NODE_NAME     J6U1 1
 '@BASEBOARD_FAB2_LIB.BASEBOARD_FAB2(SCH_1):PAGE46_I67@MSTR_SCONN.SCONN288_H44441003(CHIPS)':
 '12V'<1>: CDS_PINID='\12v\(1)';
NODE_NAME     J4G3 145
 '@BASEBOARD_FAB2_LIB.BASEBOARD_FAB2(SCH_1):PAGE47_I179@MSTR_SCONN.SCONN288_H44441004(CHIPS)':
 '12V'<0>: CDS_PINID='\12v\(0)';
NODE_NAME     J4G3 1
 '@BASEBOARD_FAB2_LIB.BASEBOARD_FAB2(SCH_1):PAGE47_I179@MSTR_SCONN.SCONN288_H44441004(CHIPS)':
 '12V'<1>: CDS_PINID='\12v\(1)';
NODE_NAME     J6U2 145
 '@BASEBOARD_FAB2_LIB.BASEBOARD_FAB2(SCH_1):PAGE48_I171@MSTR_SCONN.SCONN288_H44441003(CHIPS)':
 '12V'<0>: CDS_PINID='\12v\(0)';
NODE_NAME     J6U2 1
 '@BASEBOARD_FAB2_LIB.BASEBOARD_FAB2(SCH_1):PAGE48_I171@MSTR_SCONN.SCONN288_H44441003(CHIPS)':
 '12V'<1>: CDS_PINID='\12v\(1)';
NODE_NAME     R4F2 2
 '@BASEBOARD_FAB2_LIB.BASEBOARD_FAB2(SCH_1):PAGE197_I14@MSTR_DISCRETE.RES(CHIPS)':
 'B': CDS_PINID='B';
NODE_NAME     Q12W1 2
 '@BASEBOARD_FAB2_LIB.BASEBOARD_FAB2(SCH_1):PAGE197_I43@W_HDL.BSL308C-H6327-GP(CHIPS)':
 'SOURCE#2': CDS_PINID='\source#2\';
NODE_NAME     R12W4 1
 '@BASEBOARD_FAB2_LIB.BASEBOARD_FAB2(SCH_1):PAGE197_I45@MSTR_DISCRETE.RES(CHIPS)':
 'A': CDS_PINID='A';
NODE_NAME     C6U18 1
 '@BASEBOARD_FAB2_LIB.BASEBOARD_FAB2(SCH_1):PAGE197_I69@MSTR_DISCRETE.CAP(CHIPS)':
 'A': CDS_PINID='A';
NODE_NAME     C6T2 1
 '@BASEBOARD_FAB2_LIB.BASEBOARD_FAB2(SCH_1):PAGE197_I71@MSTR_DISCRETE.CAP(CHIPS)':
 'A': CDS_PINID='A';
NODE_NAME     C6U10 1
 '@BASEBOARD_FAB2_LIB.BASEBOARD_FAB2(SCH_1):PAGE197_I84@MSTR_DISCRETE.CAP(CHIPS)':
 'A': CDS_PINID='A';
NET_NAME
'P12V_NVDIMM_ABC_D'
 '@BASEBOARD_FAB2_LIB.BASEBOARD_FAB2(SCH_1):P12V_NVDIMM_ABC_D':
 C_SIGNAL='@baseboard_fab2_lib.baseboard_fab2(sch_1):p12v_nvdimm_abc_d';
NODE_NAME     Q12W1 4
 '@BASEBOARD_FAB2_LIB.BASEBOARD_FAB2(SCH_1):PAGE197_I43@W_HDL.BSL308C-H6327-GP(CHIPS)':
 'DRAIN#4': CDS_PINID='\drain#4\';
NODE_NAME     R12W3 2
 '@BASEBOARD_FAB2_LIB.BASEBOARD_FAB2(SCH_1):PAGE197_I115@W_HDL.4D02R2F-GP(CHIPS)':
 '2': CDS_PINID='\2\';
NODE_NAME     R12W2 1
 '@BASEBOARD_FAB2_LIB.BASEBOARD_FAB2(SCH_1):PAGE197_I117@W_HDL.665KR5B-1-GP(CHIPS)':
 '1': CDS_PINID='\1\';
NET_NAME
'P12V_NVDIMM_DEF'
 '@BASEBOARD_FAB2_LIB.BASEBOARD_FAB2(SCH_1):P12V_NVDIMM_DEF':
 C_SIGNAL='@baseboard_fab2_lib.baseboard_fab2(sch_1):p12v_nvdimm_def';
NODE_NAME     J4B1 145
 '@BASEBOARD_FAB2_LIB.BASEBOARD_FAB2(SCH_1):PAGE49_I169@MSTR_SCONN.SCONN288_H44441004(CHIPS)':
 '12V'<0>: CDS_PINID='\12v\(0)';
NODE_NAME     J4B1 1
 '@BASEBOARD_FAB2_LIB.BASEBOARD_FAB2(SCH_1):PAGE49_I169@MSTR_SCONN.SCONN288_H44441004(CHIPS)':
 '12V'<1>: CDS_PINID='\12v\(1)';
NODE_NAME     J6M1 145
 '@BASEBOARD_FAB2_LIB.BASEBOARD_FAB2(SCH_1):PAGE50_I50@MSTR_SCONN.SCONN288_H44441003(CHIPS)':
 '12V'<0>: CDS_PINID='\12v\(0)';
NODE_NAME     J6M1 1
 '@BASEBOARD_FAB2_LIB.BASEBOARD_FAB2(SCH_1):PAGE50_I50@MSTR_SCONN.SCONN288_H44441003(CHIPS)':
 '12V'<1>: CDS_PINID='\12v\(1)';
NODE_NAME     J4A2 145
 '@BASEBOARD_FAB2_LIB.BASEBOARD_FAB2(SCH_1):PAGE51_I167@MSTR_SCONN.SCONN288_H44441004(CHIPS)':
 '12V'<0>: CDS_PINID='\12v\(0)';
NODE_NAME     J4A2 1
 '@BASEBOARD_FAB2_LIB.BASEBOARD_FAB2(SCH_1):PAGE51_I167@MSTR_SCONN.SCONN288_H44441004(CHIPS)':
 '12V'<1>: CDS_PINID='\12v\(1)';
NODE_NAME     J6L2 145
 '@BASEBOARD_FAB2_LIB.BASEBOARD_FAB2(SCH_1):PAGE52_I55@MSTR_SCONN.SCONN288_H44441003(CHIPS)':
 '12V'<0>: CDS_PINID='\12v\(0)';
NODE_NAME     J6L2 1
 '@BASEBOARD_FAB2_LIB.BASEBOARD_FAB2(SCH_1):PAGE52_I55@MSTR_SCONN.SCONN288_H44441003(CHIPS)':
 '12V'<1>: CDS_PINID='\12v\(1)';
NODE_NAME     J4A1 145
 '@BASEBOARD_FAB2_LIB.BASEBOARD_FAB2(SCH_1):PAGE53_I171@MSTR_SCONN.SCONN288_H44441004(CHIPS)':
 '12V'<0>: CDS_PINID='\12v\(0)';
NODE_NAME     J4A1 1
 '@BASEBOARD_FAB2_LIB.BASEBOARD_FAB2(SCH_1):PAGE53_I171@MSTR_SCONN.SCONN288_H44441004(CHIPS)':
 '12V'<1>: CDS_PINID='\12v\(1)';
NODE_NAME     J6L1 145
 '@BASEBOARD_FAB2_LIB.BASEBOARD_FAB2(SCH_1):PAGE54_I170@MSTR_SCONN.SCONN288_H44441003(CHIPS)':
 '12V'<0>: CDS_PINID='\12v\(0)';
NODE_NAME     J6L1 1
 '@BASEBOARD_FAB2_LIB.BASEBOARD_FAB2(SCH_1):PAGE54_I170@MSTR_SCONN.SCONN288_H44441003(CHIPS)':
 '12V'<1>: CDS_PINID='\12v\(1)';
NODE_NAME     R4B12 2
 '@BASEBOARD_FAB2_LIB.BASEBOARD_FAB2(SCH_1):PAGE197_I6@MSTR_DISCRETE.RES(CHIPS)':
 'B': CDS_PINID='B';
NODE_NAME     Q12W2 2
 '@BASEBOARD_FAB2_LIB.BASEBOARD_FAB2(SCH_1):PAGE197_I19@W_HDL.BSL308C-H6327-GP(CHIPS)':
 'SOURCE#2': CDS_PINID='\source#2\';
NODE_NAME     R12W9 1
 '@BASEBOARD_FAB2_LIB.BASEBOARD_FAB2(SCH_1):PAGE197_I21@MSTR_DISCRETE.RES(CHIPS)':
 'A': CDS_PINID='A';
NODE_NAME     C4B11 1
 '@BASEBOARD_FAB2_LIB.BASEBOARD_FAB2(SCH_1):PAGE197_I78@MSTR_DISCRETE.CAP(CHIPS)':
 'A': CDS_PINID='A';
NODE_NAME     C4A4 1
 '@BASEBOARD_FAB2_LIB.BASEBOARD_FAB2(SCH_1):PAGE197_I81@MSTR_DISCRETE.CAP(CHIPS)':
 'A': CDS_PINID='A';
NODE_NAME     C4A17 1
 '@BASEBOARD_FAB2_LIB.BASEBOARD_FAB2(SCH_1):PAGE197_I88@MSTR_DISCRETE.CAP(CHIPS)':
 'A': CDS_PINID='A';
NET_NAME
'P12V_NVDIMM_DEF_D'
 '@BASEBOARD_FAB2_LIB.BASEBOARD_FAB2(SCH_1):P12V_NVDIMM_DEF_D':
 C_SIGNAL='@baseboard_fab2_lib.baseboard_fab2(sch_1):p12v_nvdimm_def_d';
NODE_NAME     Q12W2 4
 '@BASEBOARD_FAB2_LIB.BASEBOARD_FAB2(SCH_1):PAGE197_I19@W_HDL.BSL308C-H6327-GP(CHIPS)':
 'DRAIN#4': CDS_PINID='\drain#4\';
NODE_NAME     R12W8 2
 '@BASEBOARD_FAB2_LIB.BASEBOARD_FAB2(SCH_1):PAGE197_I113@W_HDL.4D02R2F-GP(CHIPS)':
 '2': CDS_PINID='\2\';
NODE_NAME     R12W7 1
 '@BASEBOARD_FAB2_LIB.BASEBOARD_FAB2(SCH_1):PAGE197_I121@W_HDL.665KR5B-1-GP(CHIPS)':
 '1': CDS_PINID='\1\';
NET_NAME
'P12V_NVDIMM_GHJ'
 '@BASEBOARD_FAB2_LIB.BASEBOARD_FAB2(SCH_1):P12V_NVDIMM_GHJ':
 C_SIGNAL='@baseboard_fab2_lib.baseboard_fab2(sch_1):p12v_nvdimm_ghj';
NODE_NAME     J1G1 145
 '@BASEBOARD_FAB2_LIB.BASEBOARD_FAB2(SCH_1):PAGE77_I171@MSTR_SCONN.SCONN288_H44441004(CHIPS)':
 '12V'<0>: CDS_PINID='\12v\(0)';
NODE_NAME     J1G1 1
 '@BASEBOARD_FAB2_LIB.BASEBOARD_FAB2(SCH_1):PAGE77_I171@MSTR_SCONN.SCONN288_H44441004(CHIPS)':
 '12V'<1>: CDS_PINID='\12v\(1)';
NODE_NAME     J9T1 145
 '@BASEBOARD_FAB2_LIB.BASEBOARD_FAB2(SCH_1):PAGE78_I75@MSTR_SCONN.SCONN288_H44441003(CHIPS)':
 '12V'<0>: CDS_PINID='\12v\(0)';
NODE_NAME     J9T1 1
 '@BASEBOARD_FAB2_LIB.BASEBOARD_FAB2(SCH_1):PAGE78_I75@MSTR_SCONN.SCONN288_H44441003(CHIPS)':
 '12V'<1>: CDS_PINID='\12v\(1)';
NODE_NAME     J1G2 145
 '@BASEBOARD_FAB2_LIB.BASEBOARD_FAB2(SCH_1):PAGE79_I169@MSTR_SCONN.SCONN288_H44441004(CHIPS)':
 '12V'<0>: CDS_PINID='\12v\(0)';
NODE_NAME     J1G2 1
 '@BASEBOARD_FAB2_LIB.BASEBOARD_FAB2(SCH_1):PAGE79_I169@MSTR_SCONN.SCONN288_H44441004(CHIPS)':
 '12V'<1>: CDS_PINID='\12v\(1)';
NODE_NAME     J9U1 145
 '@BASEBOARD_FAB2_LIB.BASEBOARD_FAB2(SCH_1):PAGE80_I56@MSTR_SCONN.SCONN288_H44441003(CHIPS)':
 '12V'<0>: CDS_PINID='\12v\(0)';
NODE_NAME     J9U1 1
 '@BASEBOARD_FAB2_LIB.BASEBOARD_FAB2(SCH_1):PAGE80_I56@MSTR_SCONN.SCONN288_H44441003(CHIPS)':
 '12V'<1>: CDS_PINID='\12v\(1)';
NODE_NAME     J1G3 145
 '@BASEBOARD_FAB2_LIB.BASEBOARD_FAB2(SCH_1):PAGE81_I169@MSTR_SCONN.SCONN288_H44441004(CHIPS)':
 '12V'<0>: CDS_PINID='\12v\(0)';
NODE_NAME     J1G3 1
 '@BASEBOARD_FAB2_LIB.BASEBOARD_FAB2(SCH_1):PAGE81_I169@MSTR_SCONN.SCONN288_H44441004(CHIPS)':
 '12V'<1>: CDS_PINID='\12v\(1)';
NODE_NAME     J9U2 145
 '@BASEBOARD_FAB2_LIB.BASEBOARD_FAB2(SCH_1):PAGE82_I171@MSTR_SCONN.SCONN288_H44441003(CHIPS)':
 '12V'<0>: CDS_PINID='\12v\(0)';
NODE_NAME     J9U2 1
 '@BASEBOARD_FAB2_LIB.BASEBOARD_FAB2(SCH_1):PAGE82_I171@MSTR_SCONN.SCONN288_H44441003(CHIPS)':
 '12V'<1>: CDS_PINID='\12v\(1)';
NODE_NAME     R1F3 2
 '@BASEBOARD_FAB2_LIB.BASEBOARD_FAB2(SCH_1):PAGE197_I50@MSTR_DISCRETE.RES(CHIPS)':
 'B': CDS_PINID='B';
NODE_NAME     R12W14 1
 '@BASEBOARD_FAB2_LIB.BASEBOARD_FAB2(SCH_1):PAGE197_I53@MSTR_DISCRETE.RES(CHIPS)':
 'A': CDS_PINID='A';
NODE_NAME     C9T8 1
 '@BASEBOARD_FAB2_LIB.BASEBOARD_FAB2(SCH_1):PAGE197_I56@MSTR_DISCRETE.CAP(CHIPS)':
 'A': CDS_PINID='A';
NODE_NAME     C9U11 1
 '@BASEBOARD_FAB2_LIB.BASEBOARD_FAB2(SCH_1):PAGE197_I63@MSTR_DISCRETE.CAP(CHIPS)':
 'A': CDS_PINID='A';
NODE_NAME     C9U8 1
 '@BASEBOARD_FAB2_LIB.BASEBOARD_FAB2(SCH_1):PAGE197_I66@MSTR_DISCRETE.CAP(CHIPS)':
 'A': CDS_PINID='A';
NODE_NAME     Q12W3 2
 '@BASEBOARD_FAB2_LIB.BASEBOARD_FAB2(SCH_1):PAGE197_I91@W_HDL.BSL308C-H6327-GP(CHIPS)':
 'SOURCE#2': CDS_PINID='\source#2\';
NET_NAME
'P12V_NVDIMM_GHJ_D'
 '@BASEBOARD_FAB2_LIB.BASEBOARD_FAB2(SCH_1):P12V_NVDIMM_GHJ_D':
 C_SIGNAL='@baseboard_fab2_lib.baseboard_fab2(sch_1):p12v_nvdimm_ghj_d';
NODE_NAME     Q12W3 4
 '@BASEBOARD_FAB2_LIB.BASEBOARD_FAB2(SCH_1):PAGE197_I91@W_HDL.BSL308C-H6327-GP(CHIPS)':
 'DRAIN#4': CDS_PINID='\drain#4\';
NODE_NAME     R12W13 2
 '@BASEBOARD_FAB2_LIB.BASEBOARD_FAB2(SCH_1):PAGE197_I116@W_HDL.4D02R2F-GP(CHIPS)':
 '2': CDS_PINID='\2\';
NODE_NAME     R12W12 1
 '@BASEBOARD_FAB2_LIB.BASEBOARD_FAB2(SCH_1):PAGE197_I119@W_HDL.665KR5B-1-GP(CHIPS)':
 '1': CDS_PINID='\1\';
NET_NAME
'P12V_NVDIMM_KLM'
 '@BASEBOARD_FAB2_LIB.BASEBOARD_FAB2(SCH_1):P12V_NVDIMM_KLM':
 C_SIGNAL='@baseboard_fab2_lib.baseboard_fab2(sch_1):p12v_nvdimm_klm';
NODE_NAME     J1B1 145
 '@BASEBOARD_FAB2_LIB.BASEBOARD_FAB2(SCH_1):PAGE83_I167@MSTR_SCONN.SCONN288_H44441004(CHIPS)':
 '12V'<0>: CDS_PINID='\12v\(0)';
NODE_NAME     J1B1 1
 '@BASEBOARD_FAB2_LIB.BASEBOARD_FAB2(SCH_1):PAGE83_I167@MSTR_SCONN.SCONN288_H44441004(CHIPS)':
 '12V'<1>: CDS_PINID='\12v\(1)';
NODE_NAME     J9M1 145
 '@BASEBOARD_FAB2_LIB.BASEBOARD_FAB2(SCH_1):PAGE84_I57@MSTR_SCONN.SCONN288_H44441003(CHIPS)':
 '12V'<0>: CDS_PINID='\12v\(0)';
NODE_NAME     J9M1 1
 '@BASEBOARD_FAB2_LIB.BASEBOARD_FAB2(SCH_1):PAGE84_I57@MSTR_SCONN.SCONN288_H44441003(CHIPS)':
 '12V'<1>: CDS_PINID='\12v\(1)';
NODE_NAME     J1A2 145
 '@BASEBOARD_FAB2_LIB.BASEBOARD_FAB2(SCH_1):PAGE85_I172@MSTR_SCONN.SCONN288_H44441004(CHIPS)':
 '12V'<0>: CDS_PINID='\12v\(0)';
NODE_NAME     J1A2 1
 '@BASEBOARD_FAB2_LIB.BASEBOARD_FAB2(SCH_1):PAGE85_I172@MSTR_SCONN.SCONN288_H44441004(CHIPS)':
 '12V'<1>: CDS_PINID='\12v\(1)';
NODE_NAME     J9L2 145
 '@BASEBOARD_FAB2_LIB.BASEBOARD_FAB2(SCH_1):PAGE86_I55@MSTR_SCONN.SCONN288_H44441003(CHIPS)':
 '12V'<0>: CDS_PINID='\12v\(0)';
NODE_NAME     J9L2 1
 '@BASEBOARD_FAB2_LIB.BASEBOARD_FAB2(SCH_1):PAGE86_I55@MSTR_SCONN.SCONN288_H44441003(CHIPS)':
 '12V'<1>: CDS_PINID='\12v\(1)';
NODE_NAME     J1A1 145
 '@BASEBOARD_FAB2_LIB.BASEBOARD_FAB2(SCH_1):PAGE87_I169@MSTR_SCONN.SCONN288_H44441004(CHIPS)':
 '12V'<0>: CDS_PINID='\12v\(0)';
NODE_NAME     J1A1 1
 '@BASEBOARD_FAB2_LIB.BASEBOARD_FAB2(SCH_1):PAGE87_I169@MSTR_SCONN.SCONN288_H44441004(CHIPS)':
 '12V'<1>: CDS_PINID='\12v\(1)';
NODE_NAME     J9L1 145
 '@BASEBOARD_FAB2_LIB.BASEBOARD_FAB2(SCH_1):PAGE88_I168@MSTR_SCONN.SCONN288_H44441003(CHIPS)':
 '12V'<0>: CDS_PINID='\12v\(0)';
NODE_NAME     J9L1 1
 '@BASEBOARD_FAB2_LIB.BASEBOARD_FAB2(SCH_1):PAGE88_I168@MSTR_SCONN.SCONN288_H44441003(CHIPS)':
 '12V'<1>: CDS_PINID='\12v\(1)';
NODE_NAME     R9M4 2
 '@BASEBOARD_FAB2_LIB.BASEBOARD_FAB2(SCH_1):PAGE197_I29@MSTR_DISCRETE.RES(CHIPS)':
 'B': CDS_PINID='B';
NODE_NAME     Q12W4 2
 '@BASEBOARD_FAB2_LIB.BASEBOARD_FAB2(SCH_1):PAGE197_I35@W_HDL.BSL308C-H6327-GP(CHIPS)':
 'SOURCE#2': CDS_PINID='\source#2\';
NODE_NAME     R12W19 1
 '@BASEBOARD_FAB2_LIB.BASEBOARD_FAB2(SCH_1):PAGE197_I37@MSTR_DISCRETE.RES(CHIPS)':
 'A': CDS_PINID='A';
NODE_NAME     C1A4 1
 '@BASEBOARD_FAB2_LIB.BASEBOARD_FAB2(SCH_1):PAGE197_I60@MSTR_DISCRETE.CAP(CHIPS)':
 'A': CDS_PINID='A';
NODE_NAME     C1B7 1
 '@BASEBOARD_FAB2_LIB.BASEBOARD_FAB2(SCH_1):PAGE197_I72@MSTR_DISCRETE.CAP(CHIPS)':
 'A': CDS_PINID='A';
NODE_NAME     C1A16 1
 '@BASEBOARD_FAB2_LIB.BASEBOARD_FAB2(SCH_1):PAGE197_I75@MSTR_DISCRETE.CAP(CHIPS)':
 'A': CDS_PINID='A';
NET_NAME
'P12V_NVDIMM_KLM_D'
 '@BASEBOARD_FAB2_LIB.BASEBOARD_FAB2(SCH_1):P12V_NVDIMM_KLM_D':
 C_SIGNAL='@baseboard_fab2_lib.baseboard_fab2(sch_1):p12v_nvdimm_klm_d';
NODE_NAME     Q12W4 4
 '@BASEBOARD_FAB2_LIB.BASEBOARD_FAB2(SCH_1):PAGE197_I35@W_HDL.BSL308C-H6327-GP(CHIPS)':
 'DRAIN#4': CDS_PINID='\drain#4\';
NODE_NAME     R12W18 2
 '@BASEBOARD_FAB2_LIB.BASEBOARD_FAB2(SCH_1):PAGE197_I114@W_HDL.4D02R2F-GP(CHIPS)':
 '2': CDS_PINID='\2\';
NODE_NAME     R12W17 1
 '@BASEBOARD_FAB2_LIB.BASEBOARD_FAB2(SCH_1):PAGE197_I123@W_HDL.665KR5B-1-GP(CHIPS)':
 '1': CDS_PINID='\1\';
NET_NAME
'P12V_PSU'
 '@BASEBOARD_FAB2_LIB.BASEBOARD_FAB2(SCH_1):P12V_PSU':
 C_SIGNAL='@baseboard_fab2_lib.baseboard_fab2(sch_1):p12v_psu';
NODE_NAME     C9R5 1
 '@BASEBOARD_FAB2_LIB.BASEBOARD_FAB2(SCH_1):PAGE195_I31@MSTR_DISCRETE.CAP(CHIPS)':
 'A': CDS_PINID='A';
NODE_NAME     C1E12 1
 '@BASEBOARD_FAB2_LIB.BASEBOARD_FAB2(SCH_1):PAGE195_I32@MSTR_DISCRETE.CAP(CHIPS)':
 'A': CDS_PINID='A';
NODE_NAME     C1E15 1
 '@BASEBOARD_FAB2_LIB.BASEBOARD_FAB2(SCH_1):PAGE195_I35@MSTR_DISCRETE.CAP(CHIPS)':
 'A': CDS_PINID='A';
NODE_NAME     C9R12 1
 '@BASEBOARD_FAB2_LIB.BASEBOARD_FAB2(SCH_1):PAGE195_I36@DEV_DISCRETE.CAP_A(CHIPS)':
 'A': CDS_PINID='A';
NODE_NAME     C9R6 1
 '@BASEBOARD_FAB2_LIB.BASEBOARD_FAB2(SCH_1):PAGE195_I37@DEV_DISCRETE.CAP_A(CHIPS)':
 'A': CDS_PINID='A';
NODE_NAME     C1E17 1
 '@BASEBOARD_FAB2_LIB.BASEBOARD_FAB2(SCH_1):PAGE195_I38@DEV_DISCRETE.CAP_A(CHIPS)':
 'A': CDS_PINID='A';
NODE_NAME     C1E16 1
 '@BASEBOARD_FAB2_LIB.BASEBOARD_FAB2(SCH_1):PAGE195_I39@DEV_DISCRETE.CAP_A(CHIPS)':
 'A': CDS_PINID='A';
NODE_NAME     R9P30 1
 '@BASEBOARD_FAB2_LIB.BASEBOARD_FAB2(SCH_1):PAGE199_I2@MSTR_DISCRETE.RES(CHIPS)':
 'A': CDS_PINID='A';
NODE_NAME     R9P29 1
 '@BASEBOARD_FAB2_LIB.BASEBOARD_FAB2(SCH_1):PAGE199_I12@MSTR_DISCRETE.RES(CHIPS)':
 'A': CDS_PINID='A';
NODE_NAME     R1D15 1
 '@BASEBOARD_FAB2_LIB.BASEBOARD_FAB2(SCH_1):PAGE199_I92@MSTR_DISCRETE.RES(CHIPS)':
 'A': CDS_PINID='A';
NODE_NAME     VR1D1 1
 '@BASEBOARD_FAB2_LIB.BASEBOARD_FAB2(SCH_1):PAGE199_I99@MSTR_DISCRETE.ZENER(CHIPS)':
 'C': CDS_PINID='C';
NODE_NAME     R9R1 1
 '@BASEBOARD_FAB2_LIB.BASEBOARD_FAB2(SCH_1):PAGE200_I49@MSTR_DISCRETE.RES_PWR(CHIPS)':
 '1': CDS_PINID='\1\';
NODE_NAME     R9R1 5
 '@BASEBOARD_FAB2_LIB.BASEBOARD_FAB2(SCH_1):PAGE200_I49@MSTR_DISCRETE.RES_PWR(CHIPS)':
 '5': CDS_PINID='\5\';
NODE_NAME     R1D49 1
 '@BASEBOARD_FAB2_LIB.BASEBOARD_FAB2(SCH_1):PAGE200_I50@MSTR_DISCRETE.RES_PWR(CHIPS)':
 '1': CDS_PINID='\1\';
NODE_NAME     R1D49 5
 '@BASEBOARD_FAB2_LIB.BASEBOARD_FAB2(SCH_1):PAGE200_I50@MSTR_DISCRETE.RES_PWR(CHIPS)':
 '5': CDS_PINID='\5\';
NODE_NAME     J1E1 1_1
 '@BASEBOARD_FAB2_LIB.BASEBOARD_FAB2(SCH_1):PAGE195_I114@W_HDL.FCI-CONN12-2R-GP(CHIPS)':
 '1_1': CDS_PINID='\1_1\';
NODE_NAME     J1E1 1_2
 '@BASEBOARD_FAB2_LIB.BASEBOARD_FAB2(SCH_1):PAGE195_I114@W_HDL.FCI-CONN12-2R-GP(CHIPS)':
 '1_2': CDS_PINID='\1_2\';
NODE_NAME     J1E1 1_3
 '@BASEBOARD_FAB2_LIB.BASEBOARD_FAB2(SCH_1):PAGE195_I114@W_HDL.FCI-CONN12-2R-GP(CHIPS)':
 '1_3': CDS_PINID='\1_3\';
NODE_NAME     J1E1 2_1
 '@BASEBOARD_FAB2_LIB.BASEBOARD_FAB2(SCH_1):PAGE195_I114@W_HDL.FCI-CONN12-2R-GP(CHIPS)':
 '2_1': CDS_PINID='\2_1\';
NODE_NAME     J1E1 2_2
 '@BASEBOARD_FAB2_LIB.BASEBOARD_FAB2(SCH_1):PAGE195_I114@W_HDL.FCI-CONN12-2R-GP(CHIPS)':
 '2_2': CDS_PINID='\2_2\';
NODE_NAME     J1E1 2_3
 '@BASEBOARD_FAB2_LIB.BASEBOARD_FAB2(SCH_1):PAGE195_I114@W_HDL.FCI-CONN12-2R-GP(CHIPS)':
 '2_3': CDS_PINID='\2_3\';
NODE_NAME     J1D1 1_1
 '@BASEBOARD_FAB2_LIB.BASEBOARD_FAB2(SCH_1):PAGE195_I115@W_HDL.FCI-CONN12-2R-GP(CHIPS)':
 '1_1': CDS_PINID='\1_1\';
NODE_NAME     J1D1 1_2
 '@BASEBOARD_FAB2_LIB.BASEBOARD_FAB2(SCH_1):PAGE195_I115@W_HDL.FCI-CONN12-2R-GP(CHIPS)':
 '1_2': CDS_PINID='\1_2\';
NODE_NAME     J1D1 1_3
 '@BASEBOARD_FAB2_LIB.BASEBOARD_FAB2(SCH_1):PAGE195_I115@W_HDL.FCI-CONN12-2R-GP(CHIPS)':
 '1_3': CDS_PINID='\1_3\';
NODE_NAME     J1D1 2_1
 '@BASEBOARD_FAB2_LIB.BASEBOARD_FAB2(SCH_1):PAGE195_I115@W_HDL.FCI-CONN12-2R-GP(CHIPS)':
 '2_1': CDS_PINID='\2_1\';
NODE_NAME     J1D1 2_2
 '@BASEBOARD_FAB2_LIB.BASEBOARD_FAB2(SCH_1):PAGE195_I115@W_HDL.FCI-CONN12-2R-GP(CHIPS)':
 '2_2': CDS_PINID='\2_2\';
NODE_NAME     J1D1 2_3
 '@BASEBOARD_FAB2_LIB.BASEBOARD_FAB2(SCH_1):PAGE195_I115@W_HDL.FCI-CONN12-2R-GP(CHIPS)':
 '2_3': CDS_PINID='\2_3\';
NODE_NAME     R9T9 1
 '@BASEBOARD_FAB2_LIB.BASEBOARD_FAB2(SCH_1):PAGE181_I4@MSTR_DISCRETE.RES(CHIPS)':
 'A': CDS_PINID='A';
NODE_NAME     R9T6 1
 '@BASEBOARD_FAB2_LIB.BASEBOARD_FAB2(SCH_1):PAGE181_I68@MSTR_DISCRETE.RES(CHIPS)':
 'A': CDS_PINID='A';
NODE_NAME     R9P28 1
 '@BASEBOARD_FAB2_LIB.BASEBOARD_FAB2(SCH_1):PAGE199_I138@MSTR_DISCRETE.RES(CHIPS)':
 'A': CDS_PINID='A';
NET_NAME
'P12V_PUMP'
 '@BASEBOARD_FAB2_LIB.BASEBOARD_FAB2(SCH_1):P12V_PUMP':
 C_SIGNAL='@baseboard_fab2_lib.baseboard_fab2(sch_1):p12v_pump';
NODE_NAME     C10W2 1
 '@BASEBOARD_FAB2_LIB.BASEBOARD_FAB2(SCH_1):PAGE251_I1@DEV_DISCRETE.CAP_A(CHIPS)':
 'A': CDS_PINID='A';
NODE_NAME     C10W1 1
 '@BASEBOARD_FAB2_LIB.BASEBOARD_FAB2(SCH_1):PAGE251_I3@MSTR_DISCRETE.CAP(CHIPS)':
 'A': CDS_PINID='A';
NODE_NAME     R10W5 2
 '@BASEBOARD_FAB2_LIB.BASEBOARD_FAB2(SCH_1):PAGE251_I5@MSTR_DISCRETE.RES(CHIPS)':
 'B': CDS_PINID='B';
NODE_NAME     J1B2 2
 '@BASEBOARD_FAB2_LIB.BASEBOARD_FAB2(SCH_1):PAGE251_I25@MSTR_CONN.CONN6_C74770005(CHIPS)':
 'IO2': CDS_PINID='IO2';
NET_NAME
'P12V_STBY'
 '@BASEBOARD_FAB2_LIB.BASEBOARD_FAB2(SCH_1):P12V_STBY':
 C_SIGNAL='@baseboard_fab2_lib.baseboard_fab2(sch_1):p12v_stby';
NODE_NAME     R1L9 1
 '@BASEBOARD_FAB2_LIB.BASEBOARD_FAB2(SCH_1):PAGE155_I130@MSTR_DISCRETE.RES(CHIPS)':
 'A': CDS_PINID='A';
NODE_NAME     R1U32 1
 '@BASEBOARD_FAB2_LIB.BASEBOARD_FAB2(SCH_1):PAGE169_I82@MSTR_DISCRETE.RES(CHIPS)':
 'A': CDS_PINID='A';
NODE_NAME     C1M27 1
 '@BASEBOARD_FAB2_LIB.BASEBOARD_FAB2(SCH_1):PAGE186_I3@MSTR_DISCRETE.CAP(CHIPS)':
 'A': CDS_PINID='A';
NODE_NAME     C1M26 1
 '@BASEBOARD_FAB2_LIB.BASEBOARD_FAB2(SCH_1):PAGE186_I6@MSTR_DISCRETE.CAP(CHIPS)':
 'A': CDS_PINID='A';
NODE_NAME     C1M23 1
 '@BASEBOARD_FAB2_LIB.BASEBOARD_FAB2(SCH_1):PAGE186_I7@DEV_DISCRETE.CAP_A(CHIPS)':
 'A': CDS_PINID='A';
NODE_NAME     C1M22 1
 '@BASEBOARD_FAB2_LIB.BASEBOARD_FAB2(SCH_1):PAGE186_I8@DEV_DISCRETE.CAP_A(CHIPS)':
 'A': CDS_PINID='A';
NODE_NAME     J9B3 2
 '@BASEBOARD_FAB2_LIB.BASEBOARD_FAB2(SCH_1):PAGE186_I336@MSTR_SCONN.SCONN120_A28699018(CHIPS)':
 'IO2': CDS_PINID='IO2';
NODE_NAME     J9B3 4
 '@BASEBOARD_FAB2_LIB.BASEBOARD_FAB2(SCH_1):PAGE186_I336@MSTR_SCONN.SCONN120_A28699018(CHIPS)':
 'IO4': CDS_PINID='IO4';
NODE_NAME     J9B3 6
 '@BASEBOARD_FAB2_LIB.BASEBOARD_FAB2(SCH_1):PAGE186_I336@MSTR_SCONN.SCONN120_A28699018(CHIPS)':
 'IO6': CDS_PINID='IO6';
NODE_NAME     J8E3 2
 '@BASEBOARD_FAB2_LIB.BASEBOARD_FAB2(SCH_1):PAGE187_I119@MSTR_SCONN.SCONN80_E67482007(CHIPS)':
 'IO2': CDS_PINID='IO2';
NODE_NAME     J8E3 4
 '@BASEBOARD_FAB2_LIB.BASEBOARD_FAB2(SCH_1):PAGE187_I119@MSTR_SCONN.SCONN80_E67482007(CHIPS)':
 'IO4': CDS_PINID='IO4';
NODE_NAME     C2R15 1
 '@BASEBOARD_FAB2_LIB.BASEBOARD_FAB2(SCH_1):PAGE188_I2@DEV_DISCRETE.CAP_A(CHIPS)':
 'A': CDS_PINID='A';
NODE_NAME     C2R18 1
 '@BASEBOARD_FAB2_LIB.BASEBOARD_FAB2(SCH_1):PAGE188_I3@DEV_DISCRETE.CAP_A(CHIPS)':
 'A': CDS_PINID='A';
NODE_NAME     C2P11 1
 '@BASEBOARD_FAB2_LIB.BASEBOARD_FAB2(SCH_1):PAGE188_I21@DEV_DISCRETE.CAP_A(CHIPS)':
 'A': CDS_PINID='A';
NODE_NAME     C2P12 1
 '@BASEBOARD_FAB2_LIB.BASEBOARD_FAB2(SCH_1):PAGE188_I23@DEV_DISCRETE.CAP_A(CHIPS)':
 'A': CDS_PINID='A';
NODE_NAME     C2R17 1
 '@BASEBOARD_FAB2_LIB.BASEBOARD_FAB2(SCH_1):PAGE188_I25@DEV_DISCRETE.CAP_A(CHIPS)':
 'A': CDS_PINID='A';
NODE_NAME     J8E4 33
 '@BASEBOARD_FAB2_LIB.BASEBOARD_FAB2(SCH_1):PAGE188_I27@MSTR_SCONN.SCONN64_H87568002_A(CHIPS)':
 'IO33': CDS_PINID='IO33';
NODE_NAME     J8E4 34
 '@BASEBOARD_FAB2_LIB.BASEBOARD_FAB2(SCH_1):PAGE188_I27@MSTR_SCONN.SCONN64_H87568002_A(CHIPS)':
 'IO34': CDS_PINID='IO34';
NODE_NAME     J8E4 35
 '@BASEBOARD_FAB2_LIB.BASEBOARD_FAB2(SCH_1):PAGE188_I27@MSTR_SCONN.SCONN64_H87568002_A(CHIPS)':
 'IO35': CDS_PINID='IO35';
NODE_NAME     C2R16 1
 '@BASEBOARD_FAB2_LIB.BASEBOARD_FAB2(SCH_1):PAGE188_I40@DEV_DISCRETE.CAP_A(CHIPS)':
 'A': CDS_PINID='A';
NODE_NAME     C2P10 1
 '@BASEBOARD_FAB2_LIB.BASEBOARD_FAB2(SCH_1):PAGE188_I41@MSTR_DISCRETE.CAP(CHIPS)':
 'A': CDS_PINID='A';
NODE_NAME     C2P16 1
 '@BASEBOARD_FAB2_LIB.BASEBOARD_FAB2(SCH_1):PAGE188_I53@DEV_DISCRETE.CAP_A(CHIPS)':
 'A': CDS_PINID='A';
NODE_NAME     C2P15 1
 '@BASEBOARD_FAB2_LIB.BASEBOARD_FAB2(SCH_1):PAGE188_I55@DEV_DISCRETE.CAP_A(CHIPS)':
 'A': CDS_PINID='A';
NODE_NAME     C2P14 1
 '@BASEBOARD_FAB2_LIB.BASEBOARD_FAB2(SCH_1):PAGE188_I56@DEV_DISCRETE.CAP_A(CHIPS)':
 'A': CDS_PINID='A';
NODE_NAME     C2P13 1
 '@BASEBOARD_FAB2_LIB.BASEBOARD_FAB2(SCH_1):PAGE188_I57@DEV_DISCRETE.CAP_A(CHIPS)':
 'A': CDS_PINID='A';
NODE_NAME     J4B2 A1
 '@BASEBOARD_FAB2_LIB.BASEBOARD_FAB2(SCH_1):PAGE193_I46@MSTR_SCONN.SCONN120_H61426002(CHIPS)':
 'IOA1': CDS_PINID='IOA1';
NODE_NAME     J4B2 A2
 '@BASEBOARD_FAB2_LIB.BASEBOARD_FAB2(SCH_1):PAGE193_I46@MSTR_SCONN.SCONN120_H61426002(CHIPS)':
 'IOA2': CDS_PINID='IOA2';
NODE_NAME     J4B2 A3
 '@BASEBOARD_FAB2_LIB.BASEBOARD_FAB2(SCH_1):PAGE193_I46@MSTR_SCONN.SCONN120_H61426002(CHIPS)':
 'IOA3': CDS_PINID='IOA3';
NODE_NAME     J4B2 A4
 '@BASEBOARD_FAB2_LIB.BASEBOARD_FAB2(SCH_1):PAGE193_I46@MSTR_SCONN.SCONN120_H61426002(CHIPS)':
 'IOA4': CDS_PINID='IOA4';
NODE_NAME     J4B2 A5
 '@BASEBOARD_FAB2_LIB.BASEBOARD_FAB2(SCH_1):PAGE193_I46@MSTR_SCONN.SCONN120_H61426002(CHIPS)':
 'IOA5': CDS_PINID='IOA5';
NODE_NAME     J4B2 A6
 '@BASEBOARD_FAB2_LIB.BASEBOARD_FAB2(SCH_1):PAGE193_I46@MSTR_SCONN.SCONN120_H61426002(CHIPS)':
 'IOA6': CDS_PINID='IOA6';
NODE_NAME     J4B2 A7
 '@BASEBOARD_FAB2_LIB.BASEBOARD_FAB2(SCH_1):PAGE193_I46@MSTR_SCONN.SCONN120_H61426002(CHIPS)':
 'IOA7': CDS_PINID='IOA7';
NODE_NAME     J4B2 A8
 '@BASEBOARD_FAB2_LIB.BASEBOARD_FAB2(SCH_1):PAGE193_I46@MSTR_SCONN.SCONN120_H61426002(CHIPS)':
 'IOA8': CDS_PINID='IOA8';
NODE_NAME     J4B2 B1
 '@BASEBOARD_FAB2_LIB.BASEBOARD_FAB2(SCH_1):PAGE193_I46@MSTR_SCONN.SCONN120_H61426002(CHIPS)':
 'IOB1': CDS_PINID='IOB1';
NODE_NAME     J4B2 B2
 '@BASEBOARD_FAB2_LIB.BASEBOARD_FAB2(SCH_1):PAGE193_I46@MSTR_SCONN.SCONN120_H61426002(CHIPS)':
 'IOB2': CDS_PINID='IOB2';
NODE_NAME     J4B2 B3
 '@BASEBOARD_FAB2_LIB.BASEBOARD_FAB2(SCH_1):PAGE193_I46@MSTR_SCONN.SCONN120_H61426002(CHIPS)':
 'IOB3': CDS_PINID='IOB3';
NODE_NAME     J4B2 B4
 '@BASEBOARD_FAB2_LIB.BASEBOARD_FAB2(SCH_1):PAGE193_I46@MSTR_SCONN.SCONN120_H61426002(CHIPS)':
 'IOB4': CDS_PINID='IOB4';
NODE_NAME     J4B2 B5
 '@BASEBOARD_FAB2_LIB.BASEBOARD_FAB2(SCH_1):PAGE193_I46@MSTR_SCONN.SCONN120_H61426002(CHIPS)':
 'IOB5': CDS_PINID='IOB5';
NODE_NAME     J4B2 B6
 '@BASEBOARD_FAB2_LIB.BASEBOARD_FAB2(SCH_1):PAGE193_I46@MSTR_SCONN.SCONN120_H61426002(CHIPS)':
 'IOB6': CDS_PINID='IOB6';
NODE_NAME     J4B2 B7
 '@BASEBOARD_FAB2_LIB.BASEBOARD_FAB2(SCH_1):PAGE193_I46@MSTR_SCONN.SCONN120_H61426002(CHIPS)':
 'IOB7': CDS_PINID='IOB7';
NODE_NAME     J4B2 B8
 '@BASEBOARD_FAB2_LIB.BASEBOARD_FAB2(SCH_1):PAGE193_I46@MSTR_SCONN.SCONN120_H61426002(CHIPS)':
 'IOB8': CDS_PINID='IOB8';
NODE_NAME     J6B1 A1
 '@BASEBOARD_FAB2_LIB.BASEBOARD_FAB2(SCH_1):PAGE194_I56@MSTR_SCONN.SCONN120_H61426002(CHIPS)':
 'IOA1': CDS_PINID='IOA1';
NODE_NAME     J6B1 A2
 '@BASEBOARD_FAB2_LIB.BASEBOARD_FAB2(SCH_1):PAGE194_I56@MSTR_SCONN.SCONN120_H61426002(CHIPS)':
 'IOA2': CDS_PINID='IOA2';
NODE_NAME     J6B1 A3
 '@BASEBOARD_FAB2_LIB.BASEBOARD_FAB2(SCH_1):PAGE194_I56@MSTR_SCONN.SCONN120_H61426002(CHIPS)':
 'IOA3': CDS_PINID='IOA3';
NODE_NAME     J6B1 A4
 '@BASEBOARD_FAB2_LIB.BASEBOARD_FAB2(SCH_1):PAGE194_I56@MSTR_SCONN.SCONN120_H61426002(CHIPS)':
 'IOA4': CDS_PINID='IOA4';
NODE_NAME     J6B1 A5
 '@BASEBOARD_FAB2_LIB.BASEBOARD_FAB2(SCH_1):PAGE194_I56@MSTR_SCONN.SCONN120_H61426002(CHIPS)':
 'IOA5': CDS_PINID='IOA5';
NODE_NAME     J6B1 A6
 '@BASEBOARD_FAB2_LIB.BASEBOARD_FAB2(SCH_1):PAGE194_I56@MSTR_SCONN.SCONN120_H61426002(CHIPS)':
 'IOA6': CDS_PINID='IOA6';
NODE_NAME     J6B1 A7
 '@BASEBOARD_FAB2_LIB.BASEBOARD_FAB2(SCH_1):PAGE194_I56@MSTR_SCONN.SCONN120_H61426002(CHIPS)':
 'IOA7': CDS_PINID='IOA7';
NODE_NAME     J6B1 A8
 '@BASEBOARD_FAB2_LIB.BASEBOARD_FAB2(SCH_1):PAGE194_I56@MSTR_SCONN.SCONN120_H61426002(CHIPS)':
 'IOA8': CDS_PINID='IOA8';
NODE_NAME     J6B1 B1
 '@BASEBOARD_FAB2_LIB.BASEBOARD_FAB2(SCH_1):PAGE194_I56@MSTR_SCONN.SCONN120_H61426002(CHIPS)':
 'IOB1': CDS_PINID='IOB1';
NODE_NAME     J6B1 B2
 '@BASEBOARD_FAB2_LIB.BASEBOARD_FAB2(SCH_1):PAGE194_I56@MSTR_SCONN.SCONN120_H61426002(CHIPS)':
 'IOB2': CDS_PINID='IOB2';
NODE_NAME     J6B1 B3
 '@BASEBOARD_FAB2_LIB.BASEBOARD_FAB2(SCH_1):PAGE194_I56@MSTR_SCONN.SCONN120_H61426002(CHIPS)':
 'IOB3': CDS_PINID='IOB3';
NODE_NAME     J6B1 B4
 '@BASEBOARD_FAB2_LIB.BASEBOARD_FAB2(SCH_1):PAGE194_I56@MSTR_SCONN.SCONN120_H61426002(CHIPS)':
 'IOB4': CDS_PINID='IOB4';
NODE_NAME     J6B1 B5
 '@BASEBOARD_FAB2_LIB.BASEBOARD_FAB2(SCH_1):PAGE194_I56@MSTR_SCONN.SCONN120_H61426002(CHIPS)':
 'IOB5': CDS_PINID='IOB5';
NODE_NAME     J6B1 B6
 '@BASEBOARD_FAB2_LIB.BASEBOARD_FAB2(SCH_1):PAGE194_I56@MSTR_SCONN.SCONN120_H61426002(CHIPS)':
 'IOB6': CDS_PINID='IOB6';
NODE_NAME     J6B1 B7
 '@BASEBOARD_FAB2_LIB.BASEBOARD_FAB2(SCH_1):PAGE194_I56@MSTR_SCONN.SCONN120_H61426002(CHIPS)':
 'IOB7': CDS_PINID='IOB7';
NODE_NAME     J6B1 B8
 '@BASEBOARD_FAB2_LIB.BASEBOARD_FAB2(SCH_1):PAGE194_I56@MSTR_SCONN.SCONN120_H61426002(CHIPS)':
 'IOB8': CDS_PINID='IOB8';
NODE_NAME     C4F6 1
 '@BASEBOARD_FAB2_LIB.BASEBOARD_FAB2(SCH_1):PAGE195_I82@MSTR_DISCRETE.CAPP(CHIPS)':
 'A': CDS_PINID='A';
NODE_NAME     C4B13 1
 '@BASEBOARD_FAB2_LIB.BASEBOARD_FAB2(SCH_1):PAGE195_I83@MSTR_DISCRETE.CAPP(CHIPS)':
 'A': CDS_PINID='A';
NODE_NAME     C1B14 1
 '@BASEBOARD_FAB2_LIB.BASEBOARD_FAB2(SCH_1):PAGE195_I84@MSTR_DISCRETE.CAPP(CHIPS)':
 'A': CDS_PINID='A';
NODE_NAME     C1F7 1
 '@BASEBOARD_FAB2_LIB.BASEBOARD_FAB2(SCH_1):PAGE195_I85@MSTR_DISCRETE.CAPP(CHIPS)':
 'A': CDS_PINID='A';
NODE_NAME     C4F5 1
 '@BASEBOARD_FAB2_LIB.BASEBOARD_FAB2(SCH_1):PAGE195_I96@MSTR_DISCRETE.CAPP(CHIPS)':
 'A': CDS_PINID='A';
NODE_NAME     C4B14 1
 '@BASEBOARD_FAB2_LIB.BASEBOARD_FAB2(SCH_1):PAGE195_I97@MSTR_DISCRETE.CAPP(CHIPS)':
 'A': CDS_PINID='A';
NODE_NAME     C3T6 1
 '@BASEBOARD_FAB2_LIB.BASEBOARD_FAB2(SCH_1):PAGE195_I98@MSTR_DISCRETE.CAPP(CHIPS)':
 'A': CDS_PINID='A';
NODE_NAME     C9M3 1
 '@BASEBOARD_FAB2_LIB.BASEBOARD_FAB2(SCH_1):PAGE195_I99@MSTR_DISCRETE.CAPP(CHIPS)':
 'A': CDS_PINID='A';
NODE_NAME     C3B6 1
 '@BASEBOARD_FAB2_LIB.BASEBOARD_FAB2(SCH_1):PAGE195_I100@MSTR_DISCRETE.CAPP(CHIPS)':
 'A': CDS_PINID='A';
NODE_NAME     C1R23 1
 '@BASEBOARD_FAB2_LIB.BASEBOARD_FAB2(SCH_1):PAGE195_I101@MSTR_DISCRETE.CAPP(CHIPS)':
 'A': CDS_PINID='A';
NODE_NAME     C4M6 1
 '@BASEBOARD_FAB2_LIB.BASEBOARD_FAB2(SCH_1):PAGE195_I102@MSTR_DISCRETE.CAPP(CHIPS)':
 'A': CDS_PINID='A';
NODE_NAME     C1M5 1
 '@BASEBOARD_FAB2_LIB.BASEBOARD_FAB2(SCH_1):PAGE195_I103@MSTR_DISCRETE.CAPP(CHIPS)':
 'A': CDS_PINID='A';
NODE_NAME     C3T13 1
 '@BASEBOARD_FAB2_LIB.BASEBOARD_FAB2(SCH_1):PAGE195_I104@MSTR_DISCRETE.CAPP(CHIPS)':
 'A': CDS_PINID='A';
NODE_NAME     C4M7 1
 '@BASEBOARD_FAB2_LIB.BASEBOARD_FAB2(SCH_1):PAGE195_I105@MSTR_DISCRETE.CAPP(CHIPS)':
 'A': CDS_PINID='A';
NODE_NAME     C3T15 1
 '@BASEBOARD_FAB2_LIB.BASEBOARD_FAB2(SCH_1):PAGE195_I106@MSTR_DISCRETE.CAPP(CHIPS)':
 'A': CDS_PINID='A';
NODE_NAME     C7M6 1
 '@BASEBOARD_FAB2_LIB.BASEBOARD_FAB2(SCH_1):PAGE195_I108@MSTR_DISCRETE.CAPP(CHIPS)':
 'A': CDS_PINID='A';
NODE_NAME     C6N5 1
 '@BASEBOARD_FAB2_LIB.BASEBOARD_FAB2(SCH_1):PAGE195_I109@MSTR_DISCRETE.CAPP(CHIPS)':
 'A': CDS_PINID='A';
NODE_NAME     C9T3 1
 '@BASEBOARD_FAB2_LIB.BASEBOARD_FAB2(SCH_1):PAGE195_I111@MSTR_DISCRETE.CAPP(CHIPS)':
 'A': CDS_PINID='A';
NODE_NAME     C4F4 1
 '@BASEBOARD_FAB2_LIB.BASEBOARD_FAB2(SCH_1):PAGE195_I112@MSTR_DISCRETE.CAPP(CHIPS)':
 'A': CDS_PINID='A';
NODE_NAME     C3T3 1
 '@BASEBOARD_FAB2_LIB.BASEBOARD_FAB2(SCH_1):PAGE195_I113@MSTR_DISCRETE.CAPP(CHIPS)':
 'A': CDS_PINID='A';
NODE_NAME     R3P48 1
 '@BASEBOARD_FAB2_LIB.BASEBOARD_FAB2(SCH_1):PAGE196_I74@MSTR_DISCRETE.RES(CHIPS)':
 'A': CDS_PINID='A';
NODE_NAME     EU7E1 5
 '@BASEBOARD_FAB2_LIB.BASEBOARD_FAB2(SCH_1):PAGE198_I19@MSTR_VREG.SLG55021(CHIPS)':
 'D': CDS_PINID='D';
NODE_NAME     C7E5 1
 '@BASEBOARD_FAB2_LIB.BASEBOARD_FAB2(SCH_1):PAGE198_I52@DEV_DISCRETE.CAP_A(CHIPS)':
 'A': CDS_PINID='A';
NODE_NAME     C7E6 1
 '@BASEBOARD_FAB2_LIB.BASEBOARD_FAB2(SCH_1):PAGE198_I53@MSTR_DISCRETE.CAP(CHIPS)':
 'A': CDS_PINID='A';
NODE_NAME     EU9M1 5
 '@BASEBOARD_FAB2_LIB.BASEBOARD_FAB2(SCH_1):PAGE198_I69@MSTR_VREG.SLG55021(CHIPS)':
 'D': CDS_PINID='D';
NODE_NAME     C9M10 1
 '@BASEBOARD_FAB2_LIB.BASEBOARD_FAB2(SCH_1):PAGE198_I74@MSTR_DISCRETE.CAP(CHIPS)':
 'A': CDS_PINID='A';
NODE_NAME     C9M9 1
 '@BASEBOARD_FAB2_LIB.BASEBOARD_FAB2(SCH_1):PAGE198_I76@DEV_DISCRETE.CAP_A(CHIPS)':
 'A': CDS_PINID='A';
NODE_NAME     Q1B1 5
 '@BASEBOARD_FAB2_LIB.BASEBOARD_FAB2(SCH_1):PAGE198_I86@MSTR_DISCRETE.MOSFET_N(CHIPS)':
 'DRN': CDS_PINID='DRN';
NODE_NAME     Q7E7 5
 '@BASEBOARD_FAB2_LIB.BASEBOARD_FAB2(SCH_1):PAGE198_I88@MSTR_DISCRETE.MOSFET_N(CHIPS)':
 'DRN': CDS_PINID='DRN';
NODE_NAME     R9P18 1
 '@BASEBOARD_FAB2_LIB.BASEBOARD_FAB2(SCH_1):PAGE199_I41@MSTR_DISCRETE.RES(CHIPS)':
 'A': CDS_PINID='A';
NODE_NAME     R9P23 1
 '@BASEBOARD_FAB2_LIB.BASEBOARD_FAB2(SCH_1):PAGE199_I54@MSTR_DISCRETE.RES(CHIPS)':
 'A': CDS_PINID='A';
NODE_NAME     R1D36 1
 '@BASEBOARD_FAB2_LIB.BASEBOARD_FAB2(SCH_1):PAGE199_I65@MSTR_DISCRETE.RES(CHIPS)':
 'A': CDS_PINID='A';
NODE_NAME     EU1E3 1
 '@BASEBOARD_FAB2_LIB.BASEBOARD_FAB2(SCH_1):PAGE200_I54@MSTR_DISCRETE.MOSFETN_1D3S(CHIPS)':
 'S1': CDS_PINID='S1';
NODE_NAME     EU1E3 2
 '@BASEBOARD_FAB2_LIB.BASEBOARD_FAB2(SCH_1):PAGE200_I54@MSTR_DISCRETE.MOSFETN_1D3S(CHIPS)':
 'S2': CDS_PINID='S2';
NODE_NAME     EU1E3 3
 '@BASEBOARD_FAB2_LIB.BASEBOARD_FAB2(SCH_1):PAGE200_I54@MSTR_DISCRETE.MOSFETN_1D3S(CHIPS)':
 'S3': CDS_PINID='S3';
NODE_NAME     EU9R1 1
 '@BASEBOARD_FAB2_LIB.BASEBOARD_FAB2(SCH_1):PAGE200_I57@MSTR_DISCRETE.MOSFETN_1D3S(CHIPS)':
 'S1': CDS_PINID='S1';
NODE_NAME     EU9R1 2
 '@BASEBOARD_FAB2_LIB.BASEBOARD_FAB2(SCH_1):PAGE200_I57@MSTR_DISCRETE.MOSFETN_1D3S(CHIPS)':
 'S2': CDS_PINID='S2';
NODE_NAME     EU9R1 3
 '@BASEBOARD_FAB2_LIB.BASEBOARD_FAB2(SCH_1):PAGE200_I57@MSTR_DISCRETE.MOSFETN_1D3S(CHIPS)':
 'S3': CDS_PINID='S3';
NODE_NAME     EU1E1 1
 '@BASEBOARD_FAB2_LIB.BASEBOARD_FAB2(SCH_1):PAGE200_I59@MSTR_DISCRETE.MOSFETN_1D3S(CHIPS)':
 'S1': CDS_PINID='S1';
NODE_NAME     EU1E1 2
 '@BASEBOARD_FAB2_LIB.BASEBOARD_FAB2(SCH_1):PAGE200_I59@MSTR_DISCRETE.MOSFETN_1D3S(CHIPS)':
 'S2': CDS_PINID='S2';
NODE_NAME     EU1E1 3
 '@BASEBOARD_FAB2_LIB.BASEBOARD_FAB2(SCH_1):PAGE200_I59@MSTR_DISCRETE.MOSFETN_1D3S(CHIPS)':
 'S3': CDS_PINID='S3';
NODE_NAME     U9P1 2
 '@BASEBOARD_FAB2_LIB.BASEBOARD_FAB2(SCH_1):PAGE200_I163@MSTR_VREG.TPS3700(CHIPS)':
 'VDD': CDS_PINID='VDD';
NODE_NAME     U1D2 2
 '@BASEBOARD_FAB2_LIB.BASEBOARD_FAB2(SCH_1):PAGE200_I170@MSTR_VREG.TPS3700(CHIPS)':
 'VDD': CDS_PINID='VDD';
NODE_NAME     C9P6 1
 '@BASEBOARD_FAB2_LIB.BASEBOARD_FAB2(SCH_1):PAGE200_I185@DEV_DISCRETE.CAP_A(CHIPS)':
 'A': CDS_PINID='A';
NODE_NAME     C1D9 1
 '@BASEBOARD_FAB2_LIB.BASEBOARD_FAB2(SCH_1):PAGE200_I187@DEV_DISCRETE.CAP_A(CHIPS)':
 'A': CDS_PINID='A';
NODE_NAME     CR1F5 1
 '@BASEBOARD_FAB2_LIB.BASEBOARD_FAB2(SCH_1):PAGE200_I220@MSTR_DISCRETE.DIODE(CHIPS)':
 'C': CDS_PINID='C';
NODE_NAME     R9P33 1
 '@BASEBOARD_FAB2_LIB.BASEBOARD_FAB2(SCH_1):PAGE200_I222@MSTR_DISCRETE.RES(CHIPS)':
 'A': CDS_PINID='A';
NODE_NAME     FB7F1 1
 '@BASEBOARD_FAB2_LIB.BASEBOARD_FAB2(SCH_1):PAGE231_I162@MSTR_DISCRETE.FERRITE(CHIPS)':
 'A': CDS_PINID='A';
NODE_NAME     FB7B1 1
 '@BASEBOARD_FAB2_LIB.BASEBOARD_FAB2(SCH_1):PAGE232_I200@MSTR_DISCRETE.FERRITE(CHIPS)':
 'A': CDS_PINID='A';
NODE_NAME     FB4G1 1
 '@BASEBOARD_FAB2_LIB.BASEBOARD_FAB2(SCH_1):PAGE233_I198@MSTR_DISCRETE.FERRITE(CHIPS)':
 'A': CDS_PINID='A';
NODE_NAME     FB4A1 1
 '@BASEBOARD_FAB2_LIB.BASEBOARD_FAB2(SCH_1):PAGE234_I154@MSTR_DISCRETE.FERRITE(CHIPS)':
 'A': CDS_PINID='A';
NODE_NAME     FB7E1 1
 '@BASEBOARD_FAB2_LIB.BASEBOARD_FAB2(SCH_1):PAGE241_I82@MSTR_DISCRETE.FERRITE(CHIPS)':
 'A': CDS_PINID='A';
NODE_NAME     L7C1 1
 '@BASEBOARD_FAB2_LIB.BASEBOARD_FAB2(SCH_1):PAGE212_I142@W_HDL.IND-100NH-35-GP(CHIPS)':
 'S': CDS_PINID='S';
NODE_NAME     L4C1 1
 '@BASEBOARD_FAB2_LIB.BASEBOARD_FAB2(SCH_1):PAGE204_I105@W_HDL.IND-80NH-1-GP(CHIPS)':
 'S': CDS_PINID='S';
NODE_NAME     L1B2 1
 '@BASEBOARD_FAB2_LIB.BASEBOARD_FAB2(SCH_1):PAGE209_I81@W_HDL.IND-80NH-1-GP(CHIPS)':
 'S': CDS_PINID='S';
NODE_NAME     L7F2 1
 '@BASEBOARD_FAB2_LIB.BASEBOARD_FAB2(SCH_1):PAGE217_I261@W_HDL.IND-100NH-35-GP(CHIPS)':
 'S': CDS_PINID='S';
NODE_NAME     L7A5 1
 '@BASEBOARD_FAB2_LIB.BASEBOARD_FAB2(SCH_1):PAGE220_I241@W_HDL.IND-100NH-35-GP(CHIPS)':
 'S': CDS_PINID='S';
NODE_NAME     L1F1 1
 '@BASEBOARD_FAB2_LIB.BASEBOARD_FAB2(SCH_1):PAGE225_I253@W_HDL.IND-100NH-35-GP(CHIPS)':
 'S': CDS_PINID='S';
NODE_NAME     L1B1 1
 '@BASEBOARD_FAB2_LIB.BASEBOARD_FAB2(SCH_1):PAGE228_I247@W_HDL.IND-100NH-35-GP(CHIPS)':
 'S': CDS_PINID='S';
NODE_NAME     R4B12 1
 '@BASEBOARD_FAB2_LIB.BASEBOARD_FAB2(SCH_1):PAGE197_I6@MSTR_DISCRETE.RES(CHIPS)':
 'A': CDS_PINID='A';
NODE_NAME     R4F2 1
 '@BASEBOARD_FAB2_LIB.BASEBOARD_FAB2(SCH_1):PAGE197_I14@MSTR_DISCRETE.RES(CHIPS)':
 'A': CDS_PINID='A';
NODE_NAME     R9M4 1
 '@BASEBOARD_FAB2_LIB.BASEBOARD_FAB2(SCH_1):PAGE197_I29@MSTR_DISCRETE.RES(CHIPS)':
 'A': CDS_PINID='A';
NODE_NAME     R1F3 1
 '@BASEBOARD_FAB2_LIB.BASEBOARD_FAB2(SCH_1):PAGE197_I50@MSTR_DISCRETE.RES(CHIPS)':
 'A': CDS_PINID='A';
NODE_NAME     R12W1 1
 '@BASEBOARD_FAB2_LIB.BASEBOARD_FAB2(SCH_1):PAGE197_I101@W_HDL.665KR5B-1-GP(CHIPS)':
 '1': CDS_PINID='\1\';
NODE_NAME     FB9E1 1
 '@BASEBOARD_FAB2_LIB.BASEBOARD_FAB2(SCH_1):PAGE240_I193@W_HDL.BLM31SN500SN1L-GP(CHIPS)':
 '1': CDS_PINID='\1\';
NODE_NAME     R9P13 1
 '@BASEBOARD_FAB2_LIB.BASEBOARD_FAB2(SCH_1):PAGE200_I249@W_HDL.270KR2F-GP(CHIPS)':
 '1': CDS_PINID='\1\';
NODE_NAME     R12W8 1
 '@BASEBOARD_FAB2_LIB.BASEBOARD_FAB2(SCH_1):PAGE197_I113@W_HDL.4D02R2F-GP(CHIPS)':
 '1': CDS_PINID='\1\';
NODE_NAME     R12W18 1
 '@BASEBOARD_FAB2_LIB.BASEBOARD_FAB2(SCH_1):PAGE197_I114@W_HDL.4D02R2F-GP(CHIPS)':
 '1': CDS_PINID='\1\';
NODE_NAME     R12W3 1
 '@BASEBOARD_FAB2_LIB.BASEBOARD_FAB2(SCH_1):PAGE197_I115@W_HDL.4D02R2F-GP(CHIPS)':
 '1': CDS_PINID='\1\';
NODE_NAME     R12W13 1
 '@BASEBOARD_FAB2_LIB.BASEBOARD_FAB2(SCH_1):PAGE197_I116@W_HDL.4D02R2F-GP(CHIPS)':
 '1': CDS_PINID='\1\';
NODE_NAME     R12W11 1
 '@BASEBOARD_FAB2_LIB.BASEBOARD_FAB2(SCH_1):PAGE197_I118@W_HDL.665KR5B-1-GP(CHIPS)':
 '1': CDS_PINID='\1\';
NODE_NAME     R12W6 1
 '@BASEBOARD_FAB2_LIB.BASEBOARD_FAB2(SCH_1):PAGE197_I120@W_HDL.665KR5B-1-GP(CHIPS)':
 '1': CDS_PINID='\1\';
NODE_NAME     R12W16 1
 '@BASEBOARD_FAB2_LIB.BASEBOARD_FAB2(SCH_1):PAGE197_I122@W_HDL.665KR5B-1-GP(CHIPS)':
 '1': CDS_PINID='\1\';
NODE_NAME     R9P7 1
 '@BASEBOARD_FAB2_LIB.BASEBOARD_FAB2(SCH_1):PAGE200_I252@MSTR_DISCRETE.RES(CHIPS)':
 'A': CDS_PINID='A';
NET_NAME
'P12V_SWITCH_G'
 '@BASEBOARD_FAB2_LIB.BASEBOARD_FAB2(SCH_1):P12V_SWITCH_G':
 C_SIGNAL='@baseboard_fab2_lib.baseboard_fab2(sch_1):p12v_switch_g';
NODE_NAME     EU7E1 7
 '@BASEBOARD_FAB2_LIB.BASEBOARD_FAB2(SCH_1):PAGE198_I19@MSTR_VREG.SLG55021(CHIPS)':
 'G': CDS_PINID='G';
NODE_NAME     Q7E7 4
 '@BASEBOARD_FAB2_LIB.BASEBOARD_FAB2(SCH_1):PAGE198_I88@MSTR_DISCRETE.MOSFET_N(CHIPS)':
 'GATE': CDS_PINID='GATE';
NET_NAME
'P1V05_PCH_STBY'
 '@BASEBOARD_FAB2_LIB.BASEBOARD_FAB2(SCH_1):P1V05_PCH_STBY':
 C_SIGNAL='@baseboard_fab2_lib.baseboard_fab2(sch_1):p1v05_pch_stby';
NODE_NAME     C9A6 1
 '@BASEBOARD_FAB2_LIB.BASEBOARD_FAB2(SCH_1):PAGE111_I25@DEV_DISCRETE.CAP_A(CHIPS)':
 'A': CDS_PINID='A';
NODE_NAME     J9A3 43
 '@BASEBOARD_FAB2_LIB.BASEBOARD_FAB2(SCH_1):PAGE111_I26@MSTR_SCONN.SCONN60_C21100002(CHIPS)':
 'IO43': CDS_PINID='IO43';
NODE_NAME     J9A3 44
 '@BASEBOARD_FAB2_LIB.BASEBOARD_FAB2(SCH_1):PAGE111_I26@MSTR_SCONN.SCONN60_C21100002(CHIPS)':
 'IO44': CDS_PINID='IO44';
NODE_NAME     C1L5 1
 '@BASEBOARD_FAB2_LIB.BASEBOARD_FAB2(SCH_1):PAGE111_I30@DEV_DISCRETE.CAP_A(CHIPS)':
 'A': CDS_PINID='A';
NODE_NAME     R9A17 2
 '@BASEBOARD_FAB2_LIB.BASEBOARD_FAB2(SCH_1):PAGE111_I57@MSTR_DISCRETE.RES(CHIPS)':
 'B': CDS_PINID='B';
NODE_NAME     R1L39 1
 '@BASEBOARD_FAB2_LIB.BASEBOARD_FAB2(SCH_1):PAGE112_I76@MSTR_DISCRETE.RES(CHIPS)':
 'A': CDS_PINID='A';
NODE_NAME     R1L41 1
 '@BASEBOARD_FAB2_LIB.BASEBOARD_FAB2(SCH_1):PAGE112_I77@MSTR_DISCRETE.RES(CHIPS)':
 'A': CDS_PINID='A';
NODE_NAME     R9A11 1
 '@BASEBOARD_FAB2_LIB.BASEBOARD_FAB2(SCH_1):PAGE112_I78@MSTR_DISCRETE.RES(CHIPS)':
 'A': CDS_PINID='A';
NODE_NAME     R8A13 1
 '@BASEBOARD_FAB2_LIB.BASEBOARD_FAB2(SCH_1):PAGE112_I79@MSTR_DISCRETE.RES(CHIPS)':
 'A': CDS_PINID='A';
NODE_NAME     R8A14 1
 '@BASEBOARD_FAB2_LIB.BASEBOARD_FAB2(SCH_1):PAGE112_I80@MSTR_DISCRETE.RES(CHIPS)':
 'A': CDS_PINID='A';
NODE_NAME     U7C1 AH50
 '@BASEBOARD_FAB2_LIB.BASEBOARD_FAB2(SCH_1):PAGE122_I63@MSTR_U_PROC.LBG_CORE_QAT_EXT_D(CHIPS)':
 'VCCA_CLKUNF_1P05'<0>: CDS_PINID='VCCA_CLKUNF_1P05(0)';
NODE_NAME     U7C1 U50
 '@BASEBOARD_FAB2_LIB.BASEBOARD_FAB2(SCH_1):PAGE122_I63@MSTR_U_PROC.LBG_CORE_QAT_EXT_D(CHIPS)':
 'VCCA_CLKUNF_1P05'<1>: CDS_PINID='VCCA_CLKUNF_1P05(1)';
NODE_NAME     U7C1 AW45
 '@BASEBOARD_FAB2_LIB.BASEBOARD_FAB2(SCH_1):PAGE122_I63@MSTR_U_PROC.LBG_CORE_QAT_EXT_D(CHIPS)':
 'VCCMPHY_1P05'<0>: CDS_PINID='VCCMPHY_1P05(0)';
NODE_NAME     U7C1 AW43
 '@BASEBOARD_FAB2_LIB.BASEBOARD_FAB2(SCH_1):PAGE122_I63@MSTR_U_PROC.LBG_CORE_QAT_EXT_D(CHIPS)':
 'VCCMPHY_1P05'<1>: CDS_PINID='VCCMPHY_1P05(1)';
NODE_NAME     U7C1 AJ43
 '@BASEBOARD_FAB2_LIB.BASEBOARD_FAB2(SCH_1):PAGE122_I63@MSTR_U_PROC.LBG_CORE_QAT_EXT_D(CHIPS)':
 'VCCMPHY_1P05'<2>: CDS_PINID='VCCMPHY_1P05(2)';
NODE_NAME     U7C1 AU45
 '@BASEBOARD_FAB2_LIB.BASEBOARD_FAB2(SCH_1):PAGE122_I63@MSTR_U_PROC.LBG_CORE_QAT_EXT_D(CHIPS)':
 'VCCMPHY_1P05'<3>: CDS_PINID='VCCMPHY_1P05(3)';
NODE_NAME     U7C1 AU43
 '@BASEBOARD_FAB2_LIB.BASEBOARD_FAB2(SCH_1):PAGE122_I63@MSTR_U_PROC.LBG_CORE_QAT_EXT_D(CHIPS)':
 'VCCMPHY_1P05'<4>: CDS_PINID='VCCMPHY_1P05(4)';
NODE_NAME     U7C1 AT45
 '@BASEBOARD_FAB2_LIB.BASEBOARD_FAB2(SCH_1):PAGE122_I63@MSTR_U_PROC.LBG_CORE_QAT_EXT_D(CHIPS)':
 'VCCMPHY_1P05'<5>: CDS_PINID='VCCMPHY_1P05(5)';
NODE_NAME     U7C1 AT43
 '@BASEBOARD_FAB2_LIB.BASEBOARD_FAB2(SCH_1):PAGE122_I63@MSTR_U_PROC.LBG_CORE_QAT_EXT_D(CHIPS)':
 'VCCMPHY_1P05'<6>: CDS_PINID='VCCMPHY_1P05(6)';
NODE_NAME     U7C1 AP45
 '@BASEBOARD_FAB2_LIB.BASEBOARD_FAB2(SCH_1):PAGE122_I63@MSTR_U_PROC.LBG_CORE_QAT_EXT_D(CHIPS)':
 'VCCMPHY_1P05'<7>: CDS_PINID='VCCMPHY_1P05(7)';
NODE_NAME     U7C1 AP43
 '@BASEBOARD_FAB2_LIB.BASEBOARD_FAB2(SCH_1):PAGE122_I63@MSTR_U_PROC.LBG_CORE_QAT_EXT_D(CHIPS)':
 'VCCMPHY_1P05'<8>: CDS_PINID='VCCMPHY_1P05(8)';
NODE_NAME     U7C1 AM45
 '@BASEBOARD_FAB2_LIB.BASEBOARD_FAB2(SCH_1):PAGE122_I63@MSTR_U_PROC.LBG_CORE_QAT_EXT_D(CHIPS)':
 'VCCMPHY_1P05'<9>: CDS_PINID='VCCMPHY_1P05(9)';
NODE_NAME     U7C1 AM43
 '@BASEBOARD_FAB2_LIB.BASEBOARD_FAB2(SCH_1):PAGE122_I63@MSTR_U_PROC.LBG_CORE_QAT_EXT_D(CHIPS)':
 'VCCMPHY_1P05'<10>: CDS_PINID='VCCMPHY_1P05(10)';
NODE_NAME     U7C1 AK45
 '@BASEBOARD_FAB2_LIB.BASEBOARD_FAB2(SCH_1):PAGE122_I63@MSTR_U_PROC.LBG_CORE_QAT_EXT_D(CHIPS)':
 'VCCMPHY_1P05'<11>: CDS_PINID='VCCMPHY_1P05(11)';
NODE_NAME     U7C1 AK43
 '@BASEBOARD_FAB2_LIB.BASEBOARD_FAB2(SCH_1):PAGE122_I63@MSTR_U_PROC.LBG_CORE_QAT_EXT_D(CHIPS)':
 'VCCMPHY_1P05'<12>: CDS_PINID='VCCMPHY_1P05(12)';
NODE_NAME     U7C1 BB37
 '@BASEBOARD_FAB2_LIB.BASEBOARD_FAB2(SCH_1):PAGE122_I63@MSTR_U_PROC.LBG_CORE_QAT_EXT_D(CHIPS)':
 'VCCP10GBE_LV_1P05'<0>: CDS_PINID='VCCP10GBE_LV_1P05(0)';
NODE_NAME     U7C1 BB33
 '@BASEBOARD_FAB2_LIB.BASEBOARD_FAB2(SCH_1):PAGE122_I63@MSTR_U_PROC.LBG_CORE_QAT_EXT_D(CHIPS)':
 'VCCP10GBE_LV_1P05'<1>: CDS_PINID='VCCP10GBE_LV_1P05(1)';
NODE_NAME     U7C1 BA37
 '@BASEBOARD_FAB2_LIB.BASEBOARD_FAB2(SCH_1):PAGE122_I63@MSTR_U_PROC.LBG_CORE_QAT_EXT_D(CHIPS)':
 'VCCP10GBE_LV_1P05'<2>: CDS_PINID='VCCP10GBE_LV_1P05(2)';
NODE_NAME     U7C1 BA36
 '@BASEBOARD_FAB2_LIB.BASEBOARD_FAB2(SCH_1):PAGE122_I63@MSTR_U_PROC.LBG_CORE_QAT_EXT_D(CHIPS)':
 'VCCP10GBE_LV_1P05'<3>: CDS_PINID='VCCP10GBE_LV_1P05(3)';
NODE_NAME     U7C1 BA34
 '@BASEBOARD_FAB2_LIB.BASEBOARD_FAB2(SCH_1):PAGE122_I63@MSTR_U_PROC.LBG_CORE_QAT_EXT_D(CHIPS)':
 'VCCP10GBE_LV_1P05'<4>: CDS_PINID='VCCP10GBE_LV_1P05(4)';
NODE_NAME     U7C1 BA32
 '@BASEBOARD_FAB2_LIB.BASEBOARD_FAB2(SCH_1):PAGE122_I63@MSTR_U_PROC.LBG_CORE_QAT_EXT_D(CHIPS)':
 'VCCP10GBE_LV_1P05'<5>: CDS_PINID='VCCP10GBE_LV_1P05(5)';
NODE_NAME     U7C1 BA30
 '@BASEBOARD_FAB2_LIB.BASEBOARD_FAB2(SCH_1):PAGE122_I63@MSTR_U_PROC.LBG_CORE_QAT_EXT_D(CHIPS)':
 'VCCP10GBE_LV_1P05'<6>: CDS_PINID='VCCP10GBE_LV_1P05(6)';
NODE_NAME     U7C1 AT48
 '@BASEBOARD_FAB2_LIB.BASEBOARD_FAB2(SCH_1):PAGE122_I63@MSTR_U_PROC.LBG_CORE_QAT_EXT_D(CHIPS)':
 'VCCP_HSIOPLLUNF_1P05': CDS_PINID='VCCP_HSIOPLLUNF_1P05';
NODE_NAME     U7C1 AM48
 '@BASEBOARD_FAB2_LIB.BASEBOARD_FAB2(SCH_1):PAGE122_I63@MSTR_U_PROC.LBG_CORE_QAT_EXT_D(CHIPS)':
 'VCCP_UPPLLUNF_1P05': CDS_PINID='VCCP_UPPLLUNF_1P05';
NODE_NAME     U7C1 BF46
 '@BASEBOARD_FAB2_LIB.BASEBOARD_FAB2(SCH_1):PAGE122_I63@MSTR_U_PROC.LBG_CORE_QAT_EXT_D(CHIPS)':
 'VCCPRIM_1P05'<0>: CDS_PINID='VCCPRIM_1P05(0)';
NODE_NAME     U7C1 BE48
 '@BASEBOARD_FAB2_LIB.BASEBOARD_FAB2(SCH_1):PAGE122_I63@MSTR_U_PROC.LBG_CORE_QAT_EXT_D(CHIPS)':
 'VCCPRIM_1P05'<1>: CDS_PINID='VCCPRIM_1P05(1)';
NODE_NAME     U7C1 AU39
 '@BASEBOARD_FAB2_LIB.BASEBOARD_FAB2(SCH_1):PAGE122_I63@MSTR_U_PROC.LBG_CORE_QAT_EXT_D(CHIPS)':
 'VCCPRIM_1P05'<2>: CDS_PINID='VCCPRIM_1P05(2)';
NODE_NAME     U7C1 AU37
 '@BASEBOARD_FAB2_LIB.BASEBOARD_FAB2(SCH_1):PAGE122_I63@MSTR_U_PROC.LBG_CORE_QAT_EXT_D(CHIPS)':
 'VCCPRIM_1P05'<3>: CDS_PINID='VCCPRIM_1P05(3)';
NODE_NAME     U7C1 AT39
 '@BASEBOARD_FAB2_LIB.BASEBOARD_FAB2(SCH_1):PAGE122_I63@MSTR_U_PROC.LBG_CORE_QAT_EXT_D(CHIPS)':
 'VCCPRIM_1P05'<4>: CDS_PINID='VCCPRIM_1P05(4)';
NODE_NAME     U7C1 AM27
 '@BASEBOARD_FAB2_LIB.BASEBOARD_FAB2(SCH_1):PAGE122_I63@MSTR_U_PROC.LBG_CORE_QAT_EXT_D(CHIPS)':
 'VCCPRIM_1P05'<5>: CDS_PINID='VCCPRIM_1P05(5)';
NODE_NAME     U7C1 AJ29
 '@BASEBOARD_FAB2_LIB.BASEBOARD_FAB2(SCH_1):PAGE122_I63@MSTR_U_PROC.LBG_CORE_QAT_EXT_D(CHIPS)':
 'VCCPRIM_1P05'<6>: CDS_PINID='VCCPRIM_1P05(6)';
NODE_NAME     U7C1 AC26
 '@BASEBOARD_FAB2_LIB.BASEBOARD_FAB2(SCH_1):PAGE122_I63@MSTR_U_PROC.LBG_CORE_QAT_EXT_D(CHIPS)':
 'VCCPRIM_1P05'<7>: CDS_PINID='VCCPRIM_1P05(7)';
NODE_NAME     U7C1 AA46
 '@BASEBOARD_FAB2_LIB.BASEBOARD_FAB2(SCH_1):PAGE122_I63@MSTR_U_PROC.LBG_CORE_QAT_EXT_D(CHIPS)':
 'VCCPRIM_1P05'<8>: CDS_PINID='VCCPRIM_1P05(8)';
NODE_NAME     U7C1 AA45
 '@BASEBOARD_FAB2_LIB.BASEBOARD_FAB2(SCH_1):PAGE122_I63@MSTR_U_PROC.LBG_CORE_QAT_EXT_D(CHIPS)':
 'VCCPRIM_1P05'<9>: CDS_PINID='VCCPRIM_1P05(9)';
NODE_NAME     U7C1 Y46
 '@BASEBOARD_FAB2_LIB.BASEBOARD_FAB2(SCH_1):PAGE122_I63@MSTR_U_PROC.LBG_CORE_QAT_EXT_D(CHIPS)':
 'VCCPRIM_1P05'<10>: CDS_PINID='VCCPRIM_1P05(10)';
NODE_NAME     U7C1 Y45
 '@BASEBOARD_FAB2_LIB.BASEBOARD_FAB2(SCH_1):PAGE122_I63@MSTR_U_PROC.LBG_CORE_QAT_EXT_D(CHIPS)':
 'VCCPRIM_1P05'<11>: CDS_PINID='VCCPRIM_1P05(11)';
NODE_NAME     U7C1 V44
 '@BASEBOARD_FAB2_LIB.BASEBOARD_FAB2(SCH_1):PAGE122_I63@MSTR_U_PROC.LBG_CORE_QAT_EXT_D(CHIPS)':
 'VCCPRIM_1P05'<12>: CDS_PINID='VCCPRIM_1P05(12)';
NODE_NAME     U7C1 U46
 '@BASEBOARD_FAB2_LIB.BASEBOARD_FAB2(SCH_1):PAGE122_I63@MSTR_U_PROC.LBG_CORE_QAT_EXT_D(CHIPS)':
 'VCCPRIM_1P05'<13>: CDS_PINID='VCCPRIM_1P05(13)';
NODE_NAME     U7C1 T44
 '@BASEBOARD_FAB2_LIB.BASEBOARD_FAB2(SCH_1):PAGE122_I63@MSTR_U_PROC.LBG_CORE_QAT_EXT_D(CHIPS)':
 'VCCPRIM_1P05'<14>: CDS_PINID='VCCPRIM_1P05(14)';
NODE_NAME     U7C1 R46
 '@BASEBOARD_FAB2_LIB.BASEBOARD_FAB2(SCH_1):PAGE122_I63@MSTR_U_PROC.LBG_CORE_QAT_EXT_D(CHIPS)':
 'VCCPRIM_1P05'<15>: CDS_PINID='VCCPRIM_1P05(15)';
NODE_NAME     U7C1 R42
 '@BASEBOARD_FAB2_LIB.BASEBOARD_FAB2(SCH_1):PAGE122_I63@MSTR_U_PROC.LBG_CORE_QAT_EXT_D(CHIPS)':
 'VCCPRIM_1P05'<16>: CDS_PINID='VCCPRIM_1P05(16)';
NODE_NAME     U7C1 AK27
 '@BASEBOARD_FAB2_LIB.BASEBOARD_FAB2(SCH_1):PAGE122_I63@MSTR_U_PROC.LBG_CORE_QAT_EXT_D(CHIPS)':
 'VCCPRIM_1P05'<17>: CDS_PINID='VCCPRIM_1P05(17)';
NODE_NAME     U7C1 AA24
 '@BASEBOARD_FAB2_LIB.BASEBOARD_FAB2(SCH_1):PAGE122_I63@MSTR_U_PROC.LBG_CORE_QAT_EXT_D(CHIPS)':
 'VCCPRIM_1P05'<18>: CDS_PINID='VCCPRIM_1P05(18)';
NODE_NAME     U7C1 Y26
 '@BASEBOARD_FAB2_LIB.BASEBOARD_FAB2(SCH_1):PAGE122_I63@MSTR_U_PROC.LBG_CORE_QAT_EXT_D(CHIPS)':
 'VCCPRIM_1P05'<19>: CDS_PINID='VCCPRIM_1P05(19)';
NODE_NAME     U7C1 AE27
 '@BASEBOARD_FAB2_LIB.BASEBOARD_FAB2(SCH_1):PAGE123_I21@MSTR_U_PROC.LBG_CORE_QAT_EXT_D(CHIPS)':
 'VCCMPHY_1P05'<13>: CDS_PINID='VCCMPHY_1P05(13)';
NODE_NAME     FB3M1 1
 '@BASEBOARD_FAB2_LIB.BASEBOARD_FAB2(SCH_1):PAGE127_I8@MSTR_DISCRETE.FERRITE(CHIPS)':
 'A': CDS_PINID='A';
NODE_NAME     C3M21 1
 '@BASEBOARD_FAB2_LIB.BASEBOARD_FAB2(SCH_1):PAGE127_I9@DEV_DISCRETE.CAP_A(CHIPS)':
 'A': CDS_PINID='A';
NODE_NAME     FB3M2 1
 '@BASEBOARD_FAB2_LIB.BASEBOARD_FAB2(SCH_1):PAGE127_I17@MSTR_DISCRETE.FERRITE(CHIPS)':
 'A': CDS_PINID='A';
NODE_NAME     C3M22 1
 '@BASEBOARD_FAB2_LIB.BASEBOARD_FAB2(SCH_1):PAGE127_I18@DEV_DISCRETE.CAP_A(CHIPS)':
 'A': CDS_PINID='A';
NODE_NAME     FB3M3 1
 '@BASEBOARD_FAB2_LIB.BASEBOARD_FAB2(SCH_1):PAGE127_I26@MSTR_DISCRETE.FERRITE(CHIPS)':
 'A': CDS_PINID='A';
NODE_NAME     C3M30 1
 '@BASEBOARD_FAB2_LIB.BASEBOARD_FAB2(SCH_1):PAGE127_I27@DEV_DISCRETE.CAP_A(CHIPS)':
 'A': CDS_PINID='A';
NODE_NAME     FB2M1 1
 '@BASEBOARD_FAB2_LIB.BASEBOARD_FAB2(SCH_1):PAGE127_I46@MSTR_DISCRETE.FERRITE(CHIPS)':
 'A': CDS_PINID='A';
NODE_NAME     FB3M4 1
 '@BASEBOARD_FAB2_LIB.BASEBOARD_FAB2(SCH_1):PAGE127_I56@MSTR_DISCRETE.FERRITE(CHIPS)':
 'A': CDS_PINID='A';
NODE_NAME     C3M31 1
 '@BASEBOARD_FAB2_LIB.BASEBOARD_FAB2(SCH_1):PAGE127_I57@DEV_DISCRETE.CAP_A(CHIPS)':
 'A': CDS_PINID='A';
NODE_NAME     FB2M2 1
 '@BASEBOARD_FAB2_LIB.BASEBOARD_FAB2(SCH_1):PAGE127_I69@MSTR_DISCRETE.FERRITE(CHIPS)':
 'A': CDS_PINID='A';
NODE_NAME     L2M1 1
 '@BASEBOARD_FAB2_LIB.BASEBOARD_FAB2(SCH_1):PAGE127_I71@MSTR_DISCRETE.INDUCTOR(CHIPS)':
 'INA': CDS_PINID='INA';
NODE_NAME     C2M8 1
 '@BASEBOARD_FAB2_LIB.BASEBOARD_FAB2(SCH_1):PAGE127_I74@DEV_DISCRETE.CAP_A(CHIPS)':
 'A': CDS_PINID='A';
NODE_NAME     C2M6 1
 '@BASEBOARD_FAB2_LIB.BASEBOARD_FAB2(SCH_1):PAGE127_I76@DEV_DISCRETE.CAP_A(CHIPS)':
 'A': CDS_PINID='A';
NODE_NAME     C2M25 1
 '@BASEBOARD_FAB2_LIB.BASEBOARD_FAB2(SCH_1):PAGE127_I78@DEV_DISCRETE.CAP_A(CHIPS)':
 'A': CDS_PINID='A';
NODE_NAME     C7B15 1
 '@BASEBOARD_FAB2_LIB.BASEBOARD_FAB2(SCH_1):PAGE131_I1@DEV_DISCRETE.CAP_A(CHIPS)':
 'A': CDS_PINID='A';
NODE_NAME     C7B19 1
 '@BASEBOARD_FAB2_LIB.BASEBOARD_FAB2(SCH_1):PAGE131_I2@DEV_DISCRETE.CAP_A(CHIPS)':
 'A': CDS_PINID='A';
NODE_NAME     C7B16 1
 '@BASEBOARD_FAB2_LIB.BASEBOARD_FAB2(SCH_1):PAGE131_I3@DEV_DISCRETE.CAP_A(CHIPS)':
 'A': CDS_PINID='A';
NODE_NAME     C7B21 1
 '@BASEBOARD_FAB2_LIB.BASEBOARD_FAB2(SCH_1):PAGE131_I4@DEV_DISCRETE.CAP_A(CHIPS)':
 'A': CDS_PINID='A';
NODE_NAME     C7B20 1
 '@BASEBOARD_FAB2_LIB.BASEBOARD_FAB2(SCH_1):PAGE131_I6@DEV_DISCRETE.CAP_A(CHIPS)':
 'A': CDS_PINID='A';
NODE_NAME     C7B23 1
 '@BASEBOARD_FAB2_LIB.BASEBOARD_FAB2(SCH_1):PAGE131_I7@DEV_DISCRETE.CAP_A(CHIPS)':
 'A': CDS_PINID='A';
NODE_NAME     C8B10 1
 '@BASEBOARD_FAB2_LIB.BASEBOARD_FAB2(SCH_1):PAGE131_I8@DEV_DISCRETE.CAP_A(CHIPS)':
 'A': CDS_PINID='A';
NODE_NAME     C7B22 1
 '@BASEBOARD_FAB2_LIB.BASEBOARD_FAB2(SCH_1):PAGE131_I10@DEV_DISCRETE.CAP_A(CHIPS)':
 'A': CDS_PINID='A';
NODE_NAME     C7B24 1
 '@BASEBOARD_FAB2_LIB.BASEBOARD_FAB2(SCH_1):PAGE131_I11@DEV_DISCRETE.CAP_A(CHIPS)':
 'A': CDS_PINID='A';
NODE_NAME     C7B18 1
 '@BASEBOARD_FAB2_LIB.BASEBOARD_FAB2(SCH_1):PAGE131_I12@DEV_DISCRETE.CAP_A(CHIPS)':
 'A': CDS_PINID='A';
NODE_NAME     C8B9 1
 '@BASEBOARD_FAB2_LIB.BASEBOARD_FAB2(SCH_1):PAGE131_I14@DEV_DISCRETE.CAP_A(CHIPS)':
 'A': CDS_PINID='A';
NODE_NAME     C8B11 1
 '@BASEBOARD_FAB2_LIB.BASEBOARD_FAB2(SCH_1):PAGE131_I15@DEV_DISCRETE.CAP_A(CHIPS)':
 'A': CDS_PINID='A';
NODE_NAME     C8B14 1
 '@BASEBOARD_FAB2_LIB.BASEBOARD_FAB2(SCH_1):PAGE131_I16@DEV_DISCRETE.CAP_A(CHIPS)':
 'A': CDS_PINID='A';
NODE_NAME     C7B17 1
 '@BASEBOARD_FAB2_LIB.BASEBOARD_FAB2(SCH_1):PAGE131_I18@DEV_DISCRETE.CAP_A(CHIPS)':
 'A': CDS_PINID='A';
NODE_NAME     C8B13 1
 '@BASEBOARD_FAB2_LIB.BASEBOARD_FAB2(SCH_1):PAGE131_I20@DEV_DISCRETE.CAP_A(CHIPS)':
 'A': CDS_PINID='A';
NODE_NAME     C8B16 1
 '@BASEBOARD_FAB2_LIB.BASEBOARD_FAB2(SCH_1):PAGE131_I22@MSTR_DISCRETE.CAP(CHIPS)':
 'A': CDS_PINID='A';
NODE_NAME     C8B15 1
 '@BASEBOARD_FAB2_LIB.BASEBOARD_FAB2(SCH_1):PAGE131_I24@MSTR_DISCRETE.CAP(CHIPS)':
 'A': CDS_PINID='A';
NODE_NAME     C2M22 1
 '@BASEBOARD_FAB2_LIB.BASEBOARD_FAB2(SCH_1):PAGE131_I27@DEV_DISCRETE.CAP_A(CHIPS)':
 'A': CDS_PINID='A';
NODE_NAME     C2M21 1
 '@BASEBOARD_FAB2_LIB.BASEBOARD_FAB2(SCH_1):PAGE131_I28@DEV_DISCRETE.CAP_A(CHIPS)':
 'A': CDS_PINID='A';
NODE_NAME     C2M18 1
 '@BASEBOARD_FAB2_LIB.BASEBOARD_FAB2(SCH_1):PAGE131_I29@DEV_DISCRETE.CAP_A(CHIPS)':
 'A': CDS_PINID='A';
NODE_NAME     C2M19 1
 '@BASEBOARD_FAB2_LIB.BASEBOARD_FAB2(SCH_1):PAGE131_I31@DEV_DISCRETE.CAP_A(CHIPS)':
 'A': CDS_PINID='A';
NODE_NAME     C3M38 1
 '@BASEBOARD_FAB2_LIB.BASEBOARD_FAB2(SCH_1):PAGE131_I32@DEV_DISCRETE.CAP_A(CHIPS)':
 'A': CDS_PINID='A';
NODE_NAME     C2M17 1
 '@BASEBOARD_FAB2_LIB.BASEBOARD_FAB2(SCH_1):PAGE131_I34@MSTR_DISCRETE.CAP(CHIPS)':
 'A': CDS_PINID='A';
NODE_NAME     C2M11 1
 '@BASEBOARD_FAB2_LIB.BASEBOARD_FAB2(SCH_1):PAGE131_I35@MSTR_DISCRETE.CAP(CHIPS)':
 'A': CDS_PINID='A';
NODE_NAME     C8A13 1
 '@BASEBOARD_FAB2_LIB.BASEBOARD_FAB2(SCH_1):PAGE131_I37@MSTR_DISCRETE.CAP(CHIPS)':
 'A': CDS_PINID='A';
NODE_NAME     C2M20 1
 '@BASEBOARD_FAB2_LIB.BASEBOARD_FAB2(SCH_1):PAGE131_I39@DEV_DISCRETE.CAP_A(CHIPS)':
 'A': CDS_PINID='A';
NODE_NAME     C2N13 1
 '@BASEBOARD_FAB2_LIB.BASEBOARD_FAB2(SCH_1):PAGE131_I40@DEV_DISCRETE.CAP_A(CHIPS)':
 'A': CDS_PINID='A';
NODE_NAME     C2N2 1
 '@BASEBOARD_FAB2_LIB.BASEBOARD_FAB2(SCH_1):PAGE131_I41@DEV_DISCRETE.CAP_A(CHIPS)':
 'A': CDS_PINID='A';
NODE_NAME     C3M43 1
 '@BASEBOARD_FAB2_LIB.BASEBOARD_FAB2(SCH_1):PAGE131_I42@DEV_DISCRETE.CAP_A(CHIPS)':
 'A': CDS_PINID='A';
NODE_NAME     C2N7 1
 '@BASEBOARD_FAB2_LIB.BASEBOARD_FAB2(SCH_1):PAGE131_I43@DEV_DISCRETE.CAP_A(CHIPS)':
 'A': CDS_PINID='A';
NODE_NAME     C3M39 1
 '@BASEBOARD_FAB2_LIB.BASEBOARD_FAB2(SCH_1):PAGE131_I44@DEV_DISCRETE.CAP_A(CHIPS)':
 'A': CDS_PINID='A';
NODE_NAME     C3M42 1
 '@BASEBOARD_FAB2_LIB.BASEBOARD_FAB2(SCH_1):PAGE131_I45@DEV_DISCRETE.CAP_A(CHIPS)':
 'A': CDS_PINID='A';
NODE_NAME     C2N8 1
 '@BASEBOARD_FAB2_LIB.BASEBOARD_FAB2(SCH_1):PAGE131_I47@DEV_DISCRETE.CAP_A(CHIPS)':
 'A': CDS_PINID='A';
NODE_NAME     C2M13 1
 '@BASEBOARD_FAB2_LIB.BASEBOARD_FAB2(SCH_1):PAGE131_I48@DEV_DISCRETE.CAP_A(CHIPS)':
 'A': CDS_PINID='A';
NODE_NAME     C2N10 1
 '@BASEBOARD_FAB2_LIB.BASEBOARD_FAB2(SCH_1):PAGE131_I50@DEV_DISCRETE.CAP_A(CHIPS)':
 'A': CDS_PINID='A';
NODE_NAME     C2M12 1
 '@BASEBOARD_FAB2_LIB.BASEBOARD_FAB2(SCH_1):PAGE131_I52@DEV_DISCRETE.CAP_A(CHIPS)':
 'A': CDS_PINID='A';
NODE_NAME     R3P8 1
 '@BASEBOARD_FAB2_LIB.BASEBOARD_FAB2(SCH_1):PAGE133_I322@MSTR_DISCRETE.RES(CHIPS)':
 'A': CDS_PINID='A';
NODE_NAME     R7D44 1
 '@BASEBOARD_FAB2_LIB.BASEBOARD_FAB2(SCH_1):PAGE133_I356@MSTR_DISCRETE.RES(CHIPS)':
 'A': CDS_PINID='A';
NODE_NAME     R7C21 1
 '@BASEBOARD_FAB2_LIB.BASEBOARD_FAB2(SCH_1):PAGE134_I9@MSTR_DISCRETE.RES(CHIPS)':
 'A': CDS_PINID='A';
NODE_NAME     FB1U3 2
 '@BASEBOARD_FAB2_LIB.BASEBOARD_FAB2(SCH_1):PAGE169_I57@MSTR_DISCRETE.FERRITE(CHIPS)':
 'B': CDS_PINID='B';
NODE_NAME     C7A42 1
 '@BASEBOARD_FAB2_LIB.BASEBOARD_FAB2(SCH_1):PAGE236_I46@MSTR_DISCRETE.CAP(CHIPS)':
 'A': CDS_PINID='A';
NODE_NAME     R8B14 2
 '@BASEBOARD_FAB2_LIB.BASEBOARD_FAB2(SCH_1):PAGE236_I56@MSTR_DISCRETE.RES(CHIPS)':
 'B': CDS_PINID='B';
NODE_NAME     C3L19 1
 '@BASEBOARD_FAB2_LIB.BASEBOARD_FAB2(SCH_1):PAGE236_I76@MSTR_DISCRETE.CAPP(CHIPS)':
 'A': CDS_PINID='A';
NODE_NAME     C2L46 1
 '@BASEBOARD_FAB2_LIB.BASEBOARD_FAB2(SCH_1):PAGE236_I77@MSTR_DISCRETE.CAPP(CHIPS)':
 'A': CDS_PINID='A';
NODE_NAME     C8A15 1
 '@BASEBOARD_FAB2_LIB.BASEBOARD_FAB2(SCH_1):PAGE236_I78@MSTR_DISCRETE.CAPP(CHIPS)':
 'A': CDS_PINID='A';
NODE_NAME     C2L25 1
 '@BASEBOARD_FAB2_LIB.BASEBOARD_FAB2(SCH_1):PAGE236_I79@MSTR_DISCRETE.CAPP(CHIPS)':
 'A': CDS_PINID='A';
NODE_NAME     EU7A2 1
 '@BASEBOARD_FAB2_LIB.BASEBOARD_FAB2(SCH_1):PAGE236_I117@MSTR_DISCRETE.IR354XX(CHIPS)':
 'VOS': CDS_PINID='VOS';
NODE_NAME     R3P53 1
 '@BASEBOARD_FAB2_LIB.BASEBOARD_FAB2(SCH_1):PAGE133_I365@MSTR_DISCRETE.RES(CHIPS)':
 'A': CDS_PINID='A';
NODE_NAME     L7A4 2
 '@BASEBOARD_FAB2_LIB.BASEBOARD_FAB2(SCH_1):PAGE236_I179@W_HDL.IND-300NH-20-GP(CHIPS)':
 'F': CDS_PINID='F';
NODE_NAME     R3P5 1
 '@BASEBOARD_FAB2_LIB.BASEBOARD_FAB2(SCH_1):PAGE133_I366@MSTR_DISCRETE.RES(CHIPS)':
 'A': CDS_PINID='A';
NODE_NAME     R3P6 1
 '@BASEBOARD_FAB2_LIB.BASEBOARD_FAB2(SCH_1):PAGE133_I367@MSTR_DISCRETE.RES(CHIPS)':
 'A': CDS_PINID='A';
NODE_NAME     R3N15 1
 '@BASEBOARD_FAB2_LIB.BASEBOARD_FAB2(SCH_1):PAGE133_I368@MSTR_DISCRETE.RES(CHIPS)':
 'A': CDS_PINID='A';
NODE_NAME     R3N16 1
 '@BASEBOARD_FAB2_LIB.BASEBOARD_FAB2(SCH_1):PAGE133_I369@MSTR_DISCRETE.RES(CHIPS)':
 'A': CDS_PINID='A';
NODE_NAME     R3P7 1
 '@BASEBOARD_FAB2_LIB.BASEBOARD_FAB2(SCH_1):PAGE133_I370@MSTR_DISCRETE.RES(CHIPS)':
 'A': CDS_PINID='A';
NODE_NAME     U25W12 12
 '@BASEBOARD_FAB2_LIB.BASEBOARD_FAB2(SCH_1):PAGE269_I33@MSTR_TTL.TTL3126(CHIPS)'(0):
 'A'<0>: CDS_PINID='A(0)';
NODE_NAME     U25W12 9
 '@BASEBOARD_FAB2_LIB.BASEBOARD_FAB2(SCH_1):PAGE269_I33@MSTR_TTL.TTL3126(CHIPS)'(1):
 'A'<1>: CDS_PINID='A(1)';
NODE_NAME     U25W12 5
 '@BASEBOARD_FAB2_LIB.BASEBOARD_FAB2(SCH_1):PAGE269_I33@MSTR_TTL.TTL3126(CHIPS)'(2):
 'A'<2>: CDS_PINID='A(2)';
NODE_NAME     R25W164 1
 '@BASEBOARD_FAB2_LIB.BASEBOARD_FAB2(SCH_1):PAGE268_I29@MSTR_DISCRETE.RES(CHIPS)':
 'A': CDS_PINID='A';
NET_NAME
'P1V05_PCH_STBY_ISCLK_PLL'
 '@BASEBOARD_FAB2_LIB.BASEBOARD_FAB2(SCH_1):P1V05_PCH_STBY_ISCLK_PLL':
 C_SIGNAL='@baseboard_fab2_lib.baseboard_fab2(sch_1):p1v05_pch_stby_isclk_pll';
NODE_NAME     U7C1 W50
 '@BASEBOARD_FAB2_LIB.BASEBOARD_FAB2(SCH_1):PAGE122_I63@MSTR_U_PROC.LBG_CORE_QAT_EXT_D(CHIPS)':
 'VCCA_CLKFILT_1P05'<0>: CDS_PINID='VCCA_CLKFILT_1P05(0)';
NODE_NAME     U7C1 AG45
 '@BASEBOARD_FAB2_LIB.BASEBOARD_FAB2(SCH_1):PAGE122_I63@MSTR_U_PROC.LBG_CORE_QAT_EXT_D(CHIPS)':
 'VCCA_CLKFILT_1P05'<1>: CDS_PINID='VCCA_CLKFILT_1P05(1)';
NODE_NAME     U7C1 AJ46
 '@BASEBOARD_FAB2_LIB.BASEBOARD_FAB2(SCH_1):PAGE122_I63@MSTR_U_PROC.LBG_CORE_QAT_EXT_D(CHIPS)':
 'VCCA_CLKFILT_1P05'<2>: CDS_PINID='VCCA_CLKFILT_1P05(2)';
NODE_NAME     U7C1 AJ48
 '@BASEBOARD_FAB2_LIB.BASEBOARD_FAB2(SCH_1):PAGE122_I63@MSTR_U_PROC.LBG_CORE_QAT_EXT_D(CHIPS)':
 'VCCA_CLKFILT_1P05'<3>: CDS_PINID='VCCA_CLKFILT_1P05(3)';
NODE_NAME     U7C1 AE46
 '@BASEBOARD_FAB2_LIB.BASEBOARD_FAB2(SCH_1):PAGE122_I63@MSTR_U_PROC.LBG_CORE_QAT_EXT_D(CHIPS)':
 'VCCA_CLKFILT_1P05'<4>: CDS_PINID='VCCA_CLKFILT_1P05(4)';
NODE_NAME     FB3M4 2
 '@BASEBOARD_FAB2_LIB.BASEBOARD_FAB2(SCH_1):PAGE127_I56@MSTR_DISCRETE.FERRITE(CHIPS)':
 'B': CDS_PINID='B';
NODE_NAME     C3M29 1
 '@BASEBOARD_FAB2_LIB.BASEBOARD_FAB2(SCH_1):PAGE127_I80@DEV_DISCRETE.CAP_A(CHIPS)':
 'A': CDS_PINID='A';
NODE_NAME     C3M24 1
 '@BASEBOARD_FAB2_LIB.BASEBOARD_FAB2(SCH_1):PAGE127_I81@MSTR_DISCRETE.CAP(CHIPS)':
 'A': CDS_PINID='A';
NET_NAME
'P1V05_PCH_STBY_KR_PLL'
 '@BASEBOARD_FAB2_LIB.BASEBOARD_FAB2(SCH_1):P1V05_PCH_STBY_KR_PLL':
 C_SIGNAL='@baseboard_fab2_lib.baseboard_fab2(sch_1):p1v05_pch_stby_kr_pll';
NODE_NAME     R2N4 1
 '@BASEBOARD_FAB2_LIB.BASEBOARD_FAB2(SCH_1):PAGE118_I96@MSTR_DISCRETE.RES(CHIPS)':
 'A': CDS_PINID='A';
NODE_NAME     R2M6 2
 '@BASEBOARD_FAB2_LIB.BASEBOARD_FAB2(SCH_1):PAGE118_I99@MSTR_DISCRETE.RES(CHIPS)':
 'B': CDS_PINID='B';
NODE_NAME     U7C1 BD38
 '@BASEBOARD_FAB2_LIB.BASEBOARD_FAB2(SCH_1):PAGE122_I63@MSTR_U_PROC.LBG_CORE_QAT_EXT_D(CHIPS)':
 'VCCP10GBEPLL_1P05'<0>: CDS_PINID='VCCP10GBEPLL_1P05(0)';
NODE_NAME     U7C1 BB40
 '@BASEBOARD_FAB2_LIB.BASEBOARD_FAB2(SCH_1):PAGE122_I63@MSTR_U_PROC.LBG_CORE_QAT_EXT_D(CHIPS)':
 'VCCP10GBEPLL_1P05'<1>: CDS_PINID='VCCP10GBEPLL_1P05(1)';
NODE_NAME     U7C1 BA41
 '@BASEBOARD_FAB2_LIB.BASEBOARD_FAB2(SCH_1):PAGE122_I63@MSTR_U_PROC.LBG_CORE_QAT_EXT_D(CHIPS)':
 'VCCP10GBEPLL_1P05'<2>: CDS_PINID='VCCP10GBEPLL_1P05(2)';
NODE_NAME     U7C1 BA39
 '@BASEBOARD_FAB2_LIB.BASEBOARD_FAB2(SCH_1):PAGE122_I63@MSTR_U_PROC.LBG_CORE_QAT_EXT_D(CHIPS)':
 'VCCP10GBEPLL_1P05'<3>: CDS_PINID='VCCP10GBEPLL_1P05(3)';
NODE_NAME     C2N6 1
 '@BASEBOARD_FAB2_LIB.BASEBOARD_FAB2(SCH_1):PAGE127_I64@MSTR_DISCRETE.CAP(CHIPS)':
 'A': CDS_PINID='A';
NODE_NAME     C2N5 1
 '@BASEBOARD_FAB2_LIB.BASEBOARD_FAB2(SCH_1):PAGE127_I65@DEV_DISCRETE.CAP_A(CHIPS)':
 'A': CDS_PINID='A';
NODE_NAME     L2M1 2
 '@BASEBOARD_FAB2_LIB.BASEBOARD_FAB2(SCH_1):PAGE127_I71@MSTR_DISCRETE.INDUCTOR(CHIPS)':
 'INB': CDS_PINID='INB';
NET_NAME
'P1V05_PCH_STBY_VCCA_PLL0'
 '@BASEBOARD_FAB2_LIB.BASEBOARD_FAB2(SCH_1):P1V05_PCH_STBY_VCCA_PLL0':
 C_SIGNAL='@baseboard_fab2_lib.baseboard_fab2(sch_1):p1v05_pch_stby_vcca_pll0';
NODE_NAME     U7C1 AG48
 '@BASEBOARD_FAB2_LIB.BASEBOARD_FAB2(SCH_1):PAGE122_I63@MSTR_U_PROC.LBG_CORE_QAT_EXT_D(CHIPS)':
 'VCCA_PLL0_1P05': CDS_PINID='VCCA_PLL0_1P05';
NODE_NAME     FB3M2 2
 '@BASEBOARD_FAB2_LIB.BASEBOARD_FAB2(SCH_1):PAGE127_I17@MSTR_DISCRETE.FERRITE(CHIPS)':
 'B': CDS_PINID='B';
NODE_NAME     C3M20 1
 '@BASEBOARD_FAB2_LIB.BASEBOARD_FAB2(SCH_1):PAGE127_I84@DEV_DISCRETE.CAP_A(CHIPS)':
 'A': CDS_PINID='A';
NODE_NAME     C3M18 1
 '@BASEBOARD_FAB2_LIB.BASEBOARD_FAB2(SCH_1):PAGE127_I85@MSTR_DISCRETE.CAP(CHIPS)':
 'A': CDS_PINID='A';
NET_NAME
'P1V05_PCH_STBY_VCCA_PLL1'
 '@BASEBOARD_FAB2_LIB.BASEBOARD_FAB2(SCH_1):P1V05_PCH_STBY_VCCA_PLL1':
 C_SIGNAL='@baseboard_fab2_lib.baseboard_fab2(sch_1):p1v05_pch_stby_vcca_pll1';
NODE_NAME     U7C1 AE45
 '@BASEBOARD_FAB2_LIB.BASEBOARD_FAB2(SCH_1):PAGE122_I63@MSTR_U_PROC.LBG_CORE_QAT_EXT_D(CHIPS)':
 'VCCA_PLL1_1P05': CDS_PINID='VCCA_PLL1_1P05';
NODE_NAME     FB3M1 2
 '@BASEBOARD_FAB2_LIB.BASEBOARD_FAB2(SCH_1):PAGE127_I8@MSTR_DISCRETE.FERRITE(CHIPS)':
 'B': CDS_PINID='B';
NODE_NAME     C3M17 1
 '@BASEBOARD_FAB2_LIB.BASEBOARD_FAB2(SCH_1):PAGE127_I86@MSTR_DISCRETE.CAP(CHIPS)':
 'A': CDS_PINID='A';
NODE_NAME     C3M19 1
 '@BASEBOARD_FAB2_LIB.BASEBOARD_FAB2(SCH_1):PAGE127_I87@DEV_DISCRETE.CAP_A(CHIPS)':
 'A': CDS_PINID='A';
NET_NAME
'P1V05_PCH_STBY_VCCA_XTAL'
 '@BASEBOARD_FAB2_LIB.BASEBOARD_FAB2(SCH_1):P1V05_PCH_STBY_VCCA_XTAL':
 C_SIGNAL='@baseboard_fab2_lib.baseboard_fab2(sch_1):p1v05_pch_stby_vcca_xtal';
NODE_NAME     U7C1 AD50
 '@BASEBOARD_FAB2_LIB.BASEBOARD_FAB2(SCH_1):PAGE122_I63@MSTR_U_PROC.LBG_CORE_QAT_EXT_D(CHIPS)':
 'VCCA_CLKXTAL_1P05': CDS_PINID='VCCA_CLKXTAL_1P05';
NODE_NAME     FB3M3 2
 '@BASEBOARD_FAB2_LIB.BASEBOARD_FAB2(SCH_1):PAGE127_I26@MSTR_DISCRETE.FERRITE(CHIPS)':
 'B': CDS_PINID='B';
NODE_NAME     C3M23 1
 '@BASEBOARD_FAB2_LIB.BASEBOARD_FAB2(SCH_1):PAGE127_I82@MSTR_DISCRETE.CAP(CHIPS)':
 'A': CDS_PINID='A';
NODE_NAME     C3M27 1
 '@BASEBOARD_FAB2_LIB.BASEBOARD_FAB2(SCH_1):PAGE127_I83@DEV_DISCRETE.CAP_A(CHIPS)':
 'A': CDS_PINID='A';
NET_NAME
'P1V05_PCH_STBY_WM20_PLL'
 '@BASEBOARD_FAB2_LIB.BASEBOARD_FAB2(SCH_1):P1V05_PCH_STBY_WM20_PLL':
 C_SIGNAL='@baseboard_fab2_lib.baseboard_fab2(sch_1):p1v05_pch_stby_wm20_pll';
NODE_NAME     U7C1 AN50
 '@BASEBOARD_FAB2_LIB.BASEBOARD_FAB2(SCH_1):PAGE122_I63@MSTR_U_PROC.LBG_CORE_QAT_EXT_D(CHIPS)':
 'VCCP_UPPLL_1P05'<0>: CDS_PINID='VCCP_UPPLL_1P05(0)';
NODE_NAME     U7C1 AK50
 '@BASEBOARD_FAB2_LIB.BASEBOARD_FAB2(SCH_1):PAGE122_I63@MSTR_U_PROC.LBG_CORE_QAT_EXT_D(CHIPS)':
 'VCCP_UPPLL_1P05'<2>: CDS_PINID='VCCP_UPPLL_1P05(2)';
NODE_NAME     C2M5 1
 '@BASEBOARD_FAB2_LIB.BASEBOARD_FAB2(SCH_1):PAGE127_I43@MSTR_DISCRETE.CAP(CHIPS)':
 'A': CDS_PINID='A';
NODE_NAME     C2M7 1
 '@BASEBOARD_FAB2_LIB.BASEBOARD_FAB2(SCH_1):PAGE127_I44@DEV_DISCRETE.CAP_A(CHIPS)':
 'A': CDS_PINID='A';
NODE_NAME     FB2M1 2
 '@BASEBOARD_FAB2_LIB.BASEBOARD_FAB2(SCH_1):PAGE127_I46@MSTR_DISCRETE.FERRITE(CHIPS)':
 'B': CDS_PINID='B';
NET_NAME
'P1V05_PCH_STBY_WM26_PLL'
 '@BASEBOARD_FAB2_LIB.BASEBOARD_FAB2(SCH_1):P1V05_PCH_STBY_WM26_PLL':
 C_SIGNAL='@baseboard_fab2_lib.baseboard_fab2(sch_1):p1v05_pch_stby_wm26_pll';
NODE_NAME     U7C1 AW48
 '@BASEBOARD_FAB2_LIB.BASEBOARD_FAB2(SCH_1):PAGE122_I63@MSTR_U_PROC.LBG_CORE_QAT_EXT_D(CHIPS)':
 'VCCP_HSIOPLL_1P05'<0>: CDS_PINID='VCCP_HSIOPLL_1P05(0)';
NODE_NAME     U7C1 AU48
 '@BASEBOARD_FAB2_LIB.BASEBOARD_FAB2(SCH_1):PAGE122_I63@MSTR_U_PROC.LBG_CORE_QAT_EXT_D(CHIPS)':
 'VCCP_HSIOPLL_1P05'<2>: CDS_PINID='VCCP_HSIOPLL_1P05(2)';
NODE_NAME     U7C1 AP48
 '@BASEBOARD_FAB2_LIB.BASEBOARD_FAB2(SCH_1):PAGE122_I63@MSTR_U_PROC.LBG_CORE_QAT_EXT_D(CHIPS)':
 'VCCP_HSIOPLL_1P05'<3>: CDS_PINID='VCCP_HSIOPLL_1P05(3)';
NODE_NAME     C2M10 1
 '@BASEBOARD_FAB2_LIB.BASEBOARD_FAB2(SCH_1):PAGE127_I49@MSTR_DISCRETE.CAP(CHIPS)':
 'A': CDS_PINID='A';
NODE_NAME     C2M9 1
 '@BASEBOARD_FAB2_LIB.BASEBOARD_FAB2(SCH_1):PAGE127_I50@DEV_DISCRETE.CAP_A(CHIPS)':
 'A': CDS_PINID='A';
NODE_NAME     FB2M2 2
 '@BASEBOARD_FAB2_LIB.BASEBOARD_FAB2(SCH_1):PAGE127_I69@MSTR_DISCRETE.FERRITE(CHIPS)':
 'B': CDS_PINID='B';
NET_NAME
'P1V15_AUX_BMC'
 '@BASEBOARD_FAB2_LIB.BASEBOARD_FAB2(SCH_1):P1V15_AUX_BMC':
 C_SIGNAL='@baseboard_fab2_lib.baseboard_fab2(sch_1):p1v15_aux_bmc';
NODE_NAME     C9E10 1
 '@BASEBOARD_FAB2_LIB.BASEBOARD_FAB2(SCH_1):PAGE238_I23@MSTR_DISCRETE.CAP(CHIPS)':
 'A': CDS_PINID='A';
NODE_NAME     C9F4 1
 '@BASEBOARD_FAB2_LIB.BASEBOARD_FAB2(SCH_1):PAGE238_I30@MSTR_DISCRETE.CAP(CHIPS)':
 'A': CDS_PINID='A';
NODE_NAME     EU9F1 1
 '@BASEBOARD_FAB2_LIB.BASEBOARD_FAB2(SCH_1):PAGE238_I40@MSTR_VREG.RT9059(CHIPS)':
 'VOUT'<0>: CDS_PINID='VOUT(0)';
NODE_NAME     EU9F1 2
 '@BASEBOARD_FAB2_LIB.BASEBOARD_FAB2(SCH_1):PAGE238_I40@MSTR_VREG.RT9059(CHIPS)':
 'VOUT'<1>: CDS_PINID='VOUT(1)';
NODE_NAME     EU9F1 3
 '@BASEBOARD_FAB2_LIB.BASEBOARD_FAB2(SCH_1):PAGE238_I40@MSTR_VREG.RT9059(CHIPS)':
 'VOUT'<2>: CDS_PINID='VOUT(2)';
NODE_NAME     R9F6 1
 '@BASEBOARD_FAB2_LIB.BASEBOARD_FAB2(SCH_1):PAGE238_I45@W_HDL.4K42R2F-GP(CHIPS)':
 '1': CDS_PINID='\1\';
NODE_NAME     U25W4 F6
 '@BASEBOARD_FAB2_LIB.BASEBOARD_FAB2(SCH_1):PAGE148_I28@W_HDL.AST2520A1-GP-GP(CHIPS)':
 'IV11D0': CDS_PINID='IV11D0';
NODE_NAME     U25W4 G10
 '@BASEBOARD_FAB2_LIB.BASEBOARD_FAB2(SCH_1):PAGE148_I28@W_HDL.AST2520A1-GP-GP(CHIPS)':
 'IV11D1': CDS_PINID='IV11D1';
NODE_NAME     U25W4 G11
 '@BASEBOARD_FAB2_LIB.BASEBOARD_FAB2(SCH_1):PAGE148_I28@W_HDL.AST2520A1-GP-GP(CHIPS)':
 'IV11D2': CDS_PINID='IV11D2';
NODE_NAME     U25W4 G12
 '@BASEBOARD_FAB2_LIB.BASEBOARD_FAB2(SCH_1):PAGE148_I28@W_HDL.AST2520A1-GP-GP(CHIPS)':
 'IV11D3': CDS_PINID='IV11D3';
NODE_NAME     U25W4 G13
 '@BASEBOARD_FAB2_LIB.BASEBOARD_FAB2(SCH_1):PAGE148_I28@W_HDL.AST2520A1-GP-GP(CHIPS)':
 'IV11D4': CDS_PINID='IV11D4';
NODE_NAME     U25W4 G14
 '@BASEBOARD_FAB2_LIB.BASEBOARD_FAB2(SCH_1):PAGE148_I28@W_HDL.AST2520A1-GP-GP(CHIPS)':
 'IV11D5': CDS_PINID='IV11D5';
NODE_NAME     U25W4 G15
 '@BASEBOARD_FAB2_LIB.BASEBOARD_FAB2(SCH_1):PAGE148_I28@W_HDL.AST2520A1-GP-GP(CHIPS)':
 'IV11D6': CDS_PINID='IV11D6';
NODE_NAME     U25W4 G7
 '@BASEBOARD_FAB2_LIB.BASEBOARD_FAB2(SCH_1):PAGE148_I28@W_HDL.AST2520A1-GP-GP(CHIPS)':
 'IV11D7': CDS_PINID='IV11D7';
NODE_NAME     U25W4 G8
 '@BASEBOARD_FAB2_LIB.BASEBOARD_FAB2(SCH_1):PAGE148_I28@W_HDL.AST2520A1-GP-GP(CHIPS)':
 'IV11D8': CDS_PINID='IV11D8';
NODE_NAME     U25W4 G9
 '@BASEBOARD_FAB2_LIB.BASEBOARD_FAB2(SCH_1):PAGE148_I28@W_HDL.AST2520A1-GP-GP(CHIPS)':
 'IV11D9': CDS_PINID='IV11D9';
NODE_NAME     U25W4 H16
 '@BASEBOARD_FAB2_LIB.BASEBOARD_FAB2(SCH_1):PAGE148_I28@W_HDL.AST2520A1-GP-GP(CHIPS)':
 'IV11D10': CDS_PINID='IV11D10';
NODE_NAME     U25W4 J16
 '@BASEBOARD_FAB2_LIB.BASEBOARD_FAB2(SCH_1):PAGE148_I28@W_HDL.AST2520A1-GP-GP(CHIPS)':
 'IV11D11': CDS_PINID='IV11D11';
NODE_NAME     U25W4 L7
 '@BASEBOARD_FAB2_LIB.BASEBOARD_FAB2(SCH_1):PAGE148_I28@W_HDL.AST2520A1-GP-GP(CHIPS)':
 'IV11D12': CDS_PINID='IV11D12';
NODE_NAME     U25W4 N16
 '@BASEBOARD_FAB2_LIB.BASEBOARD_FAB2(SCH_1):PAGE148_I28@W_HDL.AST2520A1-GP-GP(CHIPS)':
 'IV11D13': CDS_PINID='IV11D13';
NODE_NAME     U25W4 N7
 '@BASEBOARD_FAB2_LIB.BASEBOARD_FAB2(SCH_1):PAGE148_I28@W_HDL.AST2520A1-GP-GP(CHIPS)':
 'IV11D14': CDS_PINID='IV11D14';
NODE_NAME     U25W4 P10
 '@BASEBOARD_FAB2_LIB.BASEBOARD_FAB2(SCH_1):PAGE148_I28@W_HDL.AST2520A1-GP-GP(CHIPS)':
 'IV11D15': CDS_PINID='IV11D15';
NODE_NAME     U25W4 P11
 '@BASEBOARD_FAB2_LIB.BASEBOARD_FAB2(SCH_1):PAGE148_I28@W_HDL.AST2520A1-GP-GP(CHIPS)':
 'IV11D16': CDS_PINID='IV11D16';
NODE_NAME     U25W4 P12
 '@BASEBOARD_FAB2_LIB.BASEBOARD_FAB2(SCH_1):PAGE148_I28@W_HDL.AST2520A1-GP-GP(CHIPS)':
 'IV11D17': CDS_PINID='IV11D17';
NODE_NAME     U25W4 P13
 '@BASEBOARD_FAB2_LIB.BASEBOARD_FAB2(SCH_1):PAGE148_I28@W_HDL.AST2520A1-GP-GP(CHIPS)':
 'IV11D18': CDS_PINID='IV11D18';
NODE_NAME     U25W4 P14
 '@BASEBOARD_FAB2_LIB.BASEBOARD_FAB2(SCH_1):PAGE148_I28@W_HDL.AST2520A1-GP-GP(CHIPS)':
 'IV11D19': CDS_PINID='IV11D19';
NODE_NAME     U25W4 P16
 '@BASEBOARD_FAB2_LIB.BASEBOARD_FAB2(SCH_1):PAGE148_I28@W_HDL.AST2520A1-GP-GP(CHIPS)':
 'IV11D20': CDS_PINID='IV11D20';
NODE_NAME     U25W4 P7
 '@BASEBOARD_FAB2_LIB.BASEBOARD_FAB2(SCH_1):PAGE148_I28@W_HDL.AST2520A1-GP-GP(CHIPS)':
 'IV11D21': CDS_PINID='IV11D21';
NODE_NAME     U25W4 P9
 '@BASEBOARD_FAB2_LIB.BASEBOARD_FAB2(SCH_1):PAGE148_I28@W_HDL.AST2520A1-GP-GP(CHIPS)':
 'IV11D22': CDS_PINID='IV11D22';
NODE_NAME     U25W4 R16
 '@BASEBOARD_FAB2_LIB.BASEBOARD_FAB2(SCH_1):PAGE148_I28@W_HDL.AST2520A1-GP-GP(CHIPS)':
 'IV11D23': CDS_PINID='IV11D23';
NODE_NAME     U25W4 R7
 '@BASEBOARD_FAB2_LIB.BASEBOARD_FAB2(SCH_1):PAGE148_I28@W_HDL.AST2520A1-GP-GP(CHIPS)':
 'IV11D24': CDS_PINID='IV11D24';
NODE_NAME     U25W4 L17
 '@BASEBOARD_FAB2_LIB.BASEBOARD_FAB2(SCH_1):PAGE148_I28@W_HDL.AST2520A1-GP-GP(CHIPS)':
 'PEAV11': CDS_PINID='PEAV11';
NODE_NAME     U25W4 V17
 '@BASEBOARD_FAB2_LIB.BASEBOARD_FAB2(SCH_1):PAGE148_I28@W_HDL.AST2520A1-GP-GP(CHIPS)':
 'PLLDV11': CDS_PINID='PLLDV11';
NODE_NAME     FB2T7 1
 '@BASEBOARD_FAB2_LIB.BASEBOARD_FAB2(SCH_1):PAGE149_I42@W_HDL.HCB1608KF-800T30-GP(CHIPS)':
 '1': CDS_PINID='\1\';
NODE_NAME     C25W30 1
 '@BASEBOARD_FAB2_LIB.BASEBOARD_FAB2(SCH_1):PAGE149_I1@MSTR_DISCRETE.CAP(CHIPS)':
 'A': CDS_PINID='A';
NODE_NAME     C25W23 1
 '@BASEBOARD_FAB2_LIB.BASEBOARD_FAB2(SCH_1):PAGE149_I103@MSTR_DISCRETE.CAP(CHIPS)':
 'A': CDS_PINID='A';
NODE_NAME     C25W24 1
 '@BASEBOARD_FAB2_LIB.BASEBOARD_FAB2(SCH_1):PAGE149_I104@MSTR_DISCRETE.CAP(CHIPS)':
 'A': CDS_PINID='A';
NODE_NAME     C25W25 1
 '@BASEBOARD_FAB2_LIB.BASEBOARD_FAB2(SCH_1):PAGE149_I105@MSTR_DISCRETE.CAP(CHIPS)':
 'A': CDS_PINID='A';
NODE_NAME     C25W26 1
 '@BASEBOARD_FAB2_LIB.BASEBOARD_FAB2(SCH_1):PAGE149_I106@MSTR_DISCRETE.CAP(CHIPS)':
 'A': CDS_PINID='A';
NODE_NAME     C25W27 1
 '@BASEBOARD_FAB2_LIB.BASEBOARD_FAB2(SCH_1):PAGE149_I107@MSTR_DISCRETE.CAP(CHIPS)':
 'A': CDS_PINID='A';
NODE_NAME     C25W28 1
 '@BASEBOARD_FAB2_LIB.BASEBOARD_FAB2(SCH_1):PAGE149_I108@MSTR_DISCRETE.CAP(CHIPS)':
 'A': CDS_PINID='A';
NODE_NAME     C25W29 1
 '@BASEBOARD_FAB2_LIB.BASEBOARD_FAB2(SCH_1):PAGE149_I129@MSTR_DISCRETE.CAP(CHIPS)':
 'A': CDS_PINID='A';
NODE_NAME     C9W16 1
 '@BASEBOARD_FAB2_LIB.BASEBOARD_FAB2(SCH_1):PAGE238_I50@DEV_DISCRETE.CAP_A(CHIPS)':
 'A': CDS_PINID='A';
NET_NAME
'P1V2_AUX_BMC'
 '@BASEBOARD_FAB2_LIB.BASEBOARD_FAB2(SCH_1):P1V2_AUX_BMC':
 C_SIGNAL='@baseboard_fab2_lib.baseboard_fab2(sch_1):p1v2_aux_bmc';
NODE_NAME     C9F13 1
 '@BASEBOARD_FAB2_LIB.BASEBOARD_FAB2(SCH_1):PAGE239_I7@MSTR_DISCRETE.CAP(CHIPS)':
 'A': CDS_PINID='A';
NODE_NAME     C1T15 1
 '@BASEBOARD_FAB2_LIB.BASEBOARD_FAB2(SCH_1):PAGE239_I12@MSTR_DISCRETE.CAP(CHIPS)':
 'A': CDS_PINID='A';
NODE_NAME     EU9F2 1
 '@BASEBOARD_FAB2_LIB.BASEBOARD_FAB2(SCH_1):PAGE239_I70@MSTR_VREG.RT9059(CHIPS)':
 'VOUT'<0>: CDS_PINID='VOUT(0)';
NODE_NAME     EU9F2 2
 '@BASEBOARD_FAB2_LIB.BASEBOARD_FAB2(SCH_1):PAGE239_I70@MSTR_VREG.RT9059(CHIPS)':
 'VOUT'<1>: CDS_PINID='VOUT(1)';
NODE_NAME     EU9F2 3
 '@BASEBOARD_FAB2_LIB.BASEBOARD_FAB2(SCH_1):PAGE239_I70@MSTR_VREG.RT9059(CHIPS)':
 'VOUT'<2>: CDS_PINID='VOUT(2)';
NODE_NAME     R9F31 1
 '@BASEBOARD_FAB2_LIB.BASEBOARD_FAB2(SCH_1):PAGE239_I98@W_HDL.5K1R2F-2-GP(CHIPS)':
 '1': CDS_PINID='\1\';
NODE_NAME     U25W4 T10
 '@BASEBOARD_FAB2_LIB.BASEBOARD_FAB2(SCH_1):PAGE148_I28@W_HDL.AST2520A1-GP-GP(CHIPS)':
 'MVDD0': CDS_PINID='MVDD0';
NODE_NAME     U25W4 T12
 '@BASEBOARD_FAB2_LIB.BASEBOARD_FAB2(SCH_1):PAGE148_I28@W_HDL.AST2520A1-GP-GP(CHIPS)':
 'MVDD1': CDS_PINID='MVDD1';
NODE_NAME     U25W4 T13
 '@BASEBOARD_FAB2_LIB.BASEBOARD_FAB2(SCH_1):PAGE148_I28@W_HDL.AST2520A1-GP-GP(CHIPS)':
 'MVDD2': CDS_PINID='MVDD2';
NODE_NAME     U25W4 T14
 '@BASEBOARD_FAB2_LIB.BASEBOARD_FAB2(SCH_1):PAGE148_I28@W_HDL.AST2520A1-GP-GP(CHIPS)':
 'MVDD3': CDS_PINID='MVDD3';
NODE_NAME     U25W4 T8
 '@BASEBOARD_FAB2_LIB.BASEBOARD_FAB2(SCH_1):PAGE148_I28@W_HDL.AST2520A1-GP-GP(CHIPS)':
 'MVDD4': CDS_PINID='MVDD4';
NODE_NAME     U25W5 B3
 '@BASEBOARD_FAB2_LIB.BASEBOARD_FAB2(SCH_1):PAGE151_I49@W_HDL.H5AN4G6NAFR-TFC-GP(CHIPS)':
 'VDD'<0>: CDS_PINID='VDD(0)';
NODE_NAME     U25W5 B9
 '@BASEBOARD_FAB2_LIB.BASEBOARD_FAB2(SCH_1):PAGE151_I49@W_HDL.H5AN4G6NAFR-TFC-GP(CHIPS)':
 'VDD'<1>: CDS_PINID='VDD(1)';
NODE_NAME     U25W5 D1
 '@BASEBOARD_FAB2_LIB.BASEBOARD_FAB2(SCH_1):PAGE151_I49@W_HDL.H5AN4G6NAFR-TFC-GP(CHIPS)':
 'VDD'<2>: CDS_PINID='VDD(2)';
NODE_NAME     U25W5 G7
 '@BASEBOARD_FAB2_LIB.BASEBOARD_FAB2(SCH_1):PAGE151_I49@W_HDL.H5AN4G6NAFR-TFC-GP(CHIPS)':
 'VDD'<3>: CDS_PINID='VDD(3)';
NODE_NAME     U25W5 J1
 '@BASEBOARD_FAB2_LIB.BASEBOARD_FAB2(SCH_1):PAGE151_I49@W_HDL.H5AN4G6NAFR-TFC-GP(CHIPS)':
 'VDD'<4>: CDS_PINID='VDD(4)';
NODE_NAME     U25W5 J9
 '@BASEBOARD_FAB2_LIB.BASEBOARD_FAB2(SCH_1):PAGE151_I49@W_HDL.H5AN4G6NAFR-TFC-GP(CHIPS)':
 'VDD'<5>: CDS_PINID='VDD(5)';
NODE_NAME     U25W5 L1
 '@BASEBOARD_FAB2_LIB.BASEBOARD_FAB2(SCH_1):PAGE151_I49@W_HDL.H5AN4G6NAFR-TFC-GP(CHIPS)':
 'VDD'<6>: CDS_PINID='VDD(6)';
NODE_NAME     U25W5 L9
 '@BASEBOARD_FAB2_LIB.BASEBOARD_FAB2(SCH_1):PAGE151_I49@W_HDL.H5AN4G6NAFR-TFC-GP(CHIPS)':
 'VDD'<7>: CDS_PINID='VDD(7)';
NODE_NAME     U25W5 R1
 '@BASEBOARD_FAB2_LIB.BASEBOARD_FAB2(SCH_1):PAGE151_I49@W_HDL.H5AN4G6NAFR-TFC-GP(CHIPS)':
 'VDD'<8>: CDS_PINID='VDD(8)';
NODE_NAME     U25W5 T9
 '@BASEBOARD_FAB2_LIB.BASEBOARD_FAB2(SCH_1):PAGE151_I49@W_HDL.H5AN4G6NAFR-TFC-GP(CHIPS)':
 'VDD'<9>: CDS_PINID='VDD(9)';
NODE_NAME     U25W5 A1
 '@BASEBOARD_FAB2_LIB.BASEBOARD_FAB2(SCH_1):PAGE151_I49@W_HDL.H5AN4G6NAFR-TFC-GP(CHIPS)':
 'VDDQ'<0>: CDS_PINID='VDDQ(0)';
NODE_NAME     U25W5 A9
 '@BASEBOARD_FAB2_LIB.BASEBOARD_FAB2(SCH_1):PAGE151_I49@W_HDL.H5AN4G6NAFR-TFC-GP(CHIPS)':
 'VDDQ'<1>: CDS_PINID='VDDQ(1)';
NODE_NAME     U25W5 C1
 '@BASEBOARD_FAB2_LIB.BASEBOARD_FAB2(SCH_1):PAGE151_I49@W_HDL.H5AN4G6NAFR-TFC-GP(CHIPS)':
 'VDDQ'<2>: CDS_PINID='VDDQ(2)';
NODE_NAME     U25W5 D9
 '@BASEBOARD_FAB2_LIB.BASEBOARD_FAB2(SCH_1):PAGE151_I49@W_HDL.H5AN4G6NAFR-TFC-GP(CHIPS)':
 'VDDQ'<3>: CDS_PINID='VDDQ(3)';
NODE_NAME     U25W5 F2
 '@BASEBOARD_FAB2_LIB.BASEBOARD_FAB2(SCH_1):PAGE151_I49@W_HDL.H5AN4G6NAFR-TFC-GP(CHIPS)':
 'VDDQ'<4>: CDS_PINID='VDDQ(4)';
NODE_NAME     U25W5 F8
 '@BASEBOARD_FAB2_LIB.BASEBOARD_FAB2(SCH_1):PAGE151_I49@W_HDL.H5AN4G6NAFR-TFC-GP(CHIPS)':
 'VDDQ'<5>: CDS_PINID='VDDQ(5)';
NODE_NAME     U25W5 G1
 '@BASEBOARD_FAB2_LIB.BASEBOARD_FAB2(SCH_1):PAGE151_I49@W_HDL.H5AN4G6NAFR-TFC-GP(CHIPS)':
 'VDDQ'<6>: CDS_PINID='VDDQ(6)';
NODE_NAME     U25W5 G9
 '@BASEBOARD_FAB2_LIB.BASEBOARD_FAB2(SCH_1):PAGE151_I49@W_HDL.H5AN4G6NAFR-TFC-GP(CHIPS)':
 'VDDQ'<7>: CDS_PINID='VDDQ(7)';
NODE_NAME     U25W5 J2
 '@BASEBOARD_FAB2_LIB.BASEBOARD_FAB2(SCH_1):PAGE151_I49@W_HDL.H5AN4G6NAFR-TFC-GP(CHIPS)':
 'VDDQ'<8>: CDS_PINID='VDDQ(8)';
NODE_NAME     U25W5 J8
 '@BASEBOARD_FAB2_LIB.BASEBOARD_FAB2(SCH_1):PAGE151_I49@W_HDL.H5AN4G6NAFR-TFC-GP(CHIPS)':
 'VDDQ'<9>: CDS_PINID='VDDQ(9)';
NODE_NAME     R9F29 1
 '@BASEBOARD_FAB2_LIB.BASEBOARD_FAB2(SCH_1):PAGE151_I55@MSTR_DISCRETE.RES(CHIPS)':
 'A': CDS_PINID='A';
NODE_NAME     C25W16 1
 '@BASEBOARD_FAB2_LIB.BASEBOARD_FAB2(SCH_1):PAGE151_I58@MSTR_DISCRETE.CAP(CHIPS)':
 'A': CDS_PINID='A';
NODE_NAME     C25W17 1
 '@BASEBOARD_FAB2_LIB.BASEBOARD_FAB2(SCH_1):PAGE151_I120@W_HDL.SC1U16V3KX-2GP(CHIPS)':
 '1': CDS_PINID='\1\';
NODE_NAME     C25W18 1
 '@BASEBOARD_FAB2_LIB.BASEBOARD_FAB2(SCH_1):PAGE151_I121@W_HDL.SC1U16V3KX-2GP(CHIPS)':
 '1': CDS_PINID='\1\';
NODE_NAME     C25W19 1
 '@BASEBOARD_FAB2_LIB.BASEBOARD_FAB2(SCH_1):PAGE151_I123@MSTR_DISCRETE.CAP(CHIPS)':
 'A': CDS_PINID='A';
NODE_NAME     C25W1 1
 '@BASEBOARD_FAB2_LIB.BASEBOARD_FAB2(SCH_1):PAGE151_I125@MSTR_DISCRETE.CAP(CHIPS)':
 'A': CDS_PINID='A';
NODE_NAME     C25W2 1
 '@BASEBOARD_FAB2_LIB.BASEBOARD_FAB2(SCH_1):PAGE151_I139@MSTR_DISCRETE.CAP(CHIPS)':
 'A': CDS_PINID='A';
NODE_NAME     C25W3 1
 '@BASEBOARD_FAB2_LIB.BASEBOARD_FAB2(SCH_1):PAGE151_I140@MSTR_DISCRETE.CAP(CHIPS)':
 'A': CDS_PINID='A';
NODE_NAME     C25W4 1
 '@BASEBOARD_FAB2_LIB.BASEBOARD_FAB2(SCH_1):PAGE151_I141@MSTR_DISCRETE.CAP(CHIPS)':
 'A': CDS_PINID='A';
NODE_NAME     C25W5 1
 '@BASEBOARD_FAB2_LIB.BASEBOARD_FAB2(SCH_1):PAGE151_I142@MSTR_DISCRETE.CAP(CHIPS)':
 'A': CDS_PINID='A';
NODE_NAME     C25W6 1
 '@BASEBOARD_FAB2_LIB.BASEBOARD_FAB2(SCH_1):PAGE151_I143@MSTR_DISCRETE.CAP(CHIPS)':
 'A': CDS_PINID='A';
NODE_NAME     R1T30 1
 '@BASEBOARD_FAB2_LIB.BASEBOARD_FAB2(SCH_1):PAGE151_I201@MSTR_DISCRETE.RES(CHIPS)':
 'A': CDS_PINID='A';
NODE_NAME     C25W53 1
 '@BASEBOARD_FAB2_LIB.BASEBOARD_FAB2(SCH_1):PAGE149_I92@MSTR_DISCRETE.CAP(CHIPS)':
 'A': CDS_PINID='A';
NODE_NAME     C25W54 1
 '@BASEBOARD_FAB2_LIB.BASEBOARD_FAB2(SCH_1):PAGE149_I95@MSTR_DISCRETE.CAP(CHIPS)':
 'A': CDS_PINID='A';
NODE_NAME     C25W51 1
 '@BASEBOARD_FAB2_LIB.BASEBOARD_FAB2(SCH_1):PAGE149_I114@MSTR_DISCRETE.CAP(CHIPS)':
 'A': CDS_PINID='A';
NODE_NAME     C25W52 1
 '@BASEBOARD_FAB2_LIB.BASEBOARD_FAB2(SCH_1):PAGE149_I118@MSTR_DISCRETE.CAP(CHIPS)':
 'A': CDS_PINID='A';
NODE_NAME     R25W119 1
 '@BASEBOARD_FAB2_LIB.BASEBOARD_FAB2(SCH_1):PAGE151_I210@MSTR_DISCRETE.RES(CHIPS)':
 'A': CDS_PINID='A';
NODE_NAME     C25W10 1
 '@BASEBOARD_FAB2_LIB.BASEBOARD_FAB2(SCH_1):PAGE151_I213@DEV_DISCRETE.CAP_A(CHIPS)':
 'A': CDS_PINID='A';
NODE_NAME     C25W55 1
 '@BASEBOARD_FAB2_LIB.BASEBOARD_FAB2(SCH_1):PAGE149_I124@DEV_DISCRETE.CAP_A(CHIPS)':
 'A': CDS_PINID='A';
NODE_NAME     R25W30 2
 '@BASEBOARD_FAB2_LIB.BASEBOARD_FAB2(SCH_1):PAGE151_I222@MSTR_DISCRETE.RES(CHIPS)':
 'B': CDS_PINID='B';
NODE_NAME     R25W27 2
 '@BASEBOARD_FAB2_LIB.BASEBOARD_FAB2(SCH_1):PAGE151_I223@W_HDL.120R2F-GP(CHIPS)':
 '2': CDS_PINID='\2\';
NODE_NAME     R25W28 2
 '@BASEBOARD_FAB2_LIB.BASEBOARD_FAB2(SCH_1):PAGE151_I224@W_HDL.120R2F-GP(CHIPS)':
 '2': CDS_PINID='\2\';
NODE_NAME     R25W29 2
 '@BASEBOARD_FAB2_LIB.BASEBOARD_FAB2(SCH_1):PAGE151_I225@W_HDL.120R2F-GP(CHIPS)':
 '2': CDS_PINID='\2\';
NODE_NAME     R25W31 2
 '@BASEBOARD_FAB2_LIB.BASEBOARD_FAB2(SCH_1):PAGE151_I226@W_HDL.120R2F-GP(CHIPS)':
 '2': CDS_PINID='\2\';
NODE_NAME     R25W32 2
 '@BASEBOARD_FAB2_LIB.BASEBOARD_FAB2(SCH_1):PAGE151_I227@W_HDL.120R2F-GP(CHIPS)':
 '2': CDS_PINID='\2\';
NODE_NAME     R25W33 2
 '@BASEBOARD_FAB2_LIB.BASEBOARD_FAB2(SCH_1):PAGE151_I228@W_HDL.120R2F-GP(CHIPS)':
 '2': CDS_PINID='\2\';
NODE_NAME     R25W34 2
 '@BASEBOARD_FAB2_LIB.BASEBOARD_FAB2(SCH_1):PAGE151_I229@W_HDL.120R2F-GP(CHIPS)':
 '2': CDS_PINID='\2\';
NODE_NAME     R25W35 2
 '@BASEBOARD_FAB2_LIB.BASEBOARD_FAB2(SCH_1):PAGE151_I230@W_HDL.120R2F-GP(CHIPS)':
 '2': CDS_PINID='\2\';
NODE_NAME     R25W36 2
 '@BASEBOARD_FAB2_LIB.BASEBOARD_FAB2(SCH_1):PAGE151_I231@W_HDL.120R2F-GP(CHIPS)':
 '2': CDS_PINID='\2\';
NODE_NAME     R25W37 2
 '@BASEBOARD_FAB2_LIB.BASEBOARD_FAB2(SCH_1):PAGE151_I232@W_HDL.120R2F-GP(CHIPS)':
 '2': CDS_PINID='\2\';
NODE_NAME     R25W38 2
 '@BASEBOARD_FAB2_LIB.BASEBOARD_FAB2(SCH_1):PAGE151_I233@W_HDL.120R2F-GP(CHIPS)':
 '2': CDS_PINID='\2\';
NODE_NAME     R25W39 2
 '@BASEBOARD_FAB2_LIB.BASEBOARD_FAB2(SCH_1):PAGE151_I234@W_HDL.120R2F-GP(CHIPS)':
 '2': CDS_PINID='\2\';
NODE_NAME     R25W41 2
 '@BASEBOARD_FAB2_LIB.BASEBOARD_FAB2(SCH_1):PAGE151_I235@W_HDL.120R2F-GP(CHIPS)':
 '2': CDS_PINID='\2\';
NODE_NAME     R25W42 2
 '@BASEBOARD_FAB2_LIB.BASEBOARD_FAB2(SCH_1):PAGE151_I236@W_HDL.120R2F-GP(CHIPS)':
 '2': CDS_PINID='\2\';
NODE_NAME     R25W44 2
 '@BASEBOARD_FAB2_LIB.BASEBOARD_FAB2(SCH_1):PAGE151_I237@W_HDL.120R2F-GP(CHIPS)':
 '2': CDS_PINID='\2\';
NODE_NAME     R25W43 2
 '@BASEBOARD_FAB2_LIB.BASEBOARD_FAB2(SCH_1):PAGE151_I238@W_HDL.120R2F-GP(CHIPS)':
 '2': CDS_PINID='\2\';
NODE_NAME     R25W47 2
 '@BASEBOARD_FAB2_LIB.BASEBOARD_FAB2(SCH_1):PAGE151_I239@W_HDL.120R2F-GP(CHIPS)':
 '2': CDS_PINID='\2\';
NODE_NAME     R25W48 2
 '@BASEBOARD_FAB2_LIB.BASEBOARD_FAB2(SCH_1):PAGE151_I240@W_HDL.120R2F-GP(CHIPS)':
 '2': CDS_PINID='\2\';
NODE_NAME     R25W46 2
 '@BASEBOARD_FAB2_LIB.BASEBOARD_FAB2(SCH_1):PAGE151_I241@W_HDL.120R2F-GP(CHIPS)':
 '2': CDS_PINID='\2\';
NODE_NAME     R25W45 2
 '@BASEBOARD_FAB2_LIB.BASEBOARD_FAB2(SCH_1):PAGE151_I242@W_HDL.120R2F-GP(CHIPS)':
 '2': CDS_PINID='\2\';
NODE_NAME     R25W49 2
 '@BASEBOARD_FAB2_LIB.BASEBOARD_FAB2(SCH_1):PAGE151_I243@W_HDL.120R2F-GP(CHIPS)':
 '2': CDS_PINID='\2\';
NODE_NAME     R25W50 2
 '@BASEBOARD_FAB2_LIB.BASEBOARD_FAB2(SCH_1):PAGE151_I244@W_HDL.120R2F-GP(CHIPS)':
 '2': CDS_PINID='\2\';
NODE_NAME     R25W51 2
 '@BASEBOARD_FAB2_LIB.BASEBOARD_FAB2(SCH_1):PAGE151_I245@W_HDL.120R2F-GP(CHIPS)':
 '2': CDS_PINID='\2\';
NODE_NAME     R25W52 2
 '@BASEBOARD_FAB2_LIB.BASEBOARD_FAB2(SCH_1):PAGE151_I246@W_HDL.120R2F-GP(CHIPS)':
 '2': CDS_PINID='\2\';
NODE_NAME     R25W40 2
 '@BASEBOARD_FAB2_LIB.BASEBOARD_FAB2(SCH_1):PAGE151_I247@W_HDL.120R2F-GP(CHIPS)':
 '2': CDS_PINID='\2\';
NODE_NAME     C9W19 1
 '@BASEBOARD_FAB2_LIB.BASEBOARD_FAB2(SCH_1):PAGE239_I111@DEV_DISCRETE.CAP_A(CHIPS)':
 'A': CDS_PINID='A';
NET_NAME
'P1V5_LAN'
 '@BASEBOARD_FAB2_LIB.BASEBOARD_FAB2(SCH_1):P1V5_LAN':
 C_SIGNAL='@baseboard_fab2_lib.baseboard_fab2(sch_1):p1v5_lan';
NODE_NAME     EU9E1 47
 '@BASEBOARD_FAB2_LIB.BASEBOARD_FAB2(SCH_1):PAGE139_I72@MSTR_INTEL.SPRINGVILLE(CHIPS)':
 'VDD1P5'<1>: CDS_PINID='VDD1P5(1)';
NODE_NAME     EU9E1 39
 '@BASEBOARD_FAB2_LIB.BASEBOARD_FAB2(SCH_1):PAGE139_I72@MSTR_INTEL.SPRINGVILLE(CHIPS)':
 'VDD1P5_OUT': CDS_PINID='VDD1P5_OUT';
NODE_NAME     C1R30 1
 '@BASEBOARD_FAB2_LIB.BASEBOARD_FAB2(SCH_1):PAGE139_I135@MSTR_DISCRETE.CAP(CHIPS)':
 'A': CDS_PINID='A';
NODE_NAME     C1R26 1
 '@BASEBOARD_FAB2_LIB.BASEBOARD_FAB2(SCH_1):PAGE139_I149@DEV_DISCRETE.CAP_A(CHIPS)':
 'A': CDS_PINID='A';
NODE_NAME     C1R29 1
 '@BASEBOARD_FAB2_LIB.BASEBOARD_FAB2(SCH_1):PAGE139_I150@DEV_DISCRETE.CAP_A(CHIPS)':
 'A': CDS_PINID='A';
NODE_NAME     C1R19 1
 '@BASEBOARD_FAB2_LIB.BASEBOARD_FAB2(SCH_1):PAGE139_I151@DEV_DISCRETE.CAP_A(CHIPS)':
 'A': CDS_PINID='A';
NODE_NAME     C1R31 1
 '@BASEBOARD_FAB2_LIB.BASEBOARD_FAB2(SCH_1):PAGE139_I152@DEV_DISCRETE.CAP_A(CHIPS)':
 'A': CDS_PINID='A';
NODE_NAME     C1R17 1
 '@BASEBOARD_FAB2_LIB.BASEBOARD_FAB2(SCH_1):PAGE139_I153@MSTR_DISCRETE.CAP(CHIPS)':
 'A': CDS_PINID='A';
NODE_NAME     R1T32 1
 '@BASEBOARD_FAB2_LIB.BASEBOARD_FAB2(SCH_1):PAGE139_I238@MSTR_DISCRETE.RES(CHIPS)':
 'A': CDS_PINID='A';
NODE_NAME     R1T33 1
 '@BASEBOARD_FAB2_LIB.BASEBOARD_FAB2(SCH_1):PAGE139_I240@MSTR_DISCRETE.RES(CHIPS)':
 'A': CDS_PINID='A';
NODE_NAME     C22W35 1
 '@BASEBOARD_FAB2_LIB.BASEBOARD_FAB2(SCH_1):PAGE139_I246@W_HDL.SC22U16V5MX-4-GP(CHIPS)':
 '1': CDS_PINID='\1\';
NODE_NAME     C9E6 1
 '@BASEBOARD_FAB2_LIB.BASEBOARD_FAB2(SCH_1):PAGE139_I248@W_HDL.SC22U16V5MX-4-GP(CHIPS)':
 '1': CDS_PINID='\1\';
NET_NAME
'P1V5_LAN_I210'
 '@BASEBOARD_FAB2_LIB.BASEBOARD_FAB2(SCH_1):P1V5_LAN_I210':
 C_SIGNAL='@baseboard_fab2_lib.baseboard_fab2(sch_1):p1v5_lan_i210';
NODE_NAME     EU9E1 56
 '@BASEBOARD_FAB2_LIB.BASEBOARD_FAB2(SCH_1):PAGE139_I72@MSTR_INTEL.SPRINGVILLE(CHIPS)':
 'VDD1P5'<0>: CDS_PINID='VDD1P5(0)';
NODE_NAME     R1T32 2
 '@BASEBOARD_FAB2_LIB.BASEBOARD_FAB2(SCH_1):PAGE139_I238@MSTR_DISCRETE.RES(CHIPS)':
 'B': CDS_PINID='B';
NET_NAME
'P1V8_M2'
 '@BASEBOARD_FAB2_LIB.BASEBOARD_FAB2(SCH_1):P1V8_M2':
 C_SIGNAL='@baseboard_fab2_lib.baseboard_fab2(sch_1):p1v8_m2';
NODE_NAME     C32W1 1
 '@BASEBOARD_FAB2_LIB.BASEBOARD_FAB2(SCH_1):PAGE185_I188@DEV_DISCRETE.CAP_A(CHIPS)':
 'A': CDS_PINID='A';
NODE_NAME     C32W3 1
 '@BASEBOARD_FAB2_LIB.BASEBOARD_FAB2(SCH_1):PAGE185_I190@DEV_DISCRETE.CAP_A(CHIPS)':
 'A': CDS_PINID='A';
NODE_NAME     U32W1 1
 '@BASEBOARD_FAB2_LIB.BASEBOARD_FAB2(SCH_1):PAGE185_I191@W_HDL.TCA9517DGKR-GP(CHIPS)':
 'VCCA': CDS_PINID='VCCA';
NODE_NAME     U32W2 1
 '@BASEBOARD_FAB2_LIB.BASEBOARD_FAB2(SCH_1):PAGE185_I204@W_HDL.TCA9517DGKR-GP(CHIPS)':
 'VCCA': CDS_PINID='VCCA';
NODE_NAME     R32W2 1
 '@BASEBOARD_FAB2_LIB.BASEBOARD_FAB2(SCH_1):PAGE185_I207@MSTR_DISCRETE.RES(CHIPS)':
 'A': CDS_PINID='A';
NODE_NAME     R32W1 2
 '@BASEBOARD_FAB2_LIB.BASEBOARD_FAB2(SCH_1):PAGE185_I208@MSTR_DISCRETE.RES(CHIPS)':
 'B': CDS_PINID='B';
NODE_NAME     R32W4 1
 '@BASEBOARD_FAB2_LIB.BASEBOARD_FAB2(SCH_1):PAGE185_I211@MSTR_DISCRETE.RES(CHIPS)':
 'A': CDS_PINID='A';
NODE_NAME     VR32W1 2
 '@BASEBOARD_FAB2_LIB.BASEBOARD_FAB2(SCH_1):PAGE185_I213@W_HDL.LMV431AIMFX-GP(CHIPS)':
 'CATHODE': CDS_PINID='CATHODE';
NODE_NAME     R32W6 1
 '@BASEBOARD_FAB2_LIB.BASEBOARD_FAB2(SCH_1):PAGE185_I214@MSTR_DISCRETE.RES(CHIPS)':
 'A': CDS_PINID='A';
NODE_NAME     R32W7 1
 '@BASEBOARD_FAB2_LIB.BASEBOARD_FAB2(SCH_1):PAGE185_I215@MSTR_DISCRETE.RES(CHIPS)':
 'A': CDS_PINID='A';
NODE_NAME     R32W5 1
 '@BASEBOARD_FAB2_LIB.BASEBOARD_FAB2(SCH_1):PAGE185_I216@MSTR_DISCRETE.RES(CHIPS)':
 'A': CDS_PINID='A';
NODE_NAME     C32W5 1
 '@BASEBOARD_FAB2_LIB.BASEBOARD_FAB2(SCH_1):PAGE185_I217@MSTR_DISCRETE.CAP(CHIPS)':
 'A': CDS_PINID='A';
NET_NAME
'P1V8_MCP_CPU0'
 '@BASEBOARD_FAB2_LIB.BASEBOARD_FAB2(SCH_1):P1V8_MCP_CPU0':
 C_SIGNAL='@baseboard_fab2_lib.baseboard_fab2(sch_1):p1v8_mcp_cpu0';
NODE_NAME     U5D1 B17
 '@BASEBOARD_FAB2_LIB.BASEBOARD_FAB2(SCH_1):PAGE22_I204@CHPSET_LIB.SKX_EXT_B(CHIPS)':
 'RSVD'<294>: CDS_PINID='RSVD(294)';
NODE_NAME     U5D1 B15
 '@BASEBOARD_FAB2_LIB.BASEBOARD_FAB2(SCH_1):PAGE22_I204@CHPSET_LIB.SKX_EXT_B(CHIPS)':
 'RSVD'<295>: CDS_PINID='RSVD(295)';
NODE_NAME     U5D1 B13
 '@BASEBOARD_FAB2_LIB.BASEBOARD_FAB2(SCH_1):PAGE22_I204@CHPSET_LIB.SKX_EXT_B(CHIPS)':
 'RSVD'<296>: CDS_PINID='RSVD(296)';
NODE_NAME     U5D1 A16
 '@BASEBOARD_FAB2_LIB.BASEBOARD_FAB2(SCH_1):PAGE22_I204@CHPSET_LIB.SKX_EXT_B(CHIPS)':
 'RSVD'<301>: CDS_PINID='RSVD(301)';
NODE_NAME     U5D1 A14
 '@BASEBOARD_FAB2_LIB.BASEBOARD_FAB2(SCH_1):PAGE22_I204@CHPSET_LIB.SKX_EXT_B(CHIPS)':
 'RSVD'<302>: CDS_PINID='RSVD(302)';
NODE_NAME     C6D1 1
 '@BASEBOARD_FAB2_LIB.BASEBOARD_FAB2(SCH_1):PAGE38_I19@MSTR_DISCRETE.CAP(CHIPS)':
 'A': CDS_PINID='A';
NODE_NAME     U5D1 BT27
 '@BASEBOARD_FAB2_LIB.BASEBOARD_FAB2(SCH_1):PAGE38_I34@CHPSET_LIB.SKX_EXT_B(CHIPS)':
 'CD_VCCIN'<0>: CDS_PINID='CD_VCCIN(0)';
NODE_NAME     U5D1 BU26
 '@BASEBOARD_FAB2_LIB.BASEBOARD_FAB2(SCH_1):PAGE38_I34@CHPSET_LIB.SKX_EXT_B(CHIPS)':
 'CD_VCCIN'<1>: CDS_PINID='CD_VCCIN(1)';
NODE_NAME     U5D1 BV27
 '@BASEBOARD_FAB2_LIB.BASEBOARD_FAB2(SCH_1):PAGE38_I34@CHPSET_LIB.SKX_EXT_B(CHIPS)':
 'CD_VCCIN'<2>: CDS_PINID='CD_VCCIN(2)';
NODE_NAME     U5D1 BY27
 '@BASEBOARD_FAB2_LIB.BASEBOARD_FAB2(SCH_1):PAGE38_I34@CHPSET_LIB.SKX_EXT_B(CHIPS)':
 'CD_VCCIN'<3>: CDS_PINID='CD_VCCIN(3)';
NODE_NAME     C1M29 1
 '@BASEBOARD_FAB2_LIB.BASEBOARD_FAB2(SCH_1):PAGE113_I147@DEV_DISCRETE.CAP_A(CHIPS)':
 'A': CDS_PINID='A';
NODE_NAME     J9B4 4
 '@BASEBOARD_FAB2_LIB.BASEBOARD_FAB2(SCH_1):PAGE113_I175@MSTR_SCONN.SCONN10_C12536004(CHIPS)':
 'IO4': CDS_PINID='IO4';
NODE_NAME     U1M5 2
 '@BASEBOARD_FAB2_LIB.BASEBOARD_FAB2(SCH_1):PAGE113_I196@MSTR_TTL.74CBTLV1G125(CHIPS)':
 'A': CDS_PINID='A';
NODE_NAME     R1M19 1
 '@BASEBOARD_FAB2_LIB.BASEBOARD_FAB2(SCH_1):PAGE113_I202@MSTR_DISCRETE.RES(CHIPS)':
 'A': CDS_PINID='A';
NODE_NAME     R9B12 1
 '@BASEBOARD_FAB2_LIB.BASEBOARD_FAB2(SCH_1):PAGE113_I203@MSTR_DISCRETE.RES(CHIPS)':
 'A': CDS_PINID='A';
NODE_NAME     R1M20 1
 '@BASEBOARD_FAB2_LIB.BASEBOARD_FAB2(SCH_1):PAGE113_I204@MSTR_DISCRETE.RES(CHIPS)':
 'A': CDS_PINID='A';
NODE_NAME     R1M21 1
 '@BASEBOARD_FAB2_LIB.BASEBOARD_FAB2(SCH_1):PAGE113_I205@MSTR_DISCRETE.RES(CHIPS)':
 'A': CDS_PINID='A';
NODE_NAME     U4R1 2
 '@BASEBOARD_FAB2_LIB.BASEBOARD_FAB2(SCH_1):PAGE113_I206@MSTR_TTL.74CBTLV1G125(CHIPS)':
 'A': CDS_PINID='A';
NODE_NAME     C4T2 1
 '@BASEBOARD_FAB2_LIB.BASEBOARD_FAB2(SCH_1):PAGE194_I9@DEV_DISCRETE.CAP_A(CHIPS)':
 'A': CDS_PINID='A';
NODE_NAME     C4T1 1
 '@BASEBOARD_FAB2_LIB.BASEBOARD_FAB2(SCH_1):PAGE194_I16@DEV_DISCRETE.CAP_A(CHIPS)':
 'A': CDS_PINID='A';
NODE_NAME     J6E1 D3
 '@BASEBOARD_FAB2_LIB.BASEBOARD_FAB2(SCH_1):PAGE194_I55@MSTR_SCONN.SCONN120_H61426002(CHIPS)':
 'IOD3': CDS_PINID='IOD3';
NODE_NAME     J6E1 E1
 '@BASEBOARD_FAB2_LIB.BASEBOARD_FAB2(SCH_1):PAGE194_I55@MSTR_SCONN.SCONN120_H61426002(CHIPS)':
 'IOE1': CDS_PINID='IOE1';
NODE_NAME     J6E1 E2
 '@BASEBOARD_FAB2_LIB.BASEBOARD_FAB2(SCH_1):PAGE194_I55@MSTR_SCONN.SCONN120_H61426002(CHIPS)':
 'IOE2': CDS_PINID='IOE2';
NODE_NAME     J6E1 E3
 '@BASEBOARD_FAB2_LIB.BASEBOARD_FAB2(SCH_1):PAGE194_I55@MSTR_SCONN.SCONN120_H61426002(CHIPS)':
 'IOE3': CDS_PINID='IOE3';
NODE_NAME     J6E1 F1
 '@BASEBOARD_FAB2_LIB.BASEBOARD_FAB2(SCH_1):PAGE194_I55@MSTR_SCONN.SCONN120_H61426002(CHIPS)':
 'IOF1': CDS_PINID='IOF1';
NODE_NAME     J6E1 F2
 '@BASEBOARD_FAB2_LIB.BASEBOARD_FAB2(SCH_1):PAGE194_I55@MSTR_SCONN.SCONN120_H61426002(CHIPS)':
 'IOF2': CDS_PINID='IOF2';
NODE_NAME     J6E1 F3
 '@BASEBOARD_FAB2_LIB.BASEBOARD_FAB2(SCH_1):PAGE194_I55@MSTR_SCONN.SCONN120_H61426002(CHIPS)':
 'IOF3': CDS_PINID='IOF3';
NODE_NAME     C3T1 1
 '@BASEBOARD_FAB2_LIB.BASEBOARD_FAB2(SCH_1):PAGE194_I149@DEV_DISCRETE.CAP_A(CHIPS)':
 'A': CDS_PINID='A';
NODE_NAME     C3T2 1
 '@BASEBOARD_FAB2_LIB.BASEBOARD_FAB2(SCH_1):PAGE194_I150@DEV_DISCRETE.CAP_A(CHIPS)':
 'A': CDS_PINID='A';
NODE_NAME     R5W1 1
 '@BASEBOARD_FAB2_LIB.BASEBOARD_FAB2(SCH_1):PAGE113_I272@MSTR_DISCRETE.RES(CHIPS)':
 'A': CDS_PINID='A';
NET_NAME
'P1V8_MCP_CPU1'
 '@BASEBOARD_FAB2_LIB.BASEBOARD_FAB2(SCH_1):P1V8_MCP_CPU1':
 C_SIGNAL='@baseboard_fab2_lib.baseboard_fab2(sch_1):p1v8_mcp_cpu1';
NODE_NAME     U2D1 B17
 '@BASEBOARD_FAB2_LIB.BASEBOARD_FAB2(SCH_1):PAGE56_I169@CHPSET_LIB.SKX_EXT_B(CHIPS)':
 'RSVD'<294>: CDS_PINID='RSVD(294)';
NODE_NAME     U2D1 B15
 '@BASEBOARD_FAB2_LIB.BASEBOARD_FAB2(SCH_1):PAGE56_I169@CHPSET_LIB.SKX_EXT_B(CHIPS)':
 'RSVD'<295>: CDS_PINID='RSVD(295)';
NODE_NAME     U2D1 B13
 '@BASEBOARD_FAB2_LIB.BASEBOARD_FAB2(SCH_1):PAGE56_I169@CHPSET_LIB.SKX_EXT_B(CHIPS)':
 'RSVD'<296>: CDS_PINID='RSVD(296)';
NODE_NAME     U2D1 A16
 '@BASEBOARD_FAB2_LIB.BASEBOARD_FAB2(SCH_1):PAGE56_I169@CHPSET_LIB.SKX_EXT_B(CHIPS)':
 'RSVD'<301>: CDS_PINID='RSVD(301)';
NODE_NAME     U2D1 A14
 '@BASEBOARD_FAB2_LIB.BASEBOARD_FAB2(SCH_1):PAGE56_I169@CHPSET_LIB.SKX_EXT_B(CHIPS)':
 'RSVD'<302>: CDS_PINID='RSVD(302)';
NODE_NAME     C3D3 1
 '@BASEBOARD_FAB2_LIB.BASEBOARD_FAB2(SCH_1):PAGE72_I25@MSTR_DISCRETE.CAP(CHIPS)':
 'A': CDS_PINID='A';
NODE_NAME     U2D1 BT27
 '@BASEBOARD_FAB2_LIB.BASEBOARD_FAB2(SCH_1):PAGE72_I33@CHPSET_LIB.SKX_EXT_B(CHIPS)':
 'CD_VCCIN'<0>: CDS_PINID='CD_VCCIN(0)';
NODE_NAME     U2D1 BU26
 '@BASEBOARD_FAB2_LIB.BASEBOARD_FAB2(SCH_1):PAGE72_I33@CHPSET_LIB.SKX_EXT_B(CHIPS)':
 'CD_VCCIN'<1>: CDS_PINID='CD_VCCIN(1)';
NODE_NAME     U2D1 BV27
 '@BASEBOARD_FAB2_LIB.BASEBOARD_FAB2(SCH_1):PAGE72_I33@CHPSET_LIB.SKX_EXT_B(CHIPS)':
 'CD_VCCIN'<2>: CDS_PINID='CD_VCCIN(2)';
NODE_NAME     U2D1 BY27
 '@BASEBOARD_FAB2_LIB.BASEBOARD_FAB2(SCH_1):PAGE72_I33@CHPSET_LIB.SKX_EXT_B(CHIPS)':
 'CD_VCCIN'<3>: CDS_PINID='CD_VCCIN(3)';
NODE_NAME     U6M1 2
 '@BASEBOARD_FAB2_LIB.BASEBOARD_FAB2(SCH_1):PAGE113_I190@MSTR_TTL.74CBTLV1G125(CHIPS)':
 'A': CDS_PINID='A';
NODE_NAME     J4E1 D3
 '@BASEBOARD_FAB2_LIB.BASEBOARD_FAB2(SCH_1):PAGE193_I45@MSTR_SCONN.SCONN120_H61426002(CHIPS)':
 'IOD3': CDS_PINID='IOD3';
NODE_NAME     J4E1 E1
 '@BASEBOARD_FAB2_LIB.BASEBOARD_FAB2(SCH_1):PAGE193_I45@MSTR_SCONN.SCONN120_H61426002(CHIPS)':
 'IOE1': CDS_PINID='IOE1';
NODE_NAME     J4E1 E2
 '@BASEBOARD_FAB2_LIB.BASEBOARD_FAB2(SCH_1):PAGE193_I45@MSTR_SCONN.SCONN120_H61426002(CHIPS)':
 'IOE2': CDS_PINID='IOE2';
NODE_NAME     J4E1 E3
 '@BASEBOARD_FAB2_LIB.BASEBOARD_FAB2(SCH_1):PAGE193_I45@MSTR_SCONN.SCONN120_H61426002(CHIPS)':
 'IOE3': CDS_PINID='IOE3';
NODE_NAME     J4E1 F1
 '@BASEBOARD_FAB2_LIB.BASEBOARD_FAB2(SCH_1):PAGE193_I45@MSTR_SCONN.SCONN120_H61426002(CHIPS)':
 'IOF1': CDS_PINID='IOF1';
NODE_NAME     J4E1 F2
 '@BASEBOARD_FAB2_LIB.BASEBOARD_FAB2(SCH_1):PAGE193_I45@MSTR_SCONN.SCONN120_H61426002(CHIPS)':
 'IOF2': CDS_PINID='IOF2';
NODE_NAME     J4E1 F3
 '@BASEBOARD_FAB2_LIB.BASEBOARD_FAB2(SCH_1):PAGE193_I45@MSTR_SCONN.SCONN120_H61426002(CHIPS)':
 'IOF3': CDS_PINID='IOF3';
NODE_NAME     C4F1 1
 '@BASEBOARD_FAB2_LIB.BASEBOARD_FAB2(SCH_1):PAGE193_I68@DEV_DISCRETE.CAP_A(CHIPS)':
 'A': CDS_PINID='A';
NODE_NAME     C4F3 1
 '@BASEBOARD_FAB2_LIB.BASEBOARD_FAB2(SCH_1):PAGE193_I70@DEV_DISCRETE.CAP_A(CHIPS)':
 'A': CDS_PINID='A';
NODE_NAME     C3F1 1
 '@BASEBOARD_FAB2_LIB.BASEBOARD_FAB2(SCH_1):PAGE193_I140@DEV_DISCRETE.CAP_A(CHIPS)':
 'A': CDS_PINID='A';
NODE_NAME     C4F2 1
 '@BASEBOARD_FAB2_LIB.BASEBOARD_FAB2(SCH_1):PAGE193_I141@DEV_DISCRETE.CAP_A(CHIPS)':
 'A': CDS_PINID='A';
NODE_NAME     R5W2 1
 '@BASEBOARD_FAB2_LIB.BASEBOARD_FAB2(SCH_1):PAGE113_I273@MSTR_DISCRETE.RES(CHIPS)':
 'A': CDS_PINID='A';
NET_NAME
'P1V8_PCH_STBY'
 '@BASEBOARD_FAB2_LIB.BASEBOARD_FAB2(SCH_1):P1V8_PCH_STBY':
 C_SIGNAL='@baseboard_fab2_lib.baseboard_fab2(sch_1):p1v8_pch_stby';
NODE_NAME     U7C1 BA29
 '@BASEBOARD_FAB2_LIB.BASEBOARD_FAB2(SCH_1):PAGE122_I63@MSTR_U_PROC.LBG_CORE_QAT_EXT_D(CHIPS)':
 'VCCP10GBE_HV_1P8'<0>: CDS_PINID='VCCP10GBE_HV_1P8(0)';
NODE_NAME     U7C1 BA27
 '@BASEBOARD_FAB2_LIB.BASEBOARD_FAB2(SCH_1):PAGE122_I63@MSTR_U_PROC.LBG_CORE_QAT_EXT_D(CHIPS)':
 'VCCP10GBE_HV_1P8'<1>: CDS_PINID='VCCP10GBE_HV_1P8(1)';
NODE_NAME     U7C1 BD46
 '@BASEBOARD_FAB2_LIB.BASEBOARD_FAB2(SCH_1):PAGE122_I63@MSTR_U_PROC.LBG_CORE_QAT_EXT_D(CHIPS)':
 'VCCP_1P8'<0>: CDS_PINID='VCCP_1P8(0)';
NODE_NAME     U7C1 AE26
 '@BASEBOARD_FAB2_LIB.BASEBOARD_FAB2(SCH_1):PAGE122_I63@MSTR_U_PROC.LBG_CORE_QAT_EXT_D(CHIPS)':
 'VCCP_1P8'<1>: CDS_PINID='VCCP_1P8(1)';
NODE_NAME     U7C1 AU29
 '@BASEBOARD_FAB2_LIB.BASEBOARD_FAB2(SCH_1):PAGE122_I63@MSTR_U_PROC.LBG_CORE_QAT_EXT_D(CHIPS)':
 'VCCPGPP_1P8'<0>: CDS_PINID='VCCPGPP_1P8(0)';
NODE_NAME     U7C1 AW29
 '@BASEBOARD_FAB2_LIB.BASEBOARD_FAB2(SCH_1):PAGE122_I63@MSTR_U_PROC.LBG_CORE_QAT_EXT_D(CHIPS)':
 'VCCPGPP_1P8'<1>: CDS_PINID='VCCPGPP_1P8(1)';
NODE_NAME     U7C1 AT29
 '@BASEBOARD_FAB2_LIB.BASEBOARD_FAB2(SCH_1):PAGE122_I63@MSTR_U_PROC.LBG_CORE_QAT_EXT_D(CHIPS)':
 'VCCPGPP_1P8'<2>: CDS_PINID='VCCPGPP_1P8(2)';
NODE_NAME     U7C1 AM29
 '@BASEBOARD_FAB2_LIB.BASEBOARD_FAB2(SCH_1):PAGE122_I63@MSTR_U_PROC.LBG_CORE_QAT_EXT_D(CHIPS)':
 'VCCPGPP_1P8'<3>: CDS_PINID='VCCPGPP_1P8(3)';
NODE_NAME     U7C1 AP29
 '@BASEBOARD_FAB2_LIB.BASEBOARD_FAB2(SCH_1):PAGE122_I63@MSTR_U_PROC.LBG_CORE_QAT_EXT_D(CHIPS)':
 'VCCPGPP_1P8'<4>: CDS_PINID='VCCPGPP_1P8(4)';
NODE_NAME     U7C1 AW27
 '@BASEBOARD_FAB2_LIB.BASEBOARD_FAB2(SCH_1):PAGE122_I63@MSTR_U_PROC.LBG_CORE_QAT_EXT_D(CHIPS)':
 'VCCPGPP_1P8'<5>: CDS_PINID='VCCPGPP_1P8(5)';
NODE_NAME     U7C1 AK24
 '@BASEBOARD_FAB2_LIB.BASEBOARD_FAB2(SCH_1):PAGE122_I63@MSTR_U_PROC.LBG_CORE_QAT_EXT_D(CHIPS)':
 'VCCPGPP_1P8'<6>: CDS_PINID='VCCPGPP_1P8(6)';
NODE_NAME     U7C1 AG27
 '@BASEBOARD_FAB2_LIB.BASEBOARD_FAB2(SCH_1):PAGE122_I63@MSTR_U_PROC.LBG_CORE_QAT_EXT_D(CHIPS)':
 'VCCPHDA_1P8': CDS_PINID='VCCPHDA_1P8';
NODE_NAME     U7C1 AK29
 '@BASEBOARD_FAB2_LIB.BASEBOARD_FAB2(SCH_1):PAGE122_I63@MSTR_U_PROC.LBG_CORE_QAT_EXT_D(CHIPS)':
 'VCCPSPI_1P8': CDS_PINID='VCCPSPI_1P8';
NODE_NAME     C8B2 1
 '@BASEBOARD_FAB2_LIB.BASEBOARD_FAB2(SCH_1):PAGE130_I30@DEV_DISCRETE.CAP_A(CHIPS)':
 'A': CDS_PINID='A';
NODE_NAME     C8B3 1
 '@BASEBOARD_FAB2_LIB.BASEBOARD_FAB2(SCH_1):PAGE130_I32@DEV_DISCRETE.CAP_A(CHIPS)':
 'A': CDS_PINID='A';
NODE_NAME     C7D3 1
 '@BASEBOARD_FAB2_LIB.BASEBOARD_FAB2(SCH_1):PAGE130_I38@DEV_DISCRETE.CAP_A(CHIPS)':
 'A': CDS_PINID='A';
NODE_NAME     C8B4 1
 '@BASEBOARD_FAB2_LIB.BASEBOARD_FAB2(SCH_1):PAGE130_I39@DEV_DISCRETE.CAP_A(CHIPS)':
 'A': CDS_PINID='A';
NODE_NAME     C8B1 1
 '@BASEBOARD_FAB2_LIB.BASEBOARD_FAB2(SCH_1):PAGE130_I41@DEV_DISCRETE.CAP_A(CHIPS)':
 'A': CDS_PINID='A';
NODE_NAME     C2M1 1
 '@BASEBOARD_FAB2_LIB.BASEBOARD_FAB2(SCH_1):PAGE130_I43@DEV_DISCRETE.CAP_A(CHIPS)':
 'A': CDS_PINID='A';
NODE_NAME     C2M2 1
 '@BASEBOARD_FAB2_LIB.BASEBOARD_FAB2(SCH_1):PAGE130_I45@DEV_DISCRETE.CAP_A(CHIPS)':
 'A': CDS_PINID='A';
NODE_NAME     C2N15 1
 '@BASEBOARD_FAB2_LIB.BASEBOARD_FAB2(SCH_1):PAGE130_I47@DEV_DISCRETE.CAP_A(CHIPS)':
 'A': CDS_PINID='A';
NODE_NAME     C3N21 1
 '@BASEBOARD_FAB2_LIB.BASEBOARD_FAB2(SCH_1):PAGE130_I49@DEV_DISCRETE.CAP_A(CHIPS)':
 'A': CDS_PINID='A';
NODE_NAME     C3N25 1
 '@BASEBOARD_FAB2_LIB.BASEBOARD_FAB2(SCH_1):PAGE130_I50@DEV_DISCRETE.CAP_A(CHIPS)':
 'A': CDS_PINID='A';
NODE_NAME     C2N16 1
 '@BASEBOARD_FAB2_LIB.BASEBOARD_FAB2(SCH_1):PAGE130_I52@DEV_DISCRETE.CAP_A(CHIPS)':
 'A': CDS_PINID='A';
NODE_NAME     C3N22 1
 '@BASEBOARD_FAB2_LIB.BASEBOARD_FAB2(SCH_1):PAGE130_I53@DEV_DISCRETE.CAP_A(CHIPS)':
 'A': CDS_PINID='A';
NODE_NAME     C2L45 1
 '@BASEBOARD_FAB2_LIB.BASEBOARD_FAB2(SCH_1):PAGE237_I12@MSTR_DISCRETE.CAP(CHIPS)':
 'A': CDS_PINID='A';
NODE_NAME     C8A14 1
 '@BASEBOARD_FAB2_LIB.BASEBOARD_FAB2(SCH_1):PAGE237_I13@MSTR_DISCRETE.CAP(CHIPS)':
 'A': CDS_PINID='A';
NODE_NAME     R8A12 1
 '@BASEBOARD_FAB2_LIB.BASEBOARD_FAB2(SCH_1):PAGE237_I15@MSTR_DISCRETE.RES(CHIPS)':
 'A': CDS_PINID='A';
NODE_NAME     C8A12 1
 '@BASEBOARD_FAB2_LIB.BASEBOARD_FAB2(SCH_1):PAGE237_I77@MSTR_DISCRETE.CAP(CHIPS)':
 'A': CDS_PINID='A';
NODE_NAME     C2L32 1
 '@BASEBOARD_FAB2_LIB.BASEBOARD_FAB2(SCH_1):PAGE237_I79@MSTR_DISCRETE.CAP(CHIPS)':
 'A': CDS_PINID='A';
NODE_NAME     R2L20 1
 '@BASEBOARD_FAB2_LIB.BASEBOARD_FAB2(SCH_1):PAGE237_I81@MSTR_DISCRETE.RES(CHIPS)':
 'A': CDS_PINID='A';
NODE_NAME     EU8A2 1
 '@BASEBOARD_FAB2_LIB.BASEBOARD_FAB2(SCH_1):PAGE237_I86@MSTR_VREG.RT9059(CHIPS)':
 'VOUT'<0>: CDS_PINID='VOUT(0)';
NODE_NAME     EU8A2 2
 '@BASEBOARD_FAB2_LIB.BASEBOARD_FAB2(SCH_1):PAGE237_I86@MSTR_VREG.RT9059(CHIPS)':
 'VOUT'<1>: CDS_PINID='VOUT(1)';
NODE_NAME     EU8A2 3
 '@BASEBOARD_FAB2_LIB.BASEBOARD_FAB2(SCH_1):PAGE237_I86@MSTR_VREG.RT9059(CHIPS)':
 'VOUT'<2>: CDS_PINID='VOUT(2)';
NET_NAME
'P2E_SSB_BMC_RX_C_DN'
 '@BASEBOARD_FAB2_LIB.BASEBOARD_FAB2(SCH_1):P2E_SSB_BMC_RX_C_DN':
 C_SIGNAL='@baseboard_fab2_lib.baseboard_fab2(sch_1):p2e_ssb_bmc_rx_c_dn';
NODE_NAME     U7C1 AN70
 '@BASEBOARD_FAB2_LIB.BASEBOARD_FAB2(SCH_1):PAGE116_I220@MSTR_U_PROC.LBG_CORE_QAT_EXT_D(CHIPS)':
 'PCIE4_GBE_RXN': CDS_PINID='PCIE4_GBE_RXN';
NODE_NAME     R3M9 1
 '@BASEBOARD_FAB2_LIB.BASEBOARD_FAB2(SCH_1):PAGE116_I234@MSTR_DISCRETE.RES(CHIPS)':
 'A': CDS_PINID='A';
NODE_NAME     C25W21 2
 '@BASEBOARD_FAB2_LIB.BASEBOARD_FAB2(SCH_1):PAGE145_I159@DEV_DISCRETE.CAP_A(CHIPS)':
 'B': CDS_PINID='B';
NET_NAME
'P2E_SSB_BMC_RX_C_DP'
 '@BASEBOARD_FAB2_LIB.BASEBOARD_FAB2(SCH_1):P2E_SSB_BMC_RX_C_DP':
 C_SIGNAL='@baseboard_fab2_lib.baseboard_fab2(sch_1):p2e_ssb_bmc_rx_c_dp';
NODE_NAME     U7C1 AN72
 '@BASEBOARD_FAB2_LIB.BASEBOARD_FAB2(SCH_1):PAGE116_I220@MSTR_U_PROC.LBG_CORE_QAT_EXT_D(CHIPS)':
 'PCIE4_GBE_RXP': CDS_PINID='PCIE4_GBE_RXP';
NODE_NAME     R3M8 1
 '@BASEBOARD_FAB2_LIB.BASEBOARD_FAB2(SCH_1):PAGE116_I235@MSTR_DISCRETE.RES(CHIPS)':
 'A': CDS_PINID='A';
NODE_NAME     C25W20 2
 '@BASEBOARD_FAB2_LIB.BASEBOARD_FAB2(SCH_1):PAGE145_I158@DEV_DISCRETE.CAP_A(CHIPS)':
 'B': CDS_PINID='B';
NET_NAME
'P2E_SSB_BMC_RX_DN'
 '@BASEBOARD_FAB2_LIB.BASEBOARD_FAB2(SCH_1):P2E_SSB_BMC_RX_DN':
 C_SIGNAL='@baseboard_fab2_lib.baseboard_fab2(sch_1):p2e_ssb_bmc_rx_dn';
NODE_NAME     U25W4 L22
 '@BASEBOARD_FAB2_LIB.BASEBOARD_FAB2(SCH_1):PAGE145_I117@W_HDL.AST2520A1-GP-GP(CHIPS)':
 'PETXN': CDS_PINID='PETXN';
NODE_NAME     C25W21 1
 '@BASEBOARD_FAB2_LIB.BASEBOARD_FAB2(SCH_1):PAGE145_I159@DEV_DISCRETE.CAP_A(CHIPS)':
 'A': CDS_PINID='A';
NET_NAME
'P2E_SSB_BMC_RX_DP'
 '@BASEBOARD_FAB2_LIB.BASEBOARD_FAB2(SCH_1):P2E_SSB_BMC_RX_DP':
 C_SIGNAL='@baseboard_fab2_lib.baseboard_fab2(sch_1):p2e_ssb_bmc_rx_dp';
NODE_NAME     U25W4 L21
 '@BASEBOARD_FAB2_LIB.BASEBOARD_FAB2(SCH_1):PAGE145_I117@W_HDL.AST2520A1-GP-GP(CHIPS)':
 'PETXP': CDS_PINID='PETXP';
NODE_NAME     C25W20 1
 '@BASEBOARD_FAB2_LIB.BASEBOARD_FAB2(SCH_1):PAGE145_I158@DEV_DISCRETE.CAP_A(CHIPS)':
 'A': CDS_PINID='A';
NET_NAME
'P2E_SSB_BMC_TX_C_DN'
 '@BASEBOARD_FAB2_LIB.BASEBOARD_FAB2(SCH_1):P2E_SSB_BMC_TX_C_DN':
 C_SIGNAL='@baseboard_fab2_lib.baseboard_fab2(sch_1):p2e_ssb_bmc_tx_c_dn';
NODE_NAME     R25W65 1
 '@BASEBOARD_FAB2_LIB.BASEBOARD_FAB2(SCH_1):PAGE145_I38@MSTR_DISCRETE.RES(CHIPS)':
 'A': CDS_PINID='A';
NODE_NAME     U25W4 M22
 '@BASEBOARD_FAB2_LIB.BASEBOARD_FAB2(SCH_1):PAGE145_I117@W_HDL.AST2520A1-GP-GP(CHIPS)':
 'PERXN': CDS_PINID='PERXN';
NODE_NAME     C2M3 2
 '@BASEBOARD_FAB2_LIB.BASEBOARD_FAB2(SCH_1):PAGE116_I239@DEV_DISCRETE.CAP_A(CHIPS)':
 'B': CDS_PINID='B';
NET_NAME
'P2E_SSB_BMC_TX_C_DP'
 '@BASEBOARD_FAB2_LIB.BASEBOARD_FAB2(SCH_1):P2E_SSB_BMC_TX_C_DP':
 C_SIGNAL='@baseboard_fab2_lib.baseboard_fab2(sch_1):p2e_ssb_bmc_tx_c_dp';
NODE_NAME     R25W64 1
 '@BASEBOARD_FAB2_LIB.BASEBOARD_FAB2(SCH_1):PAGE145_I36@MSTR_DISCRETE.RES(CHIPS)':
 'A': CDS_PINID='A';
NODE_NAME     U25W4 M21
 '@BASEBOARD_FAB2_LIB.BASEBOARD_FAB2(SCH_1):PAGE145_I117@W_HDL.AST2520A1-GP-GP(CHIPS)':
 'PERXP': CDS_PINID='PERXP';
NODE_NAME     C2M4 2
 '@BASEBOARD_FAB2_LIB.BASEBOARD_FAB2(SCH_1):PAGE116_I238@DEV_DISCRETE.CAP_A(CHIPS)':
 'B': CDS_PINID='B';
NET_NAME
'P2E_SSB_BMC_TX_DN'
 '@BASEBOARD_FAB2_LIB.BASEBOARD_FAB2(SCH_1):P2E_SSB_BMC_TX_DN':
 C_SIGNAL='@baseboard_fab2_lib.baseboard_fab2(sch_1):p2e_ssb_bmc_tx_dn';
NODE_NAME     U7C1 BG66
 '@BASEBOARD_FAB2_LIB.BASEBOARD_FAB2(SCH_1):PAGE116_I220@MSTR_U_PROC.LBG_CORE_QAT_EXT_D(CHIPS)':
 'PCIE4_GBE_TXN': CDS_PINID='PCIE4_GBE_TXN';
NODE_NAME     C2M3 1
 '@BASEBOARD_FAB2_LIB.BASEBOARD_FAB2(SCH_1):PAGE116_I239@DEV_DISCRETE.CAP_A(CHIPS)':
 'A': CDS_PINID='A';
NET_NAME
'P2E_SSB_BMC_TX_DP'
 '@BASEBOARD_FAB2_LIB.BASEBOARD_FAB2(SCH_1):P2E_SSB_BMC_TX_DP':
 C_SIGNAL='@baseboard_fab2_lib.baseboard_fab2(sch_1):p2e_ssb_bmc_tx_dp';
NODE_NAME     U7C1 BJ66
 '@BASEBOARD_FAB2_LIB.BASEBOARD_FAB2(SCH_1):PAGE116_I220@MSTR_U_PROC.LBG_CORE_QAT_EXT_D(CHIPS)':
 'PCIE4_GBE_TXP': CDS_PINID='PCIE4_GBE_TXP';
NODE_NAME     C2M4 1
 '@BASEBOARD_FAB2_LIB.BASEBOARD_FAB2(SCH_1):PAGE116_I238@DEV_DISCRETE.CAP_A(CHIPS)':
 'A': CDS_PINID='A';
NET_NAME
'P2V5_AUX_BMC'
 '@BASEBOARD_FAB2_LIB.BASEBOARD_FAB2(SCH_1):P2V5_AUX_BMC':
 C_SIGNAL='@baseboard_fab2_lib.baseboard_fab2(sch_1):p2v5_aux_bmc';
NODE_NAME     EU25F2 1
 '@BASEBOARD_FAB2_LIB.BASEBOARD_FAB2(SCH_1):PAGE239_I73@MSTR_VREG.RT9059(CHIPS)':
 'VOUT'<0>: CDS_PINID='VOUT(0)';
NODE_NAME     EU25F2 2
 '@BASEBOARD_FAB2_LIB.BASEBOARD_FAB2(SCH_1):PAGE239_I73@MSTR_VREG.RT9059(CHIPS)':
 'VOUT'<1>: CDS_PINID='VOUT(1)';
NODE_NAME     EU25F2 3
 '@BASEBOARD_FAB2_LIB.BASEBOARD_FAB2(SCH_1):PAGE239_I73@MSTR_VREG.RT9059(CHIPS)':
 'VOUT'<2>: CDS_PINID='VOUT(2)';
NODE_NAME     C9W13 1
 '@BASEBOARD_FAB2_LIB.BASEBOARD_FAB2(SCH_1):PAGE239_I81@MSTR_DISCRETE.CAP(CHIPS)':
 'A': CDS_PINID='A';
NODE_NAME     C1W15 1
 '@BASEBOARD_FAB2_LIB.BASEBOARD_FAB2(SCH_1):PAGE239_I83@MSTR_DISCRETE.CAP(CHIPS)':
 'A': CDS_PINID='A';
NODE_NAME     U25W5 B1
 '@BASEBOARD_FAB2_LIB.BASEBOARD_FAB2(SCH_1):PAGE151_I49@W_HDL.H5AN4G6NAFR-TFC-GP(CHIPS)':
 'VPP'<0>: CDS_PINID='VPP(0)';
NODE_NAME     U25W5 R9
 '@BASEBOARD_FAB2_LIB.BASEBOARD_FAB2(SCH_1):PAGE151_I49@W_HDL.H5AN4G6NAFR-TFC-GP(CHIPS)':
 'VPP'<1>: CDS_PINID='VPP(1)';
NODE_NAME     C25W14 1
 '@BASEBOARD_FAB2_LIB.BASEBOARD_FAB2(SCH_1):PAGE151_I215@DEV_DISCRETE.CAP_A(CHIPS)':
 'A': CDS_PINID='A';
NODE_NAME     C25W15 1
 '@BASEBOARD_FAB2_LIB.BASEBOARD_FAB2(SCH_1):PAGE151_I216@DEV_DISCRETE.CAP_A(CHIPS)':
 'A': CDS_PINID='A';
NODE_NAME     R9W31 1
 '@BASEBOARD_FAB2_LIB.BASEBOARD_FAB2(SCH_1):PAGE239_I102@W_HDL.21K5R2F-GP(CHIPS)':
 '1': CDS_PINID='\1\';
NET_NAME
'P3E_CPU0_PE1_PCH_CON_RXN<10>'
 '@BASEBOARD_FAB2_LIB.BASEBOARD_FAB2(SCH_1):P3E_CPU0_PE1_PCH_CON_RXN'<10>:
 C_SIGNAL='@baseboard_fab2_lib.baseboard_fab2(sch_1):p3e_cpu0_pe1_pch_con_rxn(10~
)';
NODE_NAME     J8G1 88
 '@BASEBOARD_FAB2_LIB.BASEBOARD_FAB2(SCH_1):PAGE108_I258@MSTR_SCONN.SCONN200_H68296001(CHIPS)':
 'IO88': CDS_PINID='IO88';
NODE_NAME     R780 2
 '@BASEBOARD_FAB2_LIB.BASEBOARD_FAB2(SCH_1):PAGE244_I97@MSTR_DISCRETE.RES(CHIPS)':
 'B': CDS_PINID='B';
NET_NAME
'P3E_CPU0_PE1_PCH_CON_RXN<11>'
 '@BASEBOARD_FAB2_LIB.BASEBOARD_FAB2(SCH_1):P3E_CPU0_PE1_PCH_CON_RXN'<11>:
 C_SIGNAL='@baseboard_fab2_lib.baseboard_fab2(sch_1):p3e_cpu0_pe1_pch_con_rxn(11~
)';
NODE_NAME     J8G1 82
 '@BASEBOARD_FAB2_LIB.BASEBOARD_FAB2(SCH_1):PAGE108_I258@MSTR_SCONN.SCONN200_H68296001(CHIPS)':
 'IO82': CDS_PINID='IO82';
NODE_NAME     R778 2
 '@BASEBOARD_FAB2_LIB.BASEBOARD_FAB2(SCH_1):PAGE244_I94@MSTR_DISCRETE.RES(CHIPS)':
 'B': CDS_PINID='B';
NET_NAME
'P3E_CPU0_PE1_PCH_CON_RXN<12>'
 '@BASEBOARD_FAB2_LIB.BASEBOARD_FAB2(SCH_1):P3E_CPU0_PE1_PCH_CON_RXN'<12>:
 C_SIGNAL='@baseboard_fab2_lib.baseboard_fab2(sch_1):p3e_cpu0_pe1_pch_con_rxn(12~
)';
NODE_NAME     J8G1 76
 '@BASEBOARD_FAB2_LIB.BASEBOARD_FAB2(SCH_1):PAGE108_I258@MSTR_SCONN.SCONN200_H68296001(CHIPS)':
 'IO76': CDS_PINID='IO76';
NODE_NAME     R775 2
 '@BASEBOARD_FAB2_LIB.BASEBOARD_FAB2(SCH_1):PAGE244_I93@MSTR_DISCRETE.RES(CHIPS)':
 'B': CDS_PINID='B';
NET_NAME
'P3E_CPU0_PE1_PCH_CON_RXN<13>'
 '@BASEBOARD_FAB2_LIB.BASEBOARD_FAB2(SCH_1):P3E_CPU0_PE1_PCH_CON_RXN'<13>:
 C_SIGNAL='@baseboard_fab2_lib.baseboard_fab2(sch_1):p3e_cpu0_pe1_pch_con_rxn(13~
)';
NODE_NAME     J8G1 70
 '@BASEBOARD_FAB2_LIB.BASEBOARD_FAB2(SCH_1):PAGE108_I258@MSTR_SCONN.SCONN200_H68296001(CHIPS)':
 'IO70': CDS_PINID='IO70';
NODE_NAME     R771 2
 '@BASEBOARD_FAB2_LIB.BASEBOARD_FAB2(SCH_1):PAGE244_I65@MSTR_DISCRETE.RES(CHIPS)':
 'B': CDS_PINID='B';
NET_NAME
'P3E_CPU0_PE1_PCH_CON_RXN<14>'
 '@BASEBOARD_FAB2_LIB.BASEBOARD_FAB2(SCH_1):P3E_CPU0_PE1_PCH_CON_RXN'<14>:
 C_SIGNAL='@baseboard_fab2_lib.baseboard_fab2(sch_1):p3e_cpu0_pe1_pch_con_rxn(14~
)';
NODE_NAME     J8G1 60
 '@BASEBOARD_FAB2_LIB.BASEBOARD_FAB2(SCH_1):PAGE108_I258@MSTR_SCONN.SCONN200_H68296001(CHIPS)':
 'IO60': CDS_PINID='IO60';
NODE_NAME     R768 2
 '@BASEBOARD_FAB2_LIB.BASEBOARD_FAB2(SCH_1):PAGE244_I66@MSTR_DISCRETE.RES(CHIPS)':
 'B': CDS_PINID='B';
NET_NAME
'P3E_CPU0_PE1_PCH_CON_RXN<15>'
 '@BASEBOARD_FAB2_LIB.BASEBOARD_FAB2(SCH_1):P3E_CPU0_PE1_PCH_CON_RXN'<15>:
 C_SIGNAL='@baseboard_fab2_lib.baseboard_fab2(sch_1):p3e_cpu0_pe1_pch_con_rxn(15~
)';
NODE_NAME     J8G1 54
 '@BASEBOARD_FAB2_LIB.BASEBOARD_FAB2(SCH_1):PAGE108_I258@MSTR_SCONN.SCONN200_H68296001(CHIPS)':
 'IO54': CDS_PINID='IO54';
NODE_NAME     R760 2
 '@BASEBOARD_FAB2_LIB.BASEBOARD_FAB2(SCH_1):PAGE244_I64@MSTR_DISCRETE.RES(CHIPS)':
 'B': CDS_PINID='B';
NET_NAME
'P3E_CPU0_PE1_PCH_CON_RXN<8>'
 '@BASEBOARD_FAB2_LIB.BASEBOARD_FAB2(SCH_1):P3E_CPU0_PE1_PCH_CON_RXN'<8>:
 C_SIGNAL='@baseboard_fab2_lib.baseboard_fab2(sch_1):p3e_cpu0_pe1_pch_con_rxn(8)~
';
NODE_NAME     J8G1 100
 '@BASEBOARD_FAB2_LIB.BASEBOARD_FAB2(SCH_1):PAGE108_I258@MSTR_SCONN.SCONN200_H68296001(CHIPS)':
 'IO100': CDS_PINID='IO100';
NODE_NAME     R784 2
 '@BASEBOARD_FAB2_LIB.BASEBOARD_FAB2(SCH_1):PAGE244_I99@MSTR_DISCRETE.RES(CHIPS)':
 'B': CDS_PINID='B';
NET_NAME
'P3E_CPU0_PE1_PCH_CON_RXN<9>'
 '@BASEBOARD_FAB2_LIB.BASEBOARD_FAB2(SCH_1):P3E_CPU0_PE1_PCH_CON_RXN'<9>:
 C_SIGNAL='@baseboard_fab2_lib.baseboard_fab2(sch_1):p3e_cpu0_pe1_pch_con_rxn(9)~
';
NODE_NAME     J8G1 94
 '@BASEBOARD_FAB2_LIB.BASEBOARD_FAB2(SCH_1):PAGE108_I258@MSTR_SCONN.SCONN200_H68296001(CHIPS)':
 'IO94': CDS_PINID='IO94';
NODE_NAME     R782 2
 '@BASEBOARD_FAB2_LIB.BASEBOARD_FAB2(SCH_1):PAGE244_I98@MSTR_DISCRETE.RES(CHIPS)':
 'B': CDS_PINID='B';
NET_NAME
'P3E_CPU0_PE1_PCH_CON_RXP<10>'
 '@BASEBOARD_FAB2_LIB.BASEBOARD_FAB2(SCH_1):P3E_CPU0_PE1_PCH_CON_RXP'<10>:
 C_SIGNAL='@baseboard_fab2_lib.baseboard_fab2(sch_1):p3e_cpu0_pe1_pch_con_rxp(10~
)';
NODE_NAME     J8G1 90
 '@BASEBOARD_FAB2_LIB.BASEBOARD_FAB2(SCH_1):PAGE108_I258@MSTR_SCONN.SCONN200_H68296001(CHIPS)':
 'IO90': CDS_PINID='IO90';
NODE_NAME     R781 2
 '@BASEBOARD_FAB2_LIB.BASEBOARD_FAB2(SCH_1):PAGE244_I86@MSTR_DISCRETE.RES(CHIPS)':
 'B': CDS_PINID='B';
NET_NAME
'P3E_CPU0_PE1_PCH_CON_RXP<11>'
 '@BASEBOARD_FAB2_LIB.BASEBOARD_FAB2(SCH_1):P3E_CPU0_PE1_PCH_CON_RXP'<11>:
 C_SIGNAL='@baseboard_fab2_lib.baseboard_fab2(sch_1):p3e_cpu0_pe1_pch_con_rxp(11~
)';
NODE_NAME     J8G1 84
 '@BASEBOARD_FAB2_LIB.BASEBOARD_FAB2(SCH_1):PAGE108_I258@MSTR_SCONN.SCONN200_H68296001(CHIPS)':
 'IO84': CDS_PINID='IO84';
NODE_NAME     R779 2
 '@BASEBOARD_FAB2_LIB.BASEBOARD_FAB2(SCH_1):PAGE244_I74@MSTR_DISCRETE.RES(CHIPS)':
 'B': CDS_PINID='B';
NET_NAME
'P3E_CPU0_PE1_PCH_CON_RXP<12>'
 '@BASEBOARD_FAB2_LIB.BASEBOARD_FAB2(SCH_1):P3E_CPU0_PE1_PCH_CON_RXP'<12>:
 C_SIGNAL='@baseboard_fab2_lib.baseboard_fab2(sch_1):p3e_cpu0_pe1_pch_con_rxp(12~
)';
NODE_NAME     J8G1 78
 '@BASEBOARD_FAB2_LIB.BASEBOARD_FAB2(SCH_1):PAGE108_I258@MSTR_SCONN.SCONN200_H68296001(CHIPS)':
 'IO78': CDS_PINID='IO78';
NODE_NAME     R777 2
 '@BASEBOARD_FAB2_LIB.BASEBOARD_FAB2(SCH_1):PAGE244_I80@MSTR_DISCRETE.RES(CHIPS)':
 'B': CDS_PINID='B';
NET_NAME
'P3E_CPU0_PE1_PCH_CON_RXP<13>'
 '@BASEBOARD_FAB2_LIB.BASEBOARD_FAB2(SCH_1):P3E_CPU0_PE1_PCH_CON_RXP'<13>:
 C_SIGNAL='@baseboard_fab2_lib.baseboard_fab2(sch_1):p3e_cpu0_pe1_pch_con_rxp(13~
)';
NODE_NAME     J8G1 72
 '@BASEBOARD_FAB2_LIB.BASEBOARD_FAB2(SCH_1):PAGE108_I258@MSTR_SCONN.SCONN200_H68296001(CHIPS)':
 'IO72': CDS_PINID='IO72';
NODE_NAME     R774 2
 '@BASEBOARD_FAB2_LIB.BASEBOARD_FAB2(SCH_1):PAGE244_I72@MSTR_DISCRETE.RES(CHIPS)':
 'B': CDS_PINID='B';
NET_NAME
'P3E_CPU0_PE1_PCH_CON_RXP<14>'
 '@BASEBOARD_FAB2_LIB.BASEBOARD_FAB2(SCH_1):P3E_CPU0_PE1_PCH_CON_RXP'<14>:
 C_SIGNAL='@baseboard_fab2_lib.baseboard_fab2(sch_1):p3e_cpu0_pe1_pch_con_rxp(14~
)';
NODE_NAME     J8G1 62
 '@BASEBOARD_FAB2_LIB.BASEBOARD_FAB2(SCH_1):PAGE108_I258@MSTR_SCONN.SCONN200_H68296001(CHIPS)':
 'IO62': CDS_PINID='IO62';
NODE_NAME     R769 2
 '@BASEBOARD_FAB2_LIB.BASEBOARD_FAB2(SCH_1):PAGE244_I58@MSTR_DISCRETE.RES(CHIPS)':
 'B': CDS_PINID='B';
NET_NAME
'P3E_CPU0_PE1_PCH_CON_RXP<15>'
 '@BASEBOARD_FAB2_LIB.BASEBOARD_FAB2(SCH_1):P3E_CPU0_PE1_PCH_CON_RXP'<15>:
 C_SIGNAL='@baseboard_fab2_lib.baseboard_fab2(sch_1):p3e_cpu0_pe1_pch_con_rxp(15~
)';
NODE_NAME     J8G1 56
 '@BASEBOARD_FAB2_LIB.BASEBOARD_FAB2(SCH_1):PAGE108_I258@MSTR_SCONN.SCONN200_H68296001(CHIPS)':
 'IO56': CDS_PINID='IO56';
NODE_NAME     R767 2
 '@BASEBOARD_FAB2_LIB.BASEBOARD_FAB2(SCH_1):PAGE244_I39@MSTR_DISCRETE.RES(CHIPS)':
 'B': CDS_PINID='B';
NET_NAME
'P3E_CPU0_PE1_PCH_CON_RXP<8>'
 '@BASEBOARD_FAB2_LIB.BASEBOARD_FAB2(SCH_1):P3E_CPU0_PE1_PCH_CON_RXP'<8>:
 C_SIGNAL='@baseboard_fab2_lib.baseboard_fab2(sch_1):p3e_cpu0_pe1_pch_con_rxp(8)~
';
NODE_NAME     R785 2
 '@BASEBOARD_FAB2_LIB.BASEBOARD_FAB2(SCH_1):PAGE244_I103@MSTR_DISCRETE.RES(CHIPS)':
 'B': CDS_PINID='B';
NODE_NAME     J8G1 102
 '@BASEBOARD_FAB2_LIB.BASEBOARD_FAB2(SCH_1):PAGE109_I78@MSTR_SCONN.SCONN200_H68296001(CHIPS)':
 'IO102': CDS_PINID='IO102';
NET_NAME
'P3E_CPU0_PE1_PCH_CON_RXP<9>'
 '@BASEBOARD_FAB2_LIB.BASEBOARD_FAB2(SCH_1):P3E_CPU0_PE1_PCH_CON_RXP'<9>:
 C_SIGNAL='@baseboard_fab2_lib.baseboard_fab2(sch_1):p3e_cpu0_pe1_pch_con_rxp(9)~
';
NODE_NAME     J8G1 96
 '@BASEBOARD_FAB2_LIB.BASEBOARD_FAB2(SCH_1):PAGE108_I258@MSTR_SCONN.SCONN200_H68296001(CHIPS)':
 'IO96': CDS_PINID='IO96';
NODE_NAME     R783 2
 '@BASEBOARD_FAB2_LIB.BASEBOARD_FAB2(SCH_1):PAGE244_I77@MSTR_DISCRETE.RES(CHIPS)':
 'B': CDS_PINID='B';
NET_NAME
'P3E_CPU0_PE1_PCH_CON_TXN<10>'
 '@BASEBOARD_FAB2_LIB.BASEBOARD_FAB2(SCH_1):P3E_CPU0_PE1_PCH_CON_TXN'<10>:
 C_SIGNAL='@baseboard_fab2_lib.baseboard_fab2(sch_1):p3e_cpu0_pe1_pch_con_txn(10~
)';
NODE_NAME     J8G1 85
 '@BASEBOARD_FAB2_LIB.BASEBOARD_FAB2(SCH_1):PAGE108_I258@MSTR_SCONN.SCONN200_H68296001(CHIPS)':
 'IO85': CDS_PINID='IO85';
NODE_NAME     C834 2
 '@BASEBOARD_FAB2_LIB.BASEBOARD_FAB2(SCH_1):PAGE244_I50@MSTR_DISCRETE.CAP(CHIPS)':
 'B': CDS_PINID='B';
NET_NAME
'P3E_CPU0_PE1_PCH_CON_TXN<11>'
 '@BASEBOARD_FAB2_LIB.BASEBOARD_FAB2(SCH_1):P3E_CPU0_PE1_PCH_CON_TXN'<11>:
 C_SIGNAL='@baseboard_fab2_lib.baseboard_fab2(sch_1):p3e_cpu0_pe1_pch_con_txn(11~
)';
NODE_NAME     J8G1 79
 '@BASEBOARD_FAB2_LIB.BASEBOARD_FAB2(SCH_1):PAGE108_I258@MSTR_SCONN.SCONN200_H68296001(CHIPS)':
 'IO79': CDS_PINID='IO79';
NODE_NAME     C832 2
 '@BASEBOARD_FAB2_LIB.BASEBOARD_FAB2(SCH_1):PAGE244_I30@MSTR_DISCRETE.CAP(CHIPS)':
 'B': CDS_PINID='B';
NET_NAME
'P3E_CPU0_PE1_PCH_CON_TXN<12>'
 '@BASEBOARD_FAB2_LIB.BASEBOARD_FAB2(SCH_1):P3E_CPU0_PE1_PCH_CON_TXN'<12>:
 C_SIGNAL='@baseboard_fab2_lib.baseboard_fab2(sch_1):p3e_cpu0_pe1_pch_con_txn(12~
)';
NODE_NAME     J8G1 73
 '@BASEBOARD_FAB2_LIB.BASEBOARD_FAB2(SCH_1):PAGE108_I258@MSTR_SCONN.SCONN200_H68296001(CHIPS)':
 'IO73': CDS_PINID='IO73';
NODE_NAME     C840 2
 '@BASEBOARD_FAB2_LIB.BASEBOARD_FAB2(SCH_1):PAGE244_I29@MSTR_DISCRETE.CAP(CHIPS)':
 'B': CDS_PINID='B';
NET_NAME
'P3E_CPU0_PE1_PCH_CON_TXN<13>'
 '@BASEBOARD_FAB2_LIB.BASEBOARD_FAB2(SCH_1):P3E_CPU0_PE1_PCH_CON_TXN'<13>:
 C_SIGNAL='@baseboard_fab2_lib.baseboard_fab2(sch_1):p3e_cpu0_pe1_pch_con_txn(13~
)';
NODE_NAME     J8G1 67
 '@BASEBOARD_FAB2_LIB.BASEBOARD_FAB2(SCH_1):PAGE108_I258@MSTR_SCONN.SCONN200_H68296001(CHIPS)':
 'IO67': CDS_PINID='IO67';
NODE_NAME     C828 2
 '@BASEBOARD_FAB2_LIB.BASEBOARD_FAB2(SCH_1):PAGE244_I28@MSTR_DISCRETE.CAP(CHIPS)':
 'B': CDS_PINID='B';
NET_NAME
'P3E_CPU0_PE1_PCH_CON_TXN<14>'
 '@BASEBOARD_FAB2_LIB.BASEBOARD_FAB2(SCH_1):P3E_CPU0_PE1_PCH_CON_TXN'<14>:
 C_SIGNAL='@baseboard_fab2_lib.baseboard_fab2(sch_1):p3e_cpu0_pe1_pch_con_txn(14~
)';
NODE_NAME     J8G1 59
 '@BASEBOARD_FAB2_LIB.BASEBOARD_FAB2(SCH_1):PAGE108_I258@MSTR_SCONN.SCONN200_H68296001(CHIPS)':
 'IO59': CDS_PINID='IO59';
NODE_NAME     C826 2
 '@BASEBOARD_FAB2_LIB.BASEBOARD_FAB2(SCH_1):PAGE244_I24@MSTR_DISCRETE.CAP(CHIPS)':
 'B': CDS_PINID='B';
NET_NAME
'P3E_CPU0_PE1_PCH_CON_TXN<15>'
 '@BASEBOARD_FAB2_LIB.BASEBOARD_FAB2(SCH_1):P3E_CPU0_PE1_PCH_CON_TXN'<15>:
 C_SIGNAL='@baseboard_fab2_lib.baseboard_fab2(sch_1):p3e_cpu0_pe1_pch_con_txn(15~
)';
NODE_NAME     J8G1 51
 '@BASEBOARD_FAB2_LIB.BASEBOARD_FAB2(SCH_1):PAGE108_I258@MSTR_SCONN.SCONN200_H68296001(CHIPS)':
 'IO51': CDS_PINID='IO51';
NODE_NAME     C830 2
 '@BASEBOARD_FAB2_LIB.BASEBOARD_FAB2(SCH_1):PAGE244_I23@MSTR_DISCRETE.CAP(CHIPS)':
 'B': CDS_PINID='B';
NET_NAME
'P3E_CPU0_PE1_PCH_CON_TXN<8>'
 '@BASEBOARD_FAB2_LIB.BASEBOARD_FAB2(SCH_1):P3E_CPU0_PE1_PCH_CON_TXN'<8>:
 C_SIGNAL='@baseboard_fab2_lib.baseboard_fab2(sch_1):p3e_cpu0_pe1_pch_con_txn(8)~
';
NODE_NAME     J8G1 97
 '@BASEBOARD_FAB2_LIB.BASEBOARD_FAB2(SCH_1):PAGE108_I258@MSTR_SCONN.SCONN200_H68296001(CHIPS)':
 'IO97': CDS_PINID='IO97';
NODE_NAME     C842 2
 '@BASEBOARD_FAB2_LIB.BASEBOARD_FAB2(SCH_1):PAGE244_I52@MSTR_DISCRETE.CAP(CHIPS)':
 'B': CDS_PINID='B';
NET_NAME
'P3E_CPU0_PE1_PCH_CON_TXN<9>'
 '@BASEBOARD_FAB2_LIB.BASEBOARD_FAB2(SCH_1):P3E_CPU0_PE1_PCH_CON_TXN'<9>:
 C_SIGNAL='@baseboard_fab2_lib.baseboard_fab2(sch_1):p3e_cpu0_pe1_pch_con_txn(9)~
';
NODE_NAME     J8G1 91
 '@BASEBOARD_FAB2_LIB.BASEBOARD_FAB2(SCH_1):PAGE108_I258@MSTR_SCONN.SCONN200_H68296001(CHIPS)':
 'IO91': CDS_PINID='IO91';
NODE_NAME     C844 2
 '@BASEBOARD_FAB2_LIB.BASEBOARD_FAB2(SCH_1):PAGE244_I51@MSTR_DISCRETE.CAP(CHIPS)':
 'B': CDS_PINID='B';
NET_NAME
'P3E_CPU0_PE1_PCH_CON_TXP<10>'
 '@BASEBOARD_FAB2_LIB.BASEBOARD_FAB2(SCH_1):P3E_CPU0_PE1_PCH_CON_TXP'<10>:
 C_SIGNAL='@baseboard_fab2_lib.baseboard_fab2(sch_1):p3e_cpu0_pe1_pch_con_txp(10~
)';
NODE_NAME     J8G1 87
 '@BASEBOARD_FAB2_LIB.BASEBOARD_FAB2(SCH_1):PAGE108_I258@MSTR_SCONN.SCONN200_H68296001(CHIPS)':
 'IO87': CDS_PINID='IO87';
NODE_NAME     C835 2
 '@BASEBOARD_FAB2_LIB.BASEBOARD_FAB2(SCH_1):PAGE244_I41@MSTR_DISCRETE.CAP(CHIPS)':
 'B': CDS_PINID='B';
NET_NAME
'P3E_CPU0_PE1_PCH_CON_TXP<11>'
 '@BASEBOARD_FAB2_LIB.BASEBOARD_FAB2(SCH_1):P3E_CPU0_PE1_PCH_CON_TXP'<11>:
 C_SIGNAL='@baseboard_fab2_lib.baseboard_fab2(sch_1):p3e_cpu0_pe1_pch_con_txp(11~
)';
NODE_NAME     J8G1 81
 '@BASEBOARD_FAB2_LIB.BASEBOARD_FAB2(SCH_1):PAGE108_I258@MSTR_SCONN.SCONN200_H68296001(CHIPS)':
 'IO81': CDS_PINID='IO81';
NODE_NAME     C833 2
 '@BASEBOARD_FAB2_LIB.BASEBOARD_FAB2(SCH_1):PAGE244_I8@MSTR_DISCRETE.CAP(CHIPS)':
 'B': CDS_PINID='B';
NET_NAME
'P3E_CPU0_PE1_PCH_CON_TXP<12>'
 '@BASEBOARD_FAB2_LIB.BASEBOARD_FAB2(SCH_1):P3E_CPU0_PE1_PCH_CON_TXP'<12>:
 C_SIGNAL='@baseboard_fab2_lib.baseboard_fab2(sch_1):p3e_cpu0_pe1_pch_con_txp(12~
)';
NODE_NAME     J8G1 75
 '@BASEBOARD_FAB2_LIB.BASEBOARD_FAB2(SCH_1):PAGE108_I258@MSTR_SCONN.SCONN200_H68296001(CHIPS)':
 'IO75': CDS_PINID='IO75';
NODE_NAME     C841 2
 '@BASEBOARD_FAB2_LIB.BASEBOARD_FAB2(SCH_1):PAGE244_I17@MSTR_DISCRETE.CAP(CHIPS)':
 'B': CDS_PINID='B';
NET_NAME
'P3E_CPU0_PE1_PCH_CON_TXP<13>'
 '@BASEBOARD_FAB2_LIB.BASEBOARD_FAB2(SCH_1):P3E_CPU0_PE1_PCH_CON_TXP'<13>:
 C_SIGNAL='@baseboard_fab2_lib.baseboard_fab2(sch_1):p3e_cpu0_pe1_pch_con_txp(13~
)';
NODE_NAME     J8G1 69
 '@BASEBOARD_FAB2_LIB.BASEBOARD_FAB2(SCH_1):PAGE108_I258@MSTR_SCONN.SCONN200_H68296001(CHIPS)':
 'IO69': CDS_PINID='IO69';
NODE_NAME     C829 2
 '@BASEBOARD_FAB2_LIB.BASEBOARD_FAB2(SCH_1):PAGE244_I5@MSTR_DISCRETE.CAP(CHIPS)':
 'B': CDS_PINID='B';
NET_NAME
'P3E_CPU0_PE1_PCH_CON_TXP<14>'
 '@BASEBOARD_FAB2_LIB.BASEBOARD_FAB2(SCH_1):P3E_CPU0_PE1_PCH_CON_TXP'<14>:
 C_SIGNAL='@baseboard_fab2_lib.baseboard_fab2(sch_1):p3e_cpu0_pe1_pch_con_txp(14~
)';
NODE_NAME     J8G1 57
 '@BASEBOARD_FAB2_LIB.BASEBOARD_FAB2(SCH_1):PAGE108_I258@MSTR_SCONN.SCONN200_H68296001(CHIPS)':
 'IO57': CDS_PINID='IO57';
NODE_NAME     C827 2
 '@BASEBOARD_FAB2_LIB.BASEBOARD_FAB2(SCH_1):PAGE244_I12@MSTR_DISCRETE.CAP(CHIPS)':
 'B': CDS_PINID='B';
NET_NAME
'P3E_CPU0_PE1_PCH_CON_TXP<15>'
 '@BASEBOARD_FAB2_LIB.BASEBOARD_FAB2(SCH_1):P3E_CPU0_PE1_PCH_CON_TXP'<15>:
 C_SIGNAL='@baseboard_fab2_lib.baseboard_fab2(sch_1):p3e_cpu0_pe1_pch_con_txp(15~
)';
NODE_NAME     J8G1 53
 '@BASEBOARD_FAB2_LIB.BASEBOARD_FAB2(SCH_1):PAGE108_I258@MSTR_SCONN.SCONN200_H68296001(CHIPS)':
 'IO53': CDS_PINID='IO53';
NODE_NAME     C831 2
 '@BASEBOARD_FAB2_LIB.BASEBOARD_FAB2(SCH_1):PAGE244_I2@MSTR_DISCRETE.CAP(CHIPS)':
 'B': CDS_PINID='B';
NET_NAME
'P3E_CPU0_PE1_PCH_CON_TXP<8>'
 '@BASEBOARD_FAB2_LIB.BASEBOARD_FAB2(SCH_1):P3E_CPU0_PE1_PCH_CON_TXP'<8>:
 C_SIGNAL='@baseboard_fab2_lib.baseboard_fab2(sch_1):p3e_cpu0_pe1_pch_con_txp(8)~
';
NODE_NAME     J8G1 99
 '@BASEBOARD_FAB2_LIB.BASEBOARD_FAB2(SCH_1):PAGE108_I258@MSTR_SCONN.SCONN200_H68296001(CHIPS)':
 'IO99': CDS_PINID='IO99';
NODE_NAME     C843 2
 '@BASEBOARD_FAB2_LIB.BASEBOARD_FAB2(SCH_1):PAGE244_I47@MSTR_DISCRETE.CAP(CHIPS)':
 'B': CDS_PINID='B';
NET_NAME
'P3E_CPU0_PE1_PCH_CON_TXP<9>'
 '@BASEBOARD_FAB2_LIB.BASEBOARD_FAB2(SCH_1):P3E_CPU0_PE1_PCH_CON_TXP'<9>:
 C_SIGNAL='@baseboard_fab2_lib.baseboard_fab2(sch_1):p3e_cpu0_pe1_pch_con_txp(9)~
';
NODE_NAME     J8G1 93
 '@BASEBOARD_FAB2_LIB.BASEBOARD_FAB2(SCH_1):PAGE108_I258@MSTR_SCONN.SCONN200_H68296001(CHIPS)':
 'IO93': CDS_PINID='IO93';
NODE_NAME     C845 2
 '@BASEBOARD_FAB2_LIB.BASEBOARD_FAB2(SCH_1):PAGE244_I35@MSTR_DISCRETE.CAP(CHIPS)':
 'B': CDS_PINID='B';
NET_NAME
'P3E_CPU0_PE1_PCH_C_TXN<10>'
 '@BASEBOARD_FAB2_LIB.BASEBOARD_FAB2(SCH_1):P3E_CPU0_PE1_PCH_C_TXN'<10>:
 C_SIGNAL='@baseboard_fab2_lib.baseboard_fab2(sch_1):p3e_cpu0_pe1_pch_c_txn(10)';
NODE_NAME     C6B15 2
 '@BASEBOARD_FAB2_LIB.BASEBOARD_FAB2(SCH_1):PAGE105_I163@MSTR_DISCRETE.CAP(CHIPS)':
 'B': CDS_PINID='B';
NODE_NAME     U7C1 A59
 '@BASEBOARD_FAB2_LIB.BASEBOARD_FAB2(SCH_1):PAGE117_I9@MSTR_U_PROC.LBG_CORE_QAT_EXT_D(CHIPS)':
 'PCIEUP_10_RXP': CDS_PINID='PCIEUP_10_RXP';
NET_NAME
'P3E_CPU0_PE1_PCH_C_TXN<11>'
 '@BASEBOARD_FAB2_LIB.BASEBOARD_FAB2(SCH_1):P3E_CPU0_PE1_PCH_C_TXN'<11>:
 C_SIGNAL='@baseboard_fab2_lib.baseboard_fab2(sch_1):p3e_cpu0_pe1_pch_c_txn(11)';
NODE_NAME     C6B14 2
 '@BASEBOARD_FAB2_LIB.BASEBOARD_FAB2(SCH_1):PAGE105_I181@MSTR_DISCRETE.CAP(CHIPS)':
 'B': CDS_PINID='B';
NODE_NAME     U7C1 D60
 '@BASEBOARD_FAB2_LIB.BASEBOARD_FAB2(SCH_1):PAGE117_I9@MSTR_U_PROC.LBG_CORE_QAT_EXT_D(CHIPS)':
 'PCIEUP_11_RXN': CDS_PINID='PCIEUP_11_RXN';
NET_NAME
'P3E_CPU0_PE1_PCH_C_TXN<12>'
 '@BASEBOARD_FAB2_LIB.BASEBOARD_FAB2(SCH_1):P3E_CPU0_PE1_PCH_C_TXN'<12>:
 C_SIGNAL='@baseboard_fab2_lib.baseboard_fab2(sch_1):p3e_cpu0_pe1_pch_c_txn(12)';
NODE_NAME     C6B11 2
 '@BASEBOARD_FAB2_LIB.BASEBOARD_FAB2(SCH_1):PAGE105_I166@MSTR_DISCRETE.CAP(CHIPS)':
 'B': CDS_PINID='B';
NODE_NAME     U7C1 A61
 '@BASEBOARD_FAB2_LIB.BASEBOARD_FAB2(SCH_1):PAGE117_I9@MSTR_U_PROC.LBG_CORE_QAT_EXT_D(CHIPS)':
 'PCIEUP_12_RXP': CDS_PINID='PCIEUP_12_RXP';
NET_NAME
'P3E_CPU0_PE1_PCH_C_TXN<13>'
 '@BASEBOARD_FAB2_LIB.BASEBOARD_FAB2(SCH_1):P3E_CPU0_PE1_PCH_C_TXN'<13>:
 C_SIGNAL='@baseboard_fab2_lib.baseboard_fab2(sch_1):p3e_cpu0_pe1_pch_c_txn(13)';
NODE_NAME     C6B9 2
 '@BASEBOARD_FAB2_LIB.BASEBOARD_FAB2(SCH_1):PAGE105_I185@MSTR_DISCRETE.CAP(CHIPS)':
 'B': CDS_PINID='B';
NODE_NAME     U7C1 B62
 '@BASEBOARD_FAB2_LIB.BASEBOARD_FAB2(SCH_1):PAGE117_I9@MSTR_U_PROC.LBG_CORE_QAT_EXT_D(CHIPS)':
 'PCIEUP_13_RXP': CDS_PINID='PCIEUP_13_RXP';
NET_NAME
'P3E_CPU0_PE1_PCH_C_TXN<14>'
 '@BASEBOARD_FAB2_LIB.BASEBOARD_FAB2(SCH_1):P3E_CPU0_PE1_PCH_C_TXN'<14>:
 C_SIGNAL='@baseboard_fab2_lib.baseboard_fab2(sch_1):p3e_cpu0_pe1_pch_c_txn(14)';
NODE_NAME     C6B6 2
 '@BASEBOARD_FAB2_LIB.BASEBOARD_FAB2(SCH_1):PAGE105_I169@MSTR_DISCRETE.CAP(CHIPS)':
 'B': CDS_PINID='B';
NODE_NAME     U7C1 A63
 '@BASEBOARD_FAB2_LIB.BASEBOARD_FAB2(SCH_1):PAGE117_I9@MSTR_U_PROC.LBG_CORE_QAT_EXT_D(CHIPS)':
 'PCIEUP_14_RXP': CDS_PINID='PCIEUP_14_RXP';
NET_NAME
'P3E_CPU0_PE1_PCH_C_TXN<15>'
 '@BASEBOARD_FAB2_LIB.BASEBOARD_FAB2(SCH_1):P3E_CPU0_PE1_PCH_C_TXN'<15>:
 C_SIGNAL='@baseboard_fab2_lib.baseboard_fab2(sch_1):p3e_cpu0_pe1_pch_c_txn(15)';
NODE_NAME     C6B4 2
 '@BASEBOARD_FAB2_LIB.BASEBOARD_FAB2(SCH_1):PAGE105_I196@MSTR_DISCRETE.CAP(CHIPS)':
 'B': CDS_PINID='B';
NODE_NAME     U7C1 B64
 '@BASEBOARD_FAB2_LIB.BASEBOARD_FAB2(SCH_1):PAGE117_I9@MSTR_U_PROC.LBG_CORE_QAT_EXT_D(CHIPS)':
 'PCIEUP_15_RXP': CDS_PINID='PCIEUP_15_RXP';
NET_NAME
'P3E_CPU0_PE1_PCH_C_TXN<8>'
 '@BASEBOARD_FAB2_LIB.BASEBOARD_FAB2(SCH_1):P3E_CPU0_PE1_PCH_C_TXN'<8>:
 C_SIGNAL='@baseboard_fab2_lib.baseboard_fab2(sch_1):p3e_cpu0_pe1_pch_c_txn(8)';
NODE_NAME     C6B19 2
 '@BASEBOARD_FAB2_LIB.BASEBOARD_FAB2(SCH_1):PAGE105_I160@MSTR_DISCRETE.CAP(CHIPS)':
 'B': CDS_PINID='B';
NODE_NAME     U7C1 A57
 '@BASEBOARD_FAB2_LIB.BASEBOARD_FAB2(SCH_1):PAGE117_I9@MSTR_U_PROC.LBG_CORE_QAT_EXT_D(CHIPS)':
 'PCIEUP_8_RXP': CDS_PINID='PCIEUP_8_RXP';
NET_NAME
'P3E_CPU0_PE1_PCH_C_TXN<9>'
 '@BASEBOARD_FAB2_LIB.BASEBOARD_FAB2(SCH_1):P3E_CPU0_PE1_PCH_C_TXN'<9>:
 C_SIGNAL='@baseboard_fab2_lib.baseboard_fab2(sch_1):p3e_cpu0_pe1_pch_c_txn(9)';
NODE_NAME     C6B17 2
 '@BASEBOARD_FAB2_LIB.BASEBOARD_FAB2(SCH_1):PAGE105_I175@MSTR_DISCRETE.CAP(CHIPS)':
 'B': CDS_PINID='B';
NODE_NAME     U7C1 B58
 '@BASEBOARD_FAB2_LIB.BASEBOARD_FAB2(SCH_1):PAGE117_I9@MSTR_U_PROC.LBG_CORE_QAT_EXT_D(CHIPS)':
 'PCIEUP_9_RXP': CDS_PINID='PCIEUP_9_RXP';
NET_NAME
'P3E_CPU0_PE1_PCH_C_TXP<10>'
 '@BASEBOARD_FAB2_LIB.BASEBOARD_FAB2(SCH_1):P3E_CPU0_PE1_PCH_C_TXP'<10>:
 C_SIGNAL='@baseboard_fab2_lib.baseboard_fab2(sch_1):p3e_cpu0_pe1_pch_c_txp(10)';
NODE_NAME     C6B16 2
 '@BASEBOARD_FAB2_LIB.BASEBOARD_FAB2(SCH_1):PAGE105_I180@MSTR_DISCRETE.CAP(CHIPS)':
 'B': CDS_PINID='B';
NODE_NAME     U7C1 C59
 '@BASEBOARD_FAB2_LIB.BASEBOARD_FAB2(SCH_1):PAGE117_I9@MSTR_U_PROC.LBG_CORE_QAT_EXT_D(CHIPS)':
 'PCIEUP_10_RXN': CDS_PINID='PCIEUP_10_RXN';
NET_NAME
'P3E_CPU0_PE1_PCH_C_TXP<11>'
 '@BASEBOARD_FAB2_LIB.BASEBOARD_FAB2(SCH_1):P3E_CPU0_PE1_PCH_C_TXP'<11>:
 C_SIGNAL='@baseboard_fab2_lib.baseboard_fab2(sch_1):p3e_cpu0_pe1_pch_c_txp(11)';
NODE_NAME     C6B13 2
 '@BASEBOARD_FAB2_LIB.BASEBOARD_FAB2(SCH_1):PAGE105_I189@MSTR_DISCRETE.CAP(CHIPS)':
 'B': CDS_PINID='B';
NODE_NAME     U7C1 B60
 '@BASEBOARD_FAB2_LIB.BASEBOARD_FAB2(SCH_1):PAGE117_I9@MSTR_U_PROC.LBG_CORE_QAT_EXT_D(CHIPS)':
 'PCIEUP_11_RXP': CDS_PINID='PCIEUP_11_RXP';
NET_NAME
'P3E_CPU0_PE1_PCH_C_TXP<12>'
 '@BASEBOARD_FAB2_LIB.BASEBOARD_FAB2(SCH_1):P3E_CPU0_PE1_PCH_C_TXP'<12>:
 C_SIGNAL='@baseboard_fab2_lib.baseboard_fab2(sch_1):p3e_cpu0_pe1_pch_c_txp(12)';
NODE_NAME     C6B12 2
 '@BASEBOARD_FAB2_LIB.BASEBOARD_FAB2(SCH_1):PAGE105_I187@MSTR_DISCRETE.CAP(CHIPS)':
 'B': CDS_PINID='B';
NODE_NAME     U7C1 C61
 '@BASEBOARD_FAB2_LIB.BASEBOARD_FAB2(SCH_1):PAGE117_I9@MSTR_U_PROC.LBG_CORE_QAT_EXT_D(CHIPS)':
 'PCIEUP_12_RXN': CDS_PINID='PCIEUP_12_RXN';
NET_NAME
'P3E_CPU0_PE1_PCH_C_TXP<13>'
 '@BASEBOARD_FAB2_LIB.BASEBOARD_FAB2(SCH_1):P3E_CPU0_PE1_PCH_C_TXP'<13>:
 C_SIGNAL='@baseboard_fab2_lib.baseboard_fab2(sch_1):p3e_cpu0_pe1_pch_c_txp(13)';
NODE_NAME     C6B10 2
 '@BASEBOARD_FAB2_LIB.BASEBOARD_FAB2(SCH_1):PAGE105_I193@MSTR_DISCRETE.CAP(CHIPS)':
 'B': CDS_PINID='B';
NODE_NAME     U7C1 D62
 '@BASEBOARD_FAB2_LIB.BASEBOARD_FAB2(SCH_1):PAGE117_I9@MSTR_U_PROC.LBG_CORE_QAT_EXT_D(CHIPS)':
 'PCIEUP_13_RXN': CDS_PINID='PCIEUP_13_RXN';
NET_NAME
'P3E_CPU0_PE1_PCH_C_TXP<14>'
 '@BASEBOARD_FAB2_LIB.BASEBOARD_FAB2(SCH_1):P3E_CPU0_PE1_PCH_C_TXP'<14>:
 C_SIGNAL='@baseboard_fab2_lib.baseboard_fab2(sch_1):p3e_cpu0_pe1_pch_c_txp(14)';
NODE_NAME     C6B8 2
 '@BASEBOARD_FAB2_LIB.BASEBOARD_FAB2(SCH_1):PAGE105_I198@MSTR_DISCRETE.CAP(CHIPS)':
 'B': CDS_PINID='B';
NODE_NAME     U7C1 C63
 '@BASEBOARD_FAB2_LIB.BASEBOARD_FAB2(SCH_1):PAGE117_I9@MSTR_U_PROC.LBG_CORE_QAT_EXT_D(CHIPS)':
 'PCIEUP_14_RXN': CDS_PINID='PCIEUP_14_RXN';
NET_NAME
'P3E_CPU0_PE1_PCH_C_TXP<15>'
 '@BASEBOARD_FAB2_LIB.BASEBOARD_FAB2(SCH_1):P3E_CPU0_PE1_PCH_C_TXP'<15>:
 C_SIGNAL='@baseboard_fab2_lib.baseboard_fab2(sch_1):p3e_cpu0_pe1_pch_c_txp(15)';
NODE_NAME     C6B5 2
 '@BASEBOARD_FAB2_LIB.BASEBOARD_FAB2(SCH_1):PAGE105_I201@MSTR_DISCRETE.CAP(CHIPS)':
 'B': CDS_PINID='B';
NODE_NAME     U7C1 D64
 '@BASEBOARD_FAB2_LIB.BASEBOARD_FAB2(SCH_1):PAGE117_I9@MSTR_U_PROC.LBG_CORE_QAT_EXT_D(CHIPS)':
 'PCIEUP_15_RXN': CDS_PINID='PCIEUP_15_RXN';
NET_NAME
'P3E_CPU0_PE1_PCH_C_TXP<8>'
 '@BASEBOARD_FAB2_LIB.BASEBOARD_FAB2(SCH_1):P3E_CPU0_PE1_PCH_C_TXP'<8>:
 C_SIGNAL='@baseboard_fab2_lib.baseboard_fab2(sch_1):p3e_cpu0_pe1_pch_c_txp(8)';
NODE_NAME     C6B20 2
 '@BASEBOARD_FAB2_LIB.BASEBOARD_FAB2(SCH_1):PAGE105_I173@MSTR_DISCRETE.CAP(CHIPS)':
 'B': CDS_PINID='B';
NODE_NAME     U7C1 C57
 '@BASEBOARD_FAB2_LIB.BASEBOARD_FAB2(SCH_1):PAGE117_I9@MSTR_U_PROC.LBG_CORE_QAT_EXT_D(CHIPS)':
 'PCIEUP_8_RXN': CDS_PINID='PCIEUP_8_RXN';
NET_NAME
'P3E_CPU0_PE1_PCH_C_TXP<9>'
 '@BASEBOARD_FAB2_LIB.BASEBOARD_FAB2(SCH_1):P3E_CPU0_PE1_PCH_C_TXP'<9>:
 C_SIGNAL='@baseboard_fab2_lib.baseboard_fab2(sch_1):p3e_cpu0_pe1_pch_c_txp(9)';
NODE_NAME     C6B18 2
 '@BASEBOARD_FAB2_LIB.BASEBOARD_FAB2(SCH_1):PAGE105_I153@MSTR_DISCRETE.CAP(CHIPS)':
 'B': CDS_PINID='B';
NODE_NAME     U7C1 D58
 '@BASEBOARD_FAB2_LIB.BASEBOARD_FAB2(SCH_1):PAGE117_I9@MSTR_U_PROC.LBG_CORE_QAT_EXT_D(CHIPS)':
 'PCIEUP_9_RXN': CDS_PINID='PCIEUP_9_RXN';
NET_NAME
'P3E_CPU0_PE1_PCH_RXN<0>'
 '@BASEBOARD_FAB2_LIB.BASEBOARD_FAB2(SCH_1):P3E_CPU0_PE1_PCH_RXN'<0>:
 C_SIGNAL='@baseboard_fab2_lib.baseboard_fab2(sch_1):p3e_cpu0_pe1_pch_rxn(0)';
NODE_NAME     C2U4 1
 '@BASEBOARD_FAB2_LIB.BASEBOARD_FAB2(SCH_1):PAGE107_I257@MSTR_DISCRETE.CAP(CHIPS)':
 'A': CDS_PINID='A';
NODE_NAME     U7C1 J52
 '@BASEBOARD_FAB2_LIB.BASEBOARD_FAB2(SCH_1):PAGE117_I9@MSTR_U_PROC.LBG_CORE_QAT_EXT_D(CHIPS)':
 'PCIEUP_0_TXN': CDS_PINID='PCIEUP_0_TXN';
NET_NAME
'P3E_CPU0_PE1_PCH_RXN<10>'
 '@BASEBOARD_FAB2_LIB.BASEBOARD_FAB2(SCH_1):P3E_CPU0_PE1_PCH_RXN'<10>:
 C_SIGNAL='@baseboard_fab2_lib.baseboard_fab2(sch_1):p3e_cpu0_pe1_pch_rxn(10)';
NODE_NAME     U5D1 DT11
 '@BASEBOARD_FAB2_LIB.BASEBOARD_FAB2(SCH_1):PAGE30_I84@CHPSET_LIB.SKX_EXT_B(CHIPS)':
 'PE1_RX_DN'<10>: CDS_PINID='PE1_RX_DN(10)';
NODE_NAME     C3M32 2
 '@BASEBOARD_FAB2_LIB.BASEBOARD_FAB2(SCH_1):PAGE105_I223@MSTR_DISCRETE.CAP(CHIPS)':
 'B': CDS_PINID='B';
NODE_NAME     R780 1
 '@BASEBOARD_FAB2_LIB.BASEBOARD_FAB2(SCH_1):PAGE244_I97@MSTR_DISCRETE.RES(CHIPS)':
 'A': CDS_PINID='A';
NET_NAME
'P3E_CPU0_PE1_PCH_RXN<11>'
 '@BASEBOARD_FAB2_LIB.BASEBOARD_FAB2(SCH_1):P3E_CPU0_PE1_PCH_RXN'<11>:
 C_SIGNAL='@baseboard_fab2_lib.baseboard_fab2(sch_1):p3e_cpu0_pe1_pch_rxn(11)';
NODE_NAME     U5D1 DT13
 '@BASEBOARD_FAB2_LIB.BASEBOARD_FAB2(SCH_1):PAGE30_I84@CHPSET_LIB.SKX_EXT_B(CHIPS)':
 'PE1_RX_DN'<11>: CDS_PINID='PE1_RX_DN(11)';
NODE_NAME     C3M26 2
 '@BASEBOARD_FAB2_LIB.BASEBOARD_FAB2(SCH_1):PAGE105_I229@MSTR_DISCRETE.CAP(CHIPS)':
 'B': CDS_PINID='B';
NODE_NAME     R778 1
 '@BASEBOARD_FAB2_LIB.BASEBOARD_FAB2(SCH_1):PAGE244_I94@MSTR_DISCRETE.RES(CHIPS)':
 'A': CDS_PINID='A';
NET_NAME
'P3E_CPU0_PE1_PCH_RXN<12>'
 '@BASEBOARD_FAB2_LIB.BASEBOARD_FAB2(SCH_1):P3E_CPU0_PE1_PCH_RXN'<12>:
 C_SIGNAL='@baseboard_fab2_lib.baseboard_fab2(sch_1):p3e_cpu0_pe1_pch_rxn(12)';
NODE_NAME     U5D1 DV13
 '@BASEBOARD_FAB2_LIB.BASEBOARD_FAB2(SCH_1):PAGE30_I84@CHPSET_LIB.SKX_EXT_B(CHIPS)':
 'PE1_RX_DN'<12>: CDS_PINID='PE1_RX_DN(12)';
NODE_NAME     C3M4 2
 '@BASEBOARD_FAB2_LIB.BASEBOARD_FAB2(SCH_1):PAGE105_I244@MSTR_DISCRETE.CAP(CHIPS)':
 'B': CDS_PINID='B';
NODE_NAME     R775 1
 '@BASEBOARD_FAB2_LIB.BASEBOARD_FAB2(SCH_1):PAGE244_I93@MSTR_DISCRETE.RES(CHIPS)':
 'A': CDS_PINID='A';
NET_NAME
'P3E_CPU0_PE1_PCH_RXN<13>'
 '@BASEBOARD_FAB2_LIB.BASEBOARD_FAB2(SCH_1):P3E_CPU0_PE1_PCH_RXN'<13>:
 C_SIGNAL='@baseboard_fab2_lib.baseboard_fab2(sch_1):p3e_cpu0_pe1_pch_rxn(13)';
NODE_NAME     U5D1 DW14
 '@BASEBOARD_FAB2_LIB.BASEBOARD_FAB2(SCH_1):PAGE30_I84@CHPSET_LIB.SKX_EXT_B(CHIPS)':
 'PE1_RX_DN'<13>: CDS_PINID='PE1_RX_DN(13)';
NODE_NAME     C3M14 2
 '@BASEBOARD_FAB2_LIB.BASEBOARD_FAB2(SCH_1):PAGE105_I253@MSTR_DISCRETE.CAP(CHIPS)':
 'B': CDS_PINID='B';
NODE_NAME     R771 1
 '@BASEBOARD_FAB2_LIB.BASEBOARD_FAB2(SCH_1):PAGE244_I65@MSTR_DISCRETE.RES(CHIPS)':
 'A': CDS_PINID='A';
NET_NAME
'P3E_CPU0_PE1_PCH_RXN<14>'
 '@BASEBOARD_FAB2_LIB.BASEBOARD_FAB2(SCH_1):P3E_CPU0_PE1_PCH_RXN'<14>:
 C_SIGNAL='@baseboard_fab2_lib.baseboard_fab2(sch_1):p3e_cpu0_pe1_pch_rxn(14)';
NODE_NAME     U5D1 DY15
 '@BASEBOARD_FAB2_LIB.BASEBOARD_FAB2(SCH_1):PAGE30_I84@CHPSET_LIB.SKX_EXT_B(CHIPS)':
 'PE1_RX_DN'<14>: CDS_PINID='PE1_RX_DN(14)';
NODE_NAME     C3M12 2
 '@BASEBOARD_FAB2_LIB.BASEBOARD_FAB2(SCH_1):PAGE105_I246@MSTR_DISCRETE.CAP(CHIPS)':
 'B': CDS_PINID='B';
NODE_NAME     R768 1
 '@BASEBOARD_FAB2_LIB.BASEBOARD_FAB2(SCH_1):PAGE244_I66@MSTR_DISCRETE.RES(CHIPS)':
 'A': CDS_PINID='A';
NET_NAME
'P3E_CPU0_PE1_PCH_RXN<15>'
 '@BASEBOARD_FAB2_LIB.BASEBOARD_FAB2(SCH_1):P3E_CPU0_PE1_PCH_RXN'<15>:
 C_SIGNAL='@baseboard_fab2_lib.baseboard_fab2(sch_1):p3e_cpu0_pe1_pch_rxn(15)';
NODE_NAME     U5D1 DU16
 '@BASEBOARD_FAB2_LIB.BASEBOARD_FAB2(SCH_1):PAGE30_I84@CHPSET_LIB.SKX_EXT_B(CHIPS)':
 'PE1_RX_DN'<15>: CDS_PINID='PE1_RX_DN(15)';
NODE_NAME     C3M1 2
 '@BASEBOARD_FAB2_LIB.BASEBOARD_FAB2(SCH_1):PAGE105_I255@MSTR_DISCRETE.CAP(CHIPS)':
 'B': CDS_PINID='B';
NODE_NAME     R760 1
 '@BASEBOARD_FAB2_LIB.BASEBOARD_FAB2(SCH_1):PAGE244_I64@MSTR_DISCRETE.RES(CHIPS)':
 'A': CDS_PINID='A';
NET_NAME
'P3E_CPU0_PE1_PCH_RXN<1>'
 '@BASEBOARD_FAB2_LIB.BASEBOARD_FAB2(SCH_1):P3E_CPU0_PE1_PCH_RXN'<1>:
 C_SIGNAL='@baseboard_fab2_lib.baseboard_fab2(sch_1):p3e_cpu0_pe1_pch_rxn(1)';
NODE_NAME     C2U6 1
 '@BASEBOARD_FAB2_LIB.BASEBOARD_FAB2(SCH_1):PAGE107_I260@MSTR_DISCRETE.CAP(CHIPS)':
 'A': CDS_PINID='A';
NODE_NAME     U7C1 P56
 '@BASEBOARD_FAB2_LIB.BASEBOARD_FAB2(SCH_1):PAGE117_I9@MSTR_U_PROC.LBG_CORE_QAT_EXT_D(CHIPS)':
 'PCIEUP_1_TXN': CDS_PINID='PCIEUP_1_TXN';
NET_NAME
'P3E_CPU0_PE1_PCH_RXN<2>'
 '@BASEBOARD_FAB2_LIB.BASEBOARD_FAB2(SCH_1):P3E_CPU0_PE1_PCH_RXN'<2>:
 C_SIGNAL='@baseboard_fab2_lib.baseboard_fab2(sch_1):p3e_cpu0_pe1_pch_rxn(2)';
NODE_NAME     C2U8 1
 '@BASEBOARD_FAB2_LIB.BASEBOARD_FAB2(SCH_1):PAGE107_I264@MSTR_DISCRETE.CAP(CHIPS)':
 'A': CDS_PINID='A';
NODE_NAME     U7C1 H54
 '@BASEBOARD_FAB2_LIB.BASEBOARD_FAB2(SCH_1):PAGE117_I9@MSTR_U_PROC.LBG_CORE_QAT_EXT_D(CHIPS)':
 'PCIEUP_2_TXN': CDS_PINID='PCIEUP_2_TXN';
NET_NAME
'P3E_CPU0_PE1_PCH_RXN<3>'
 '@BASEBOARD_FAB2_LIB.BASEBOARD_FAB2(SCH_1):P3E_CPU0_PE1_PCH_RXN'<3>:
 C_SIGNAL='@baseboard_fab2_lib.baseboard_fab2(sch_1):p3e_cpu0_pe1_pch_rxn(3)';
NODE_NAME     C2U10 1
 '@BASEBOARD_FAB2_LIB.BASEBOARD_FAB2(SCH_1):PAGE107_I267@MSTR_DISCRETE.CAP(CHIPS)':
 'A': CDS_PINID='A';
NODE_NAME     U7C1 J56
 '@BASEBOARD_FAB2_LIB.BASEBOARD_FAB2(SCH_1):PAGE117_I9@MSTR_U_PROC.LBG_CORE_QAT_EXT_D(CHIPS)':
 'PCIEUP_3_TXN': CDS_PINID='PCIEUP_3_TXN';
NET_NAME
'P3E_CPU0_PE1_PCH_RXN<4>'
 '@BASEBOARD_FAB2_LIB.BASEBOARD_FAB2(SCH_1):P3E_CPU0_PE1_PCH_RXN'<4>:
 C_SIGNAL='@baseboard_fab2_lib.baseboard_fab2(sch_1):p3e_cpu0_pe1_pch_rxn(4)';
NODE_NAME     C2U12 1
 '@BASEBOARD_FAB2_LIB.BASEBOARD_FAB2(SCH_1):PAGE107_I265@MSTR_DISCRETE.CAP(CHIPS)':
 'A': CDS_PINID='A';
NODE_NAME     U7C1 N58
 '@BASEBOARD_FAB2_LIB.BASEBOARD_FAB2(SCH_1):PAGE117_I9@MSTR_U_PROC.LBG_CORE_QAT_EXT_D(CHIPS)':
 'PCIEUP_4_TXN': CDS_PINID='PCIEUP_4_TXN';
NET_NAME
'P3E_CPU0_PE1_PCH_RXN<5>'
 '@BASEBOARD_FAB2_LIB.BASEBOARD_FAB2(SCH_1):P3E_CPU0_PE1_PCH_RXN'<5>:
 C_SIGNAL='@baseboard_fab2_lib.baseboard_fab2(sch_1):p3e_cpu0_pe1_pch_rxn(5)';
NODE_NAME     C2U14 1
 '@BASEBOARD_FAB2_LIB.BASEBOARD_FAB2(SCH_1):PAGE107_I287@MSTR_DISCRETE.CAP(CHIPS)':
 'A': CDS_PINID='A';
NODE_NAME     U7C1 N61
 '@BASEBOARD_FAB2_LIB.BASEBOARD_FAB2(SCH_1):PAGE117_I9@MSTR_U_PROC.LBG_CORE_QAT_EXT_D(CHIPS)':
 'PCIEUP_5_TXN': CDS_PINID='PCIEUP_5_TXN';
NET_NAME
'P3E_CPU0_PE1_PCH_RXN<6>'
 '@BASEBOARD_FAB2_LIB.BASEBOARD_FAB2(SCH_1):P3E_CPU0_PE1_PCH_RXN'<6>:
 C_SIGNAL='@baseboard_fab2_lib.baseboard_fab2(sch_1):p3e_cpu0_pe1_pch_rxn(6)';
NODE_NAME     C2U16 1
 '@BASEBOARD_FAB2_LIB.BASEBOARD_FAB2(SCH_1):PAGE107_I286@MSTR_DISCRETE.CAP(CHIPS)':
 'A': CDS_PINID='A';
NODE_NAME     U7C1 H61
 '@BASEBOARD_FAB2_LIB.BASEBOARD_FAB2(SCH_1):PAGE117_I9@MSTR_U_PROC.LBG_CORE_QAT_EXT_D(CHIPS)':
 'PCIEUP_6_TXN': CDS_PINID='PCIEUP_6_TXN';
NET_NAME
'P3E_CPU0_PE1_PCH_RXN<7>'
 '@BASEBOARD_FAB2_LIB.BASEBOARD_FAB2(SCH_1):P3E_CPU0_PE1_PCH_RXN'<7>:
 C_SIGNAL='@baseboard_fab2_lib.baseboard_fab2(sch_1):p3e_cpu0_pe1_pch_rxn(7)';
NODE_NAME     C2U18 1
 '@BASEBOARD_FAB2_LIB.BASEBOARD_FAB2(SCH_1):PAGE107_I294@MSTR_DISCRETE.CAP(CHIPS)':
 'A': CDS_PINID='A';
NODE_NAME     U7C1 P59
 '@BASEBOARD_FAB2_LIB.BASEBOARD_FAB2(SCH_1):PAGE117_I9@MSTR_U_PROC.LBG_CORE_QAT_EXT_D(CHIPS)':
 'PCIEUP_7_TXN': CDS_PINID='PCIEUP_7_TXN';
NET_NAME
'P3E_CPU0_PE1_PCH_RXN<8>'
 '@BASEBOARD_FAB2_LIB.BASEBOARD_FAB2(SCH_1):P3E_CPU0_PE1_PCH_RXN'<8>:
 C_SIGNAL='@baseboard_fab2_lib.baseboard_fab2(sch_1):p3e_cpu0_pe1_pch_rxn(8)';
NODE_NAME     U5D1 DM11
 '@BASEBOARD_FAB2_LIB.BASEBOARD_FAB2(SCH_1):PAGE30_I84@CHPSET_LIB.SKX_EXT_B(CHIPS)':
 'PE1_RX_DN'<8>: CDS_PINID='PE1_RX_DN(8)';
NODE_NAME     C3M33 2
 '@BASEBOARD_FAB2_LIB.BASEBOARD_FAB2(SCH_1):PAGE105_I217@MSTR_DISCRETE.CAP(CHIPS)':
 'B': CDS_PINID='B';
NODE_NAME     R784 1
 '@BASEBOARD_FAB2_LIB.BASEBOARD_FAB2(SCH_1):PAGE244_I99@MSTR_DISCRETE.RES(CHIPS)':
 'A': CDS_PINID='A';
NET_NAME
'P3E_CPU0_PE1_PCH_RXN<9>'
 '@BASEBOARD_FAB2_LIB.BASEBOARD_FAB2(SCH_1):P3E_CPU0_PE1_PCH_RXN'<9>:
 C_SIGNAL='@baseboard_fab2_lib.baseboard_fab2(sch_1):p3e_cpu0_pe1_pch_rxn(9)';
NODE_NAME     U5D1 DP11
 '@BASEBOARD_FAB2_LIB.BASEBOARD_FAB2(SCH_1):PAGE30_I84@CHPSET_LIB.SKX_EXT_B(CHIPS)':
 'PE1_RX_DN'<9>: CDS_PINID='PE1_RX_DN(9)';
NODE_NAME     C3M35 2
 '@BASEBOARD_FAB2_LIB.BASEBOARD_FAB2(SCH_1):PAGE105_I225@MSTR_DISCRETE.CAP(CHIPS)':
 'B': CDS_PINID='B';
NODE_NAME     R782 1
 '@BASEBOARD_FAB2_LIB.BASEBOARD_FAB2(SCH_1):PAGE244_I98@MSTR_DISCRETE.RES(CHIPS)':
 'A': CDS_PINID='A';
NET_NAME
'P3E_CPU0_PE1_PCH_RXP<0>'
 '@BASEBOARD_FAB2_LIB.BASEBOARD_FAB2(SCH_1):P3E_CPU0_PE1_PCH_RXP'<0>:
 C_SIGNAL='@baseboard_fab2_lib.baseboard_fab2(sch_1):p3e_cpu0_pe1_pch_rxp(0)';
NODE_NAME     C2U3 1
 '@BASEBOARD_FAB2_LIB.BASEBOARD_FAB2(SCH_1):PAGE107_I272@MSTR_DISCRETE.CAP(CHIPS)':
 'A': CDS_PINID='A';
NODE_NAME     U7C1 G52
 '@BASEBOARD_FAB2_LIB.BASEBOARD_FAB2(SCH_1):PAGE117_I9@MSTR_U_PROC.LBG_CORE_QAT_EXT_D(CHIPS)':
 'PCIEUP_0_TXP': CDS_PINID='PCIEUP_0_TXP';
NET_NAME
'P3E_CPU0_PE1_PCH_RXP<10>'
 '@BASEBOARD_FAB2_LIB.BASEBOARD_FAB2(SCH_1):P3E_CPU0_PE1_PCH_RXP'<10>:
 C_SIGNAL='@baseboard_fab2_lib.baseboard_fab2(sch_1):p3e_cpu0_pe1_pch_rxp(10)';
NODE_NAME     U5D1 DR12
 '@BASEBOARD_FAB2_LIB.BASEBOARD_FAB2(SCH_1):PAGE30_I84@CHPSET_LIB.SKX_EXT_B(CHIPS)':
 'PE1_RX_DP'<10>: CDS_PINID='PE1_RX_DP(10)';
NODE_NAME     C3M28 2
 '@BASEBOARD_FAB2_LIB.BASEBOARD_FAB2(SCH_1):PAGE105_I212@MSTR_DISCRETE.CAP(CHIPS)':
 'B': CDS_PINID='B';
NODE_NAME     R781 1
 '@BASEBOARD_FAB2_LIB.BASEBOARD_FAB2(SCH_1):PAGE244_I86@MSTR_DISCRETE.RES(CHIPS)':
 'A': CDS_PINID='A';
NET_NAME
'P3E_CPU0_PE1_PCH_RXP<11>'
 '@BASEBOARD_FAB2_LIB.BASEBOARD_FAB2(SCH_1):P3E_CPU0_PE1_PCH_RXP'<11>:
 C_SIGNAL='@baseboard_fab2_lib.baseboard_fab2(sch_1):p3e_cpu0_pe1_pch_rxp(11)';
NODE_NAME     U5D1 DP13
 '@BASEBOARD_FAB2_LIB.BASEBOARD_FAB2(SCH_1):PAGE30_I84@CHPSET_LIB.SKX_EXT_B(CHIPS)':
 'PE1_RX_DP'<11>: CDS_PINID='PE1_RX_DP(11)';
NODE_NAME     C3M25 2
 '@BASEBOARD_FAB2_LIB.BASEBOARD_FAB2(SCH_1):PAGE105_I205@MSTR_DISCRETE.CAP(CHIPS)':
 'B': CDS_PINID='B';
NODE_NAME     R779 1
 '@BASEBOARD_FAB2_LIB.BASEBOARD_FAB2(SCH_1):PAGE244_I74@MSTR_DISCRETE.RES(CHIPS)':
 'A': CDS_PINID='A';
NET_NAME
'P3E_CPU0_PE1_PCH_RXP<12>'
 '@BASEBOARD_FAB2_LIB.BASEBOARD_FAB2(SCH_1):P3E_CPU0_PE1_PCH_RXP'<12>:
 C_SIGNAL='@baseboard_fab2_lib.baseboard_fab2(sch_1):p3e_cpu0_pe1_pch_rxp(12)';
NODE_NAME     U5D1 DU12
 '@BASEBOARD_FAB2_LIB.BASEBOARD_FAB2(SCH_1):PAGE30_I84@CHPSET_LIB.SKX_EXT_B(CHIPS)':
 'PE1_RX_DP'<12>: CDS_PINID='PE1_RX_DP(12)';
NODE_NAME     C3M3 2
 '@BASEBOARD_FAB2_LIB.BASEBOARD_FAB2(SCH_1):PAGE105_I232@MSTR_DISCRETE.CAP(CHIPS)':
 'B': CDS_PINID='B';
NODE_NAME     R777 1
 '@BASEBOARD_FAB2_LIB.BASEBOARD_FAB2(SCH_1):PAGE244_I80@MSTR_DISCRETE.RES(CHIPS)':
 'A': CDS_PINID='A';
NET_NAME
'P3E_CPU0_PE1_PCH_RXP<13>'
 '@BASEBOARD_FAB2_LIB.BASEBOARD_FAB2(SCH_1):P3E_CPU0_PE1_PCH_RXP'<13>:
 C_SIGNAL='@baseboard_fab2_lib.baseboard_fab2(sch_1):p3e_cpu0_pe1_pch_rxp(13)';
NODE_NAME     U5D1 DY13
 '@BASEBOARD_FAB2_LIB.BASEBOARD_FAB2(SCH_1):PAGE30_I84@CHPSET_LIB.SKX_EXT_B(CHIPS)':
 'PE1_RX_DP'<13>: CDS_PINID='PE1_RX_DP(13)';
NODE_NAME     C3M13 2
 '@BASEBOARD_FAB2_LIB.BASEBOARD_FAB2(SCH_1):PAGE105_I239@MSTR_DISCRETE.CAP(CHIPS)':
 'B': CDS_PINID='B';
NODE_NAME     R774 1
 '@BASEBOARD_FAB2_LIB.BASEBOARD_FAB2(SCH_1):PAGE244_I72@MSTR_DISCRETE.RES(CHIPS)':
 'A': CDS_PINID='A';
NET_NAME
'P3E_CPU0_PE1_PCH_RXP<14>'
 '@BASEBOARD_FAB2_LIB.BASEBOARD_FAB2(SCH_1):P3E_CPU0_PE1_PCH_RXP'<14>:
 C_SIGNAL='@baseboard_fab2_lib.baseboard_fab2(sch_1):p3e_cpu0_pe1_pch_rxp(14)';
NODE_NAME     U5D1 DV15
 '@BASEBOARD_FAB2_LIB.BASEBOARD_FAB2(SCH_1):PAGE30_I84@CHPSET_LIB.SKX_EXT_B(CHIPS)':
 'PE1_RX_DP'<14>: CDS_PINID='PE1_RX_DP(14)';
NODE_NAME     C3M11 2
 '@BASEBOARD_FAB2_LIB.BASEBOARD_FAB2(SCH_1):PAGE105_I234@MSTR_DISCRETE.CAP(CHIPS)':
 'B': CDS_PINID='B';
NODE_NAME     R769 1
 '@BASEBOARD_FAB2_LIB.BASEBOARD_FAB2(SCH_1):PAGE244_I58@MSTR_DISCRETE.RES(CHIPS)':
 'A': CDS_PINID='A';
NET_NAME
'P3E_CPU0_PE1_PCH_RXP<15>'
 '@BASEBOARD_FAB2_LIB.BASEBOARD_FAB2(SCH_1):P3E_CPU0_PE1_PCH_RXP'<15>:
 C_SIGNAL='@baseboard_fab2_lib.baseboard_fab2(sch_1):p3e_cpu0_pe1_pch_rxp(15)';
NODE_NAME     U5D1 DT15
 '@BASEBOARD_FAB2_LIB.BASEBOARD_FAB2(SCH_1):PAGE30_I84@CHPSET_LIB.SKX_EXT_B(CHIPS)':
 'PE1_RX_DP'<15>: CDS_PINID='PE1_RX_DP(15)';
NODE_NAME     C3M2 2
 '@BASEBOARD_FAB2_LIB.BASEBOARD_FAB2(SCH_1):PAGE105_I247@MSTR_DISCRETE.CAP(CHIPS)':
 'B': CDS_PINID='B';
NODE_NAME     R767 1
 '@BASEBOARD_FAB2_LIB.BASEBOARD_FAB2(SCH_1):PAGE244_I39@MSTR_DISCRETE.RES(CHIPS)':
 'A': CDS_PINID='A';
NET_NAME
'P3E_CPU0_PE1_PCH_RXP<1>'
 '@BASEBOARD_FAB2_LIB.BASEBOARD_FAB2(SCH_1):P3E_CPU0_PE1_PCH_RXP'<1>:
 C_SIGNAL='@baseboard_fab2_lib.baseboard_fab2(sch_1):p3e_cpu0_pe1_pch_rxp(1)';
NODE_NAME     C2U5 1
 '@BASEBOARD_FAB2_LIB.BASEBOARD_FAB2(SCH_1):PAGE107_I274@MSTR_DISCRETE.CAP(CHIPS)':
 'A': CDS_PINID='A';
NODE_NAME     U7C1 M56
 '@BASEBOARD_FAB2_LIB.BASEBOARD_FAB2(SCH_1):PAGE117_I9@MSTR_U_PROC.LBG_CORE_QAT_EXT_D(CHIPS)':
 'PCIEUP_1_TXP': CDS_PINID='PCIEUP_1_TXP';
NET_NAME
'P3E_CPU0_PE1_PCH_RXP<2>'
 '@BASEBOARD_FAB2_LIB.BASEBOARD_FAB2(SCH_1):P3E_CPU0_PE1_PCH_RXP'<2>:
 C_SIGNAL='@baseboard_fab2_lib.baseboard_fab2(sch_1):p3e_cpu0_pe1_pch_rxp(2)';
NODE_NAME     C2U7 1
 '@BASEBOARD_FAB2_LIB.BASEBOARD_FAB2(SCH_1):PAGE107_I277@MSTR_DISCRETE.CAP(CHIPS)':
 'A': CDS_PINID='A';
NODE_NAME     U7C1 G56
 '@BASEBOARD_FAB2_LIB.BASEBOARD_FAB2(SCH_1):PAGE117_I9@MSTR_U_PROC.LBG_CORE_QAT_EXT_D(CHIPS)':
 'PCIEUP_2_TXP': CDS_PINID='PCIEUP_2_TXP';
NET_NAME
'P3E_CPU0_PE1_PCH_RXP<3>'
 '@BASEBOARD_FAB2_LIB.BASEBOARD_FAB2(SCH_1):P3E_CPU0_PE1_PCH_RXP'<3>:
 C_SIGNAL='@baseboard_fab2_lib.baseboard_fab2(sch_1):p3e_cpu0_pe1_pch_rxp(3)';
NODE_NAME     C2U9 1
 '@BASEBOARD_FAB2_LIB.BASEBOARD_FAB2(SCH_1):PAGE107_I279@MSTR_DISCRETE.CAP(CHIPS)':
 'A': CDS_PINID='A';
NODE_NAME     U7C1 K58
 '@BASEBOARD_FAB2_LIB.BASEBOARD_FAB2(SCH_1):PAGE117_I9@MSTR_U_PROC.LBG_CORE_QAT_EXT_D(CHIPS)':
 'PCIEUP_3_TXP': CDS_PINID='PCIEUP_3_TXP';
NET_NAME
'P3E_CPU0_PE1_PCH_RXP<4>'
 '@BASEBOARD_FAB2_LIB.BASEBOARD_FAB2(SCH_1):P3E_CPU0_PE1_PCH_RXP'<4>:
 C_SIGNAL='@baseboard_fab2_lib.baseboard_fab2(sch_1):p3e_cpu0_pe1_pch_rxp(4)';
NODE_NAME     C2U11 1
 '@BASEBOARD_FAB2_LIB.BASEBOARD_FAB2(SCH_1):PAGE107_I278@MSTR_DISCRETE.CAP(CHIPS)':
 'A': CDS_PINID='A';
NODE_NAME     U7C1 M59
 '@BASEBOARD_FAB2_LIB.BASEBOARD_FAB2(SCH_1):PAGE117_I9@MSTR_U_PROC.LBG_CORE_QAT_EXT_D(CHIPS)':
 'PCIEUP_4_TXP': CDS_PINID='PCIEUP_4_TXP';
NET_NAME
'P3E_CPU0_PE1_PCH_RXP<5>'
 '@BASEBOARD_FAB2_LIB.BASEBOARD_FAB2(SCH_1):P3E_CPU0_PE1_PCH_RXP'<5>:
 C_SIGNAL='@baseboard_fab2_lib.baseboard_fab2(sch_1):p3e_cpu0_pe1_pch_rxp(5)';
NODE_NAME     C2U13 1
 '@BASEBOARD_FAB2_LIB.BASEBOARD_FAB2(SCH_1):PAGE107_I297@MSTR_DISCRETE.CAP(CHIPS)':
 'A': CDS_PINID='A';
NODE_NAME     U7C1 K61
 '@BASEBOARD_FAB2_LIB.BASEBOARD_FAB2(SCH_1):PAGE117_I9@MSTR_U_PROC.LBG_CORE_QAT_EXT_D(CHIPS)':
 'PCIEUP_5_TXP': CDS_PINID='PCIEUP_5_TXP';
NET_NAME
'P3E_CPU0_PE1_PCH_RXP<6>'
 '@BASEBOARD_FAB2_LIB.BASEBOARD_FAB2(SCH_1):P3E_CPU0_PE1_PCH_RXP'<6>:
 C_SIGNAL='@baseboard_fab2_lib.baseboard_fab2(sch_1):p3e_cpu0_pe1_pch_rxp(6)';
NODE_NAME     C2U15 1
 '@BASEBOARD_FAB2_LIB.BASEBOARD_FAB2(SCH_1):PAGE107_I296@MSTR_DISCRETE.CAP(CHIPS)':
 'A': CDS_PINID='A';
NODE_NAME     U7C1 J63
 '@BASEBOARD_FAB2_LIB.BASEBOARD_FAB2(SCH_1):PAGE117_I9@MSTR_U_PROC.LBG_CORE_QAT_EXT_D(CHIPS)':
 'PCIEUP_6_TXP': CDS_PINID='PCIEUP_6_TXP';
NET_NAME
'P3E_CPU0_PE1_PCH_RXP<7>'
 '@BASEBOARD_FAB2_LIB.BASEBOARD_FAB2(SCH_1):P3E_CPU0_PE1_PCH_RXP'<7>:
 C_SIGNAL='@baseboard_fab2_lib.baseboard_fab2(sch_1):p3e_cpu0_pe1_pch_rxp(7)';
NODE_NAME     C2U17 1
 '@BASEBOARD_FAB2_LIB.BASEBOARD_FAB2(SCH_1):PAGE107_I300@MSTR_DISCRETE.CAP(CHIPS)':
 'A': CDS_PINID='A';
NODE_NAME     U7C1 R61
 '@BASEBOARD_FAB2_LIB.BASEBOARD_FAB2(SCH_1):PAGE117_I9@MSTR_U_PROC.LBG_CORE_QAT_EXT_D(CHIPS)':
 'PCIEUP_7_TXP': CDS_PINID='PCIEUP_7_TXP';
NET_NAME
'P3E_CPU0_PE1_PCH_RXP<8>'
 '@BASEBOARD_FAB2_LIB.BASEBOARD_FAB2(SCH_1):P3E_CPU0_PE1_PCH_RXP'<8>:
 C_SIGNAL='@baseboard_fab2_lib.baseboard_fab2(sch_1):p3e_cpu0_pe1_pch_rxp(8)';
NODE_NAME     U5D1 DK11
 '@BASEBOARD_FAB2_LIB.BASEBOARD_FAB2(SCH_1):PAGE30_I84@CHPSET_LIB.SKX_EXT_B(CHIPS)':
 'PE1_RX_DP'<8>: CDS_PINID='PE1_RX_DP(8)';
NODE_NAME     C3M34 2
 '@BASEBOARD_FAB2_LIB.BASEBOARD_FAB2(SCH_1):PAGE105_I206@MSTR_DISCRETE.CAP(CHIPS)':
 'B': CDS_PINID='B';
NODE_NAME     R785 1
 '@BASEBOARD_FAB2_LIB.BASEBOARD_FAB2(SCH_1):PAGE244_I103@MSTR_DISCRETE.RES(CHIPS)':
 'A': CDS_PINID='A';
NET_NAME
'P3E_CPU0_PE1_PCH_RXP<9>'
 '@BASEBOARD_FAB2_LIB.BASEBOARD_FAB2(SCH_1):P3E_CPU0_PE1_PCH_RXP'<9>:
 C_SIGNAL='@baseboard_fab2_lib.baseboard_fab2(sch_1):p3e_cpu0_pe1_pch_rxp(9)';
NODE_NAME     U5D1 DN10
 '@BASEBOARD_FAB2_LIB.BASEBOARD_FAB2(SCH_1):PAGE30_I84@CHPSET_LIB.SKX_EXT_B(CHIPS)':
 'PE1_RX_DP'<9>: CDS_PINID='PE1_RX_DP(9)';
NODE_NAME     C3M36 2
 '@BASEBOARD_FAB2_LIB.BASEBOARD_FAB2(SCH_1):PAGE105_I218@MSTR_DISCRETE.CAP(CHIPS)':
 'B': CDS_PINID='B';
NODE_NAME     R783 1
 '@BASEBOARD_FAB2_LIB.BASEBOARD_FAB2(SCH_1):PAGE244_I77@MSTR_DISCRETE.RES(CHIPS)':
 'A': CDS_PINID='A';
NET_NAME
'P3E_CPU0_PE1_PCH_R_RXN<10>'
 '@BASEBOARD_FAB2_LIB.BASEBOARD_FAB2(SCH_1):P3E_CPU0_PE1_PCH_R_RXN'<10>:
 C_SIGNAL='@baseboard_fab2_lib.baseboard_fab2(sch_1):p3e_cpu0_pe1_pch_r_rxn(10)';
NODE_NAME     C3M32 1
 '@BASEBOARD_FAB2_LIB.BASEBOARD_FAB2(SCH_1):PAGE105_I223@MSTR_DISCRETE.CAP(CHIPS)':
 'A': CDS_PINID='A';
NODE_NAME     U7C1 N65
 '@BASEBOARD_FAB2_LIB.BASEBOARD_FAB2(SCH_1):PAGE117_I9@MSTR_U_PROC.LBG_CORE_QAT_EXT_D(CHIPS)':
 'PCIEUP_10_TXN': CDS_PINID='PCIEUP_10_TXN';
NET_NAME
'P3E_CPU0_PE1_PCH_R_RXN<11>'
 '@BASEBOARD_FAB2_LIB.BASEBOARD_FAB2(SCH_1):P3E_CPU0_PE1_PCH_R_RXN'<11>:
 C_SIGNAL='@baseboard_fab2_lib.baseboard_fab2(sch_1):p3e_cpu0_pe1_pch_r_rxn(11)';
NODE_NAME     C3M26 1
 '@BASEBOARD_FAB2_LIB.BASEBOARD_FAB2(SCH_1):PAGE105_I229@MSTR_DISCRETE.CAP(CHIPS)':
 'A': CDS_PINID='A';
NODE_NAME     U7C1 T59
 '@BASEBOARD_FAB2_LIB.BASEBOARD_FAB2(SCH_1):PAGE117_I9@MSTR_U_PROC.LBG_CORE_QAT_EXT_D(CHIPS)':
 'PCIEUP_11_TXN': CDS_PINID='PCIEUP_11_TXN';
NET_NAME
'P3E_CPU0_PE1_PCH_R_RXN<12>'
 '@BASEBOARD_FAB2_LIB.BASEBOARD_FAB2(SCH_1):P3E_CPU0_PE1_PCH_R_RXN'<12>:
 C_SIGNAL='@baseboard_fab2_lib.baseboard_fab2(sch_1):p3e_cpu0_pe1_pch_r_rxn(12)';
NODE_NAME     C3M4 1
 '@BASEBOARD_FAB2_LIB.BASEBOARD_FAB2(SCH_1):PAGE105_I244@MSTR_DISCRETE.CAP(CHIPS)':
 'A': CDS_PINID='A';
NODE_NAME     U7C1 R65
 '@BASEBOARD_FAB2_LIB.BASEBOARD_FAB2(SCH_1):PAGE117_I9@MSTR_U_PROC.LBG_CORE_QAT_EXT_D(CHIPS)':
 'PCIEUP_12_TXN': CDS_PINID='PCIEUP_12_TXN';
NET_NAME
'P3E_CPU0_PE1_PCH_R_RXN<13>'
 '@BASEBOARD_FAB2_LIB.BASEBOARD_FAB2(SCH_1):P3E_CPU0_PE1_PCH_R_RXN'<13>:
 C_SIGNAL='@baseboard_fab2_lib.baseboard_fab2(sch_1):p3e_cpu0_pe1_pch_r_rxn(13)';
NODE_NAME     C3M14 1
 '@BASEBOARD_FAB2_LIB.BASEBOARD_FAB2(SCH_1):PAGE105_I253@MSTR_DISCRETE.CAP(CHIPS)':
 'A': CDS_PINID='A';
NODE_NAME     U7C1 T63
 '@BASEBOARD_FAB2_LIB.BASEBOARD_FAB2(SCH_1):PAGE117_I9@MSTR_U_PROC.LBG_CORE_QAT_EXT_D(CHIPS)':
 'PCIEUP_13_TXN': CDS_PINID='PCIEUP_13_TXN';
NET_NAME
'P3E_CPU0_PE1_PCH_R_RXN<14>'
 '@BASEBOARD_FAB2_LIB.BASEBOARD_FAB2(SCH_1):P3E_CPU0_PE1_PCH_R_RXN'<14>:
 C_SIGNAL='@baseboard_fab2_lib.baseboard_fab2(sch_1):p3e_cpu0_pe1_pch_r_rxn(14)';
NODE_NAME     C3M12 1
 '@BASEBOARD_FAB2_LIB.BASEBOARD_FAB2(SCH_1):PAGE105_I246@MSTR_DISCRETE.CAP(CHIPS)':
 'A': CDS_PINID='A';
NODE_NAME     U7C1 W65
 '@BASEBOARD_FAB2_LIB.BASEBOARD_FAB2(SCH_1):PAGE117_I9@MSTR_U_PROC.LBG_CORE_QAT_EXT_D(CHIPS)':
 'PCIEUP_14_TXN': CDS_PINID='PCIEUP_14_TXN';
NET_NAME
'P3E_CPU0_PE1_PCH_R_RXN<15>'
 '@BASEBOARD_FAB2_LIB.BASEBOARD_FAB2(SCH_1):P3E_CPU0_PE1_PCH_R_RXN'<15>:
 C_SIGNAL='@baseboard_fab2_lib.baseboard_fab2(sch_1):p3e_cpu0_pe1_pch_r_rxn(15)';
NODE_NAME     C3M1 1
 '@BASEBOARD_FAB2_LIB.BASEBOARD_FAB2(SCH_1):PAGE105_I255@MSTR_DISCRETE.CAP(CHIPS)':
 'A': CDS_PINID='A';
NODE_NAME     U7C1 Y66
 '@BASEBOARD_FAB2_LIB.BASEBOARD_FAB2(SCH_1):PAGE117_I9@MSTR_U_PROC.LBG_CORE_QAT_EXT_D(CHIPS)':
 'PCIEUP_15_TXN': CDS_PINID='PCIEUP_15_TXN';
NET_NAME
'P3E_CPU0_PE1_PCH_R_RXN<8>'
 '@BASEBOARD_FAB2_LIB.BASEBOARD_FAB2(SCH_1):P3E_CPU0_PE1_PCH_R_RXN'<8>:
 C_SIGNAL='@baseboard_fab2_lib.baseboard_fab2(sch_1):p3e_cpu0_pe1_pch_r_rxn(8)';
NODE_NAME     C3M33 1
 '@BASEBOARD_FAB2_LIB.BASEBOARD_FAB2(SCH_1):PAGE105_I217@MSTR_DISCRETE.CAP(CHIPS)':
 'A': CDS_PINID='A';
NODE_NAME     U7C1 K65
 '@BASEBOARD_FAB2_LIB.BASEBOARD_FAB2(SCH_1):PAGE117_I9@MSTR_U_PROC.LBG_CORE_QAT_EXT_D(CHIPS)':
 'PCIEUP_8_TXN': CDS_PINID='PCIEUP_8_TXN';
NET_NAME
'P3E_CPU0_PE1_PCH_R_RXN<9>'
 '@BASEBOARD_FAB2_LIB.BASEBOARD_FAB2(SCH_1):P3E_CPU0_PE1_PCH_R_RXN'<9>:
 C_SIGNAL='@baseboard_fab2_lib.baseboard_fab2(sch_1):p3e_cpu0_pe1_pch_r_rxn(9)';
NODE_NAME     C3M35 1
 '@BASEBOARD_FAB2_LIB.BASEBOARD_FAB2(SCH_1):PAGE105_I225@MSTR_DISCRETE.CAP(CHIPS)':
 'A': CDS_PINID='A';
NODE_NAME     U7C1 J66
 '@BASEBOARD_FAB2_LIB.BASEBOARD_FAB2(SCH_1):PAGE117_I9@MSTR_U_PROC.LBG_CORE_QAT_EXT_D(CHIPS)':
 'PCIEUP_9_TXN': CDS_PINID='PCIEUP_9_TXN';
NET_NAME
'P3E_CPU0_PE1_PCH_R_RXP<10>'
 '@BASEBOARD_FAB2_LIB.BASEBOARD_FAB2(SCH_1):P3E_CPU0_PE1_PCH_R_RXP'<10>:
 C_SIGNAL='@baseboard_fab2_lib.baseboard_fab2(sch_1):p3e_cpu0_pe1_pch_r_rxp(10)';
NODE_NAME     C3M28 1
 '@BASEBOARD_FAB2_LIB.BASEBOARD_FAB2(SCH_1):PAGE105_I212@MSTR_DISCRETE.CAP(CHIPS)':
 'A': CDS_PINID='A';
NODE_NAME     U7C1 P66
 '@BASEBOARD_FAB2_LIB.BASEBOARD_FAB2(SCH_1):PAGE117_I9@MSTR_U_PROC.LBG_CORE_QAT_EXT_D(CHIPS)':
 'PCIEUP_10_TXP': CDS_PINID='PCIEUP_10_TXP';
NET_NAME
'P3E_CPU0_PE1_PCH_R_RXP<11>'
 '@BASEBOARD_FAB2_LIB.BASEBOARD_FAB2(SCH_1):P3E_CPU0_PE1_PCH_R_RXP'<11>:
 C_SIGNAL='@baseboard_fab2_lib.baseboard_fab2(sch_1):p3e_cpu0_pe1_pch_r_rxp(11)';
NODE_NAME     C3M25 1
 '@BASEBOARD_FAB2_LIB.BASEBOARD_FAB2(SCH_1):PAGE105_I205@MSTR_DISCRETE.CAP(CHIPS)':
 'A': CDS_PINID='A';
NODE_NAME     U7C1 V59
 '@BASEBOARD_FAB2_LIB.BASEBOARD_FAB2(SCH_1):PAGE117_I9@MSTR_U_PROC.LBG_CORE_QAT_EXT_D(CHIPS)':
 'PCIEUP_11_TXP': CDS_PINID='PCIEUP_11_TXP';
NET_NAME
'P3E_CPU0_PE1_PCH_R_RXP<12>'
 '@BASEBOARD_FAB2_LIB.BASEBOARD_FAB2(SCH_1):P3E_CPU0_PE1_PCH_R_RXP'<12>:
 C_SIGNAL='@baseboard_fab2_lib.baseboard_fab2(sch_1):p3e_cpu0_pe1_pch_r_rxp(12)';
NODE_NAME     C3M3 1
 '@BASEBOARD_FAB2_LIB.BASEBOARD_FAB2(SCH_1):PAGE105_I232@MSTR_DISCRETE.CAP(CHIPS)':
 'A': CDS_PINID='A';
NODE_NAME     U7C1 U65
 '@BASEBOARD_FAB2_LIB.BASEBOARD_FAB2(SCH_1):PAGE117_I9@MSTR_U_PROC.LBG_CORE_QAT_EXT_D(CHIPS)':
 'PCIEUP_12_TXP': CDS_PINID='PCIEUP_12_TXP';
NET_NAME
'P3E_CPU0_PE1_PCH_R_RXP<13>'
 '@BASEBOARD_FAB2_LIB.BASEBOARD_FAB2(SCH_1):P3E_CPU0_PE1_PCH_R_RXP'<13>:
 C_SIGNAL='@baseboard_fab2_lib.baseboard_fab2(sch_1):p3e_cpu0_pe1_pch_r_rxp(13)';
NODE_NAME     C3M13 1
 '@BASEBOARD_FAB2_LIB.BASEBOARD_FAB2(SCH_1):PAGE105_I239@MSTR_DISCRETE.CAP(CHIPS)':
 'A': CDS_PINID='A';
NODE_NAME     U7C1 U61
 '@BASEBOARD_FAB2_LIB.BASEBOARD_FAB2(SCH_1):PAGE117_I9@MSTR_U_PROC.LBG_CORE_QAT_EXT_D(CHIPS)':
 'PCIEUP_13_TXP': CDS_PINID='PCIEUP_13_TXP';
NET_NAME
'P3E_CPU0_PE1_PCH_R_RXP<14>'
 '@BASEBOARD_FAB2_LIB.BASEBOARD_FAB2(SCH_1):P3E_CPU0_PE1_PCH_R_RXP'<14>:
 C_SIGNAL='@baseboard_fab2_lib.baseboard_fab2(sch_1):p3e_cpu0_pe1_pch_r_rxp(14)';
NODE_NAME     C3M11 1
 '@BASEBOARD_FAB2_LIB.BASEBOARD_FAB2(SCH_1):PAGE105_I234@MSTR_DISCRETE.CAP(CHIPS)':
 'A': CDS_PINID='A';
NODE_NAME     U7C1 V63
 '@BASEBOARD_FAB2_LIB.BASEBOARD_FAB2(SCH_1):PAGE117_I9@MSTR_U_PROC.LBG_CORE_QAT_EXT_D(CHIPS)':
 'PCIEUP_14_TXP': CDS_PINID='PCIEUP_14_TXP';
NET_NAME
'P3E_CPU0_PE1_PCH_R_RXP<15>'
 '@BASEBOARD_FAB2_LIB.BASEBOARD_FAB2(SCH_1):P3E_CPU0_PE1_PCH_R_RXP'<15>:
 C_SIGNAL='@baseboard_fab2_lib.baseboard_fab2(sch_1):p3e_cpu0_pe1_pch_r_rxp(15)';
NODE_NAME     C3M2 1
 '@BASEBOARD_FAB2_LIB.BASEBOARD_FAB2(SCH_1):PAGE105_I247@MSTR_DISCRETE.CAP(CHIPS)':
 'A': CDS_PINID='A';
NODE_NAME     U7C1 AA65
 '@BASEBOARD_FAB2_LIB.BASEBOARD_FAB2(SCH_1):PAGE117_I9@MSTR_U_PROC.LBG_CORE_QAT_EXT_D(CHIPS)':
 'PCIEUP_15_TXP': CDS_PINID='PCIEUP_15_TXP';
NET_NAME
'P3E_CPU0_PE1_PCH_R_RXP<8>'
 '@BASEBOARD_FAB2_LIB.BASEBOARD_FAB2(SCH_1):P3E_CPU0_PE1_PCH_R_RXP'<8>:
 C_SIGNAL='@baseboard_fab2_lib.baseboard_fab2(sch_1):p3e_cpu0_pe1_pch_r_rxp(8)';
NODE_NAME     C3M34 1
 '@BASEBOARD_FAB2_LIB.BASEBOARD_FAB2(SCH_1):PAGE105_I206@MSTR_DISCRETE.CAP(CHIPS)':
 'A': CDS_PINID='A';
NODE_NAME     U7C1 M63
 '@BASEBOARD_FAB2_LIB.BASEBOARD_FAB2(SCH_1):PAGE117_I9@MSTR_U_PROC.LBG_CORE_QAT_EXT_D(CHIPS)':
 'PCIEUP_8_TXP': CDS_PINID='PCIEUP_8_TXP';
NET_NAME
'P3E_CPU0_PE1_PCH_R_RXP<9>'
 '@BASEBOARD_FAB2_LIB.BASEBOARD_FAB2(SCH_1):P3E_CPU0_PE1_PCH_R_RXP'<9>:
 C_SIGNAL='@baseboard_fab2_lib.baseboard_fab2(sch_1):p3e_cpu0_pe1_pch_r_rxp(9)';
NODE_NAME     C3M36 1
 '@BASEBOARD_FAB2_LIB.BASEBOARD_FAB2(SCH_1):PAGE105_I218@MSTR_DISCRETE.CAP(CHIPS)':
 'A': CDS_PINID='A';
NODE_NAME     U7C1 M66
 '@BASEBOARD_FAB2_LIB.BASEBOARD_FAB2(SCH_1):PAGE117_I9@MSTR_U_PROC.LBG_CORE_QAT_EXT_D(CHIPS)':
 'PCIEUP_9_TXP': CDS_PINID='PCIEUP_9_TXP';
NET_NAME
'P3E_CPU0_PE1_PCH_TXN<0>'
 '@BASEBOARD_FAB2_LIB.BASEBOARD_FAB2(SCH_1):P3E_CPU0_PE1_PCH_TXN'<0>:
 C_SIGNAL='@baseboard_fab2_lib.baseboard_fab2(sch_1):p3e_cpu0_pe1_pch_txn(0)';
NODE_NAME     C3P13 2
 '@BASEBOARD_FAB2_LIB.BASEBOARD_FAB2(SCH_1):PAGE107_I207@MSTR_DISCRETE.CAP(CHIPS)':
 'B': CDS_PINID='B';
NODE_NAME     U7C1 C48
 '@BASEBOARD_FAB2_LIB.BASEBOARD_FAB2(SCH_1):PAGE117_I9@MSTR_U_PROC.LBG_CORE_QAT_EXT_D(CHIPS)':
 'PCIEUP_0_RXN': CDS_PINID='PCIEUP_0_RXN';
NET_NAME
'P3E_CPU0_PE1_PCH_TXN<10>'
 '@BASEBOARD_FAB2_LIB.BASEBOARD_FAB2(SCH_1):P3E_CPU0_PE1_PCH_TXN'<10>:
 C_SIGNAL='@baseboard_fab2_lib.baseboard_fab2(sch_1):p3e_cpu0_pe1_pch_txn(10)';
NODE_NAME     U5D1 DW4
 '@BASEBOARD_FAB2_LIB.BASEBOARD_FAB2(SCH_1):PAGE30_I84@CHPSET_LIB.SKX_EXT_B(CHIPS)':
 'PE1_TX_DN'<10>: CDS_PINID='PE1_TX_DN(10)';
NODE_NAME     C6B15 1
 '@BASEBOARD_FAB2_LIB.BASEBOARD_FAB2(SCH_1):PAGE105_I163@MSTR_DISCRETE.CAP(CHIPS)':
 'A': CDS_PINID='A';
NODE_NAME     C834 1
 '@BASEBOARD_FAB2_LIB.BASEBOARD_FAB2(SCH_1):PAGE244_I50@MSTR_DISCRETE.CAP(CHIPS)':
 'A': CDS_PINID='A';
NET_NAME
'P3E_CPU0_PE1_PCH_TXN<11>'
 '@BASEBOARD_FAB2_LIB.BASEBOARD_FAB2(SCH_1):P3E_CPU0_PE1_PCH_TXN'<11>:
 C_SIGNAL='@baseboard_fab2_lib.baseboard_fab2(sch_1):p3e_cpu0_pe1_pch_txn(11)';
NODE_NAME     U5D1 DU6
 '@BASEBOARD_FAB2_LIB.BASEBOARD_FAB2(SCH_1):PAGE30_I84@CHPSET_LIB.SKX_EXT_B(CHIPS)':
 'PE1_TX_DN'<11>: CDS_PINID='PE1_TX_DN(11)';
NODE_NAME     C6B14 1
 '@BASEBOARD_FAB2_LIB.BASEBOARD_FAB2(SCH_1):PAGE105_I181@MSTR_DISCRETE.CAP(CHIPS)':
 'A': CDS_PINID='A';
NODE_NAME     C832 1
 '@BASEBOARD_FAB2_LIB.BASEBOARD_FAB2(SCH_1):PAGE244_I30@MSTR_DISCRETE.CAP(CHIPS)':
 'A': CDS_PINID='A';
NET_NAME
'P3E_CPU0_PE1_PCH_TXN<12>'
 '@BASEBOARD_FAB2_LIB.BASEBOARD_FAB2(SCH_1):P3E_CPU0_PE1_PCH_TXN'<12>:
 C_SIGNAL='@baseboard_fab2_lib.baseboard_fab2(sch_1):p3e_cpu0_pe1_pch_txn(12)';
NODE_NAME     U5D1 DV7
 '@BASEBOARD_FAB2_LIB.BASEBOARD_FAB2(SCH_1):PAGE30_I84@CHPSET_LIB.SKX_EXT_B(CHIPS)':
 'PE1_TX_DN'<12>: CDS_PINID='PE1_TX_DN(12)';
NODE_NAME     C6B11 1
 '@BASEBOARD_FAB2_LIB.BASEBOARD_FAB2(SCH_1):PAGE105_I166@MSTR_DISCRETE.CAP(CHIPS)':
 'A': CDS_PINID='A';
NODE_NAME     C840 1
 '@BASEBOARD_FAB2_LIB.BASEBOARD_FAB2(SCH_1):PAGE244_I29@MSTR_DISCRETE.CAP(CHIPS)':
 'A': CDS_PINID='A';
NET_NAME
'P3E_CPU0_PE1_PCH_TXN<13>'
 '@BASEBOARD_FAB2_LIB.BASEBOARD_FAB2(SCH_1):P3E_CPU0_PE1_PCH_TXN'<13>:
 C_SIGNAL='@baseboard_fab2_lib.baseboard_fab2(sch_1):p3e_cpu0_pe1_pch_txn(13)';
NODE_NAME     U5D1 DY7
 '@BASEBOARD_FAB2_LIB.BASEBOARD_FAB2(SCH_1):PAGE30_I84@CHPSET_LIB.SKX_EXT_B(CHIPS)':
 'PE1_TX_DN'<13>: CDS_PINID='PE1_TX_DN(13)';
NODE_NAME     C6B9 1
 '@BASEBOARD_FAB2_LIB.BASEBOARD_FAB2(SCH_1):PAGE105_I185@MSTR_DISCRETE.CAP(CHIPS)':
 'A': CDS_PINID='A';
NODE_NAME     C828 1
 '@BASEBOARD_FAB2_LIB.BASEBOARD_FAB2(SCH_1):PAGE244_I28@MSTR_DISCRETE.CAP(CHIPS)':
 'A': CDS_PINID='A';
NET_NAME
'P3E_CPU0_PE1_PCH_TXN<14>'
 '@BASEBOARD_FAB2_LIB.BASEBOARD_FAB2(SCH_1):P3E_CPU0_PE1_PCH_TXN'<14>:
 C_SIGNAL='@baseboard_fab2_lib.baseboard_fab2(sch_1):p3e_cpu0_pe1_pch_txn(14)';
NODE_NAME     U5D1 EA8
 '@BASEBOARD_FAB2_LIB.BASEBOARD_FAB2(SCH_1):PAGE30_I84@CHPSET_LIB.SKX_EXT_B(CHIPS)':
 'PE1_TX_DN'<14>: CDS_PINID='PE1_TX_DN(14)';
NODE_NAME     C6B6 1
 '@BASEBOARD_FAB2_LIB.BASEBOARD_FAB2(SCH_1):PAGE105_I169@MSTR_DISCRETE.CAP(CHIPS)':
 'A': CDS_PINID='A';
NODE_NAME     C826 1
 '@BASEBOARD_FAB2_LIB.BASEBOARD_FAB2(SCH_1):PAGE244_I24@MSTR_DISCRETE.CAP(CHIPS)':
 'A': CDS_PINID='A';
NET_NAME
'P3E_CPU0_PE1_PCH_TXN<15>'
 '@BASEBOARD_FAB2_LIB.BASEBOARD_FAB2(SCH_1):P3E_CPU0_PE1_PCH_TXN'<15>:
 C_SIGNAL='@baseboard_fab2_lib.baseboard_fab2(sch_1):p3e_cpu0_pe1_pch_txn(15)';
NODE_NAME     U5D1 ED9
 '@BASEBOARD_FAB2_LIB.BASEBOARD_FAB2(SCH_1):PAGE30_I84@CHPSET_LIB.SKX_EXT_B(CHIPS)':
 'PE1_TX_DN'<15>: CDS_PINID='PE1_TX_DN(15)';
NODE_NAME     C6B4 1
 '@BASEBOARD_FAB2_LIB.BASEBOARD_FAB2(SCH_1):PAGE105_I196@MSTR_DISCRETE.CAP(CHIPS)':
 'A': CDS_PINID='A';
NODE_NAME     C830 1
 '@BASEBOARD_FAB2_LIB.BASEBOARD_FAB2(SCH_1):PAGE244_I23@MSTR_DISCRETE.CAP(CHIPS)':
 'A': CDS_PINID='A';
NET_NAME
'P3E_CPU0_PE1_PCH_TXN<1>'
 '@BASEBOARD_FAB2_LIB.BASEBOARD_FAB2(SCH_1):P3E_CPU0_PE1_PCH_TXN'<1>:
 C_SIGNAL='@baseboard_fab2_lib.baseboard_fab2(sch_1):p3e_cpu0_pe1_pch_txn(1)';
NODE_NAME     C3P17 2
 '@BASEBOARD_FAB2_LIB.BASEBOARD_FAB2(SCH_1):PAGE107_I208@MSTR_DISCRETE.CAP(CHIPS)':
 'B': CDS_PINID='B';
NODE_NAME     U7C1 D49
 '@BASEBOARD_FAB2_LIB.BASEBOARD_FAB2(SCH_1):PAGE117_I9@MSTR_U_PROC.LBG_CORE_QAT_EXT_D(CHIPS)':
 'PCIEUP_1_RXN': CDS_PINID='PCIEUP_1_RXN';
NET_NAME
'P3E_CPU0_PE1_PCH_TXN<2>'
 '@BASEBOARD_FAB2_LIB.BASEBOARD_FAB2(SCH_1):P3E_CPU0_PE1_PCH_TXN'<2>:
 C_SIGNAL='@baseboard_fab2_lib.baseboard_fab2(sch_1):p3e_cpu0_pe1_pch_txn(2)';
NODE_NAME     C3P20 2
 '@BASEBOARD_FAB2_LIB.BASEBOARD_FAB2(SCH_1):PAGE107_I215@MSTR_DISCRETE.CAP(CHIPS)':
 'B': CDS_PINID='B';
NODE_NAME     U7C1 C50
 '@BASEBOARD_FAB2_LIB.BASEBOARD_FAB2(SCH_1):PAGE117_I9@MSTR_U_PROC.LBG_CORE_QAT_EXT_D(CHIPS)':
 'PCIEUP_2_RXN': CDS_PINID='PCIEUP_2_RXN';
NET_NAME
'P3E_CPU0_PE1_PCH_TXN<3>'
 '@BASEBOARD_FAB2_LIB.BASEBOARD_FAB2(SCH_1):P3E_CPU0_PE1_PCH_TXN'<3>:
 C_SIGNAL='@baseboard_fab2_lib.baseboard_fab2(sch_1):p3e_cpu0_pe1_pch_txn(3)';
NODE_NAME     C3P25 2
 '@BASEBOARD_FAB2_LIB.BASEBOARD_FAB2(SCH_1):PAGE107_I216@MSTR_DISCRETE.CAP(CHIPS)':
 'B': CDS_PINID='B';
NODE_NAME     U7C1 D51
 '@BASEBOARD_FAB2_LIB.BASEBOARD_FAB2(SCH_1):PAGE117_I9@MSTR_U_PROC.LBG_CORE_QAT_EXT_D(CHIPS)':
 'PCIEUP_3_RXN': CDS_PINID='PCIEUP_3_RXN';
NET_NAME
'P3E_CPU0_PE1_PCH_TXN<4>'
 '@BASEBOARD_FAB2_LIB.BASEBOARD_FAB2(SCH_1):P3E_CPU0_PE1_PCH_TXN'<4>:
 C_SIGNAL='@baseboard_fab2_lib.baseboard_fab2(sch_1):p3e_cpu0_pe1_pch_txn(4)';
NODE_NAME     C3P28 2
 '@BASEBOARD_FAB2_LIB.BASEBOARD_FAB2(SCH_1):PAGE107_I232@MSTR_DISCRETE.CAP(CHIPS)':
 'B': CDS_PINID='B';
NODE_NAME     U7C1 C52
 '@BASEBOARD_FAB2_LIB.BASEBOARD_FAB2(SCH_1):PAGE117_I9@MSTR_U_PROC.LBG_CORE_QAT_EXT_D(CHIPS)':
 'PCIEUP_4_RXN': CDS_PINID='PCIEUP_4_RXN';
NET_NAME
'P3E_CPU0_PE1_PCH_TXN<5>'
 '@BASEBOARD_FAB2_LIB.BASEBOARD_FAB2(SCH_1):P3E_CPU0_PE1_PCH_TXN'<5>:
 C_SIGNAL='@baseboard_fab2_lib.baseboard_fab2(sch_1):p3e_cpu0_pe1_pch_txn(5)';
NODE_NAME     C3P32 2
 '@BASEBOARD_FAB2_LIB.BASEBOARD_FAB2(SCH_1):PAGE107_I234@MSTR_DISCRETE.CAP(CHIPS)':
 'B': CDS_PINID='B';
NODE_NAME     U7C1 D53
 '@BASEBOARD_FAB2_LIB.BASEBOARD_FAB2(SCH_1):PAGE117_I9@MSTR_U_PROC.LBG_CORE_QAT_EXT_D(CHIPS)':
 'PCIEUP_5_RXN': CDS_PINID='PCIEUP_5_RXN';
NET_NAME
'P3E_CPU0_PE1_PCH_TXN<6>'
 '@BASEBOARD_FAB2_LIB.BASEBOARD_FAB2(SCH_1):P3E_CPU0_PE1_PCH_TXN'<6>:
 C_SIGNAL='@baseboard_fab2_lib.baseboard_fab2(sch_1):p3e_cpu0_pe1_pch_txn(6)';
NODE_NAME     C3P37 2
 '@BASEBOARD_FAB2_LIB.BASEBOARD_FAB2(SCH_1):PAGE107_I235@MSTR_DISCRETE.CAP(CHIPS)':
 'B': CDS_PINID='B';
NODE_NAME     U7C1 C54
 '@BASEBOARD_FAB2_LIB.BASEBOARD_FAB2(SCH_1):PAGE117_I9@MSTR_U_PROC.LBG_CORE_QAT_EXT_D(CHIPS)':
 'PCIEUP_6_RXN': CDS_PINID='PCIEUP_6_RXN';
NET_NAME
'P3E_CPU0_PE1_PCH_TXN<7>'
 '@BASEBOARD_FAB2_LIB.BASEBOARD_FAB2(SCH_1):P3E_CPU0_PE1_PCH_TXN'<7>:
 C_SIGNAL='@baseboard_fab2_lib.baseboard_fab2(sch_1):p3e_cpu0_pe1_pch_txn(7)';
NODE_NAME     C3P40 2
 '@BASEBOARD_FAB2_LIB.BASEBOARD_FAB2(SCH_1):PAGE107_I241@MSTR_DISCRETE.CAP(CHIPS)':
 'B': CDS_PINID='B';
NODE_NAME     U7C1 D55
 '@BASEBOARD_FAB2_LIB.BASEBOARD_FAB2(SCH_1):PAGE117_I9@MSTR_U_PROC.LBG_CORE_QAT_EXT_D(CHIPS)':
 'PCIEUP_7_RXN': CDS_PINID='PCIEUP_7_RXN';
NET_NAME
'P3E_CPU0_PE1_PCH_TXN<8>'
 '@BASEBOARD_FAB2_LIB.BASEBOARD_FAB2(SCH_1):P3E_CPU0_PE1_PCH_TXN'<8>:
 C_SIGNAL='@baseboard_fab2_lib.baseboard_fab2(sch_1):p3e_cpu0_pe1_pch_txn(8)';
NODE_NAME     U5D1 DT5
 '@BASEBOARD_FAB2_LIB.BASEBOARD_FAB2(SCH_1):PAGE30_I84@CHPSET_LIB.SKX_EXT_B(CHIPS)':
 'PE1_TX_DN'<8>: CDS_PINID='PE1_TX_DN(8)';
NODE_NAME     C6B19 1
 '@BASEBOARD_FAB2_LIB.BASEBOARD_FAB2(SCH_1):PAGE105_I160@MSTR_DISCRETE.CAP(CHIPS)':
 'A': CDS_PINID='A';
NODE_NAME     C842 1
 '@BASEBOARD_FAB2_LIB.BASEBOARD_FAB2(SCH_1):PAGE244_I52@MSTR_DISCRETE.CAP(CHIPS)':
 'A': CDS_PINID='A';
NET_NAME
'P3E_CPU0_PE1_PCH_TXN<9>'
 '@BASEBOARD_FAB2_LIB.BASEBOARD_FAB2(SCH_1):P3E_CPU0_PE1_PCH_TXN'<9>:
 C_SIGNAL='@baseboard_fab2_lib.baseboard_fab2(sch_1):p3e_cpu0_pe1_pch_txn(9)';
NODE_NAME     U5D1 DV3
 '@BASEBOARD_FAB2_LIB.BASEBOARD_FAB2(SCH_1):PAGE30_I84@CHPSET_LIB.SKX_EXT_B(CHIPS)':
 'PE1_TX_DN'<9>: CDS_PINID='PE1_TX_DN(9)';
NODE_NAME     C6B17 1
 '@BASEBOARD_FAB2_LIB.BASEBOARD_FAB2(SCH_1):PAGE105_I175@MSTR_DISCRETE.CAP(CHIPS)':
 'A': CDS_PINID='A';
NODE_NAME     C844 1
 '@BASEBOARD_FAB2_LIB.BASEBOARD_FAB2(SCH_1):PAGE244_I51@MSTR_DISCRETE.CAP(CHIPS)':
 'A': CDS_PINID='A';
NET_NAME
'P3E_CPU0_PE1_PCH_TXP<0>'
 '@BASEBOARD_FAB2_LIB.BASEBOARD_FAB2(SCH_1):P3E_CPU0_PE1_PCH_TXP'<0>:
 C_SIGNAL='@baseboard_fab2_lib.baseboard_fab2(sch_1):p3e_cpu0_pe1_pch_txp(0)';
NODE_NAME     C3P11 2
 '@BASEBOARD_FAB2_LIB.BASEBOARD_FAB2(SCH_1):PAGE107_I212@MSTR_DISCRETE.CAP(CHIPS)':
 'B': CDS_PINID='B';
NODE_NAME     U7C1 A48
 '@BASEBOARD_FAB2_LIB.BASEBOARD_FAB2(SCH_1):PAGE117_I9@MSTR_U_PROC.LBG_CORE_QAT_EXT_D(CHIPS)':
 'PCIEUP_0_RXP': CDS_PINID='PCIEUP_0_RXP';
NET_NAME
'P3E_CPU0_PE1_PCH_TXP<10>'
 '@BASEBOARD_FAB2_LIB.BASEBOARD_FAB2(SCH_1):P3E_CPU0_PE1_PCH_TXP'<10>:
 C_SIGNAL='@baseboard_fab2_lib.baseboard_fab2(sch_1):p3e_cpu0_pe1_pch_txp(10)';
NODE_NAME     U5D1 DU4
 '@BASEBOARD_FAB2_LIB.BASEBOARD_FAB2(SCH_1):PAGE30_I84@CHPSET_LIB.SKX_EXT_B(CHIPS)':
 'PE1_TX_DP'<10>: CDS_PINID='PE1_TX_DP(10)';
NODE_NAME     C6B16 1
 '@BASEBOARD_FAB2_LIB.BASEBOARD_FAB2(SCH_1):PAGE105_I180@MSTR_DISCRETE.CAP(CHIPS)':
 'A': CDS_PINID='A';
NODE_NAME     C835 1
 '@BASEBOARD_FAB2_LIB.BASEBOARD_FAB2(SCH_1):PAGE244_I41@MSTR_DISCRETE.CAP(CHIPS)':
 'A': CDS_PINID='A';
NET_NAME
'P3E_CPU0_PE1_PCH_TXP<11>'
 '@BASEBOARD_FAB2_LIB.BASEBOARD_FAB2(SCH_1):P3E_CPU0_PE1_PCH_TXP'<11>:
 C_SIGNAL='@baseboard_fab2_lib.baseboard_fab2(sch_1):p3e_cpu0_pe1_pch_txp(11)';
NODE_NAME     U5D1 DV5
 '@BASEBOARD_FAB2_LIB.BASEBOARD_FAB2(SCH_1):PAGE30_I84@CHPSET_LIB.SKX_EXT_B(CHIPS)':
 'PE1_TX_DP'<11>: CDS_PINID='PE1_TX_DP(11)';
NODE_NAME     C6B13 1
 '@BASEBOARD_FAB2_LIB.BASEBOARD_FAB2(SCH_1):PAGE105_I189@MSTR_DISCRETE.CAP(CHIPS)':
 'A': CDS_PINID='A';
NODE_NAME     C833 1
 '@BASEBOARD_FAB2_LIB.BASEBOARD_FAB2(SCH_1):PAGE244_I8@MSTR_DISCRETE.CAP(CHIPS)':
 'A': CDS_PINID='A';
NET_NAME
'P3E_CPU0_PE1_PCH_TXP<12>'
 '@BASEBOARD_FAB2_LIB.BASEBOARD_FAB2(SCH_1):P3E_CPU0_PE1_PCH_TXP'<12>:
 C_SIGNAL='@baseboard_fab2_lib.baseboard_fab2(sch_1):p3e_cpu0_pe1_pch_txp(12)';
NODE_NAME     U5D1 DT7
 '@BASEBOARD_FAB2_LIB.BASEBOARD_FAB2(SCH_1):PAGE30_I84@CHPSET_LIB.SKX_EXT_B(CHIPS)':
 'PE1_TX_DP'<12>: CDS_PINID='PE1_TX_DP(12)';
NODE_NAME     C6B12 1
 '@BASEBOARD_FAB2_LIB.BASEBOARD_FAB2(SCH_1):PAGE105_I187@MSTR_DISCRETE.CAP(CHIPS)':
 'A': CDS_PINID='A';
NODE_NAME     C841 1
 '@BASEBOARD_FAB2_LIB.BASEBOARD_FAB2(SCH_1):PAGE244_I17@MSTR_DISCRETE.CAP(CHIPS)':
 'A': CDS_PINID='A';
NET_NAME
'P3E_CPU0_PE1_PCH_TXP<13>'
 '@BASEBOARD_FAB2_LIB.BASEBOARD_FAB2(SCH_1):P3E_CPU0_PE1_PCH_TXP'<13>:
 C_SIGNAL='@baseboard_fab2_lib.baseboard_fab2(sch_1):p3e_cpu0_pe1_pch_txp(13)';
NODE_NAME     U5D1 DW6
 '@BASEBOARD_FAB2_LIB.BASEBOARD_FAB2(SCH_1):PAGE30_I84@CHPSET_LIB.SKX_EXT_B(CHIPS)':
 'PE1_TX_DP'<13>: CDS_PINID='PE1_TX_DP(13)';
NODE_NAME     C6B10 1
 '@BASEBOARD_FAB2_LIB.BASEBOARD_FAB2(SCH_1):PAGE105_I193@MSTR_DISCRETE.CAP(CHIPS)':
 'A': CDS_PINID='A';
NODE_NAME     C829 1
 '@BASEBOARD_FAB2_LIB.BASEBOARD_FAB2(SCH_1):PAGE244_I5@MSTR_DISCRETE.CAP(CHIPS)':
 'A': CDS_PINID='A';
NET_NAME
'P3E_CPU0_PE1_PCH_TXP<14>'
 '@BASEBOARD_FAB2_LIB.BASEBOARD_FAB2(SCH_1):P3E_CPU0_PE1_PCH_TXP'<14>:
 C_SIGNAL='@baseboard_fab2_lib.baseboard_fab2(sch_1):p3e_cpu0_pe1_pch_txp(14)';
NODE_NAME     U5D1 EB7
 '@BASEBOARD_FAB2_LIB.BASEBOARD_FAB2(SCH_1):PAGE30_I84@CHPSET_LIB.SKX_EXT_B(CHIPS)':
 'PE1_TX_DP'<14>: CDS_PINID='PE1_TX_DP(14)';
NODE_NAME     C6B8 1
 '@BASEBOARD_FAB2_LIB.BASEBOARD_FAB2(SCH_1):PAGE105_I198@MSTR_DISCRETE.CAP(CHIPS)':
 'A': CDS_PINID='A';
NODE_NAME     C827 1
 '@BASEBOARD_FAB2_LIB.BASEBOARD_FAB2(SCH_1):PAGE244_I12@MSTR_DISCRETE.CAP(CHIPS)':
 'A': CDS_PINID='A';
NET_NAME
'P3E_CPU0_PE1_PCH_TXP<15>'
 '@BASEBOARD_FAB2_LIB.BASEBOARD_FAB2(SCH_1):P3E_CPU0_PE1_PCH_TXP'<15>:
 C_SIGNAL='@baseboard_fab2_lib.baseboard_fab2(sch_1):p3e_cpu0_pe1_pch_txp(15)';
NODE_NAME     U5D1 EC8
 '@BASEBOARD_FAB2_LIB.BASEBOARD_FAB2(SCH_1):PAGE30_I84@CHPSET_LIB.SKX_EXT_B(CHIPS)':
 'PE1_TX_DP'<15>: CDS_PINID='PE1_TX_DP(15)';
NODE_NAME     C6B5 1
 '@BASEBOARD_FAB2_LIB.BASEBOARD_FAB2(SCH_1):PAGE105_I201@MSTR_DISCRETE.CAP(CHIPS)':
 'A': CDS_PINID='A';
NODE_NAME     C831 1
 '@BASEBOARD_FAB2_LIB.BASEBOARD_FAB2(SCH_1):PAGE244_I2@MSTR_DISCRETE.CAP(CHIPS)':
 'A': CDS_PINID='A';
NET_NAME
'P3E_CPU0_PE1_PCH_TXP<1>'
 '@BASEBOARD_FAB2_LIB.BASEBOARD_FAB2(SCH_1):P3E_CPU0_PE1_PCH_TXP'<1>:
 C_SIGNAL='@baseboard_fab2_lib.baseboard_fab2(sch_1):p3e_cpu0_pe1_pch_txp(1)';
NODE_NAME     C3P15 2
 '@BASEBOARD_FAB2_LIB.BASEBOARD_FAB2(SCH_1):PAGE107_I226@MSTR_DISCRETE.CAP(CHIPS)':
 'B': CDS_PINID='B';
NODE_NAME     U7C1 B49
 '@BASEBOARD_FAB2_LIB.BASEBOARD_FAB2(SCH_1):PAGE117_I9@MSTR_U_PROC.LBG_CORE_QAT_EXT_D(CHIPS)':
 'PCIEUP_1_RXP': CDS_PINID='PCIEUP_1_RXP';
NET_NAME
'P3E_CPU0_PE1_PCH_TXP<2>'
 '@BASEBOARD_FAB2_LIB.BASEBOARD_FAB2(SCH_1):P3E_CPU0_PE1_PCH_TXP'<2>:
 C_SIGNAL='@baseboard_fab2_lib.baseboard_fab2(sch_1):p3e_cpu0_pe1_pch_txp(2)';
NODE_NAME     C3P18 2
 '@BASEBOARD_FAB2_LIB.BASEBOARD_FAB2(SCH_1):PAGE107_I219@MSTR_DISCRETE.CAP(CHIPS)':
 'B': CDS_PINID='B';
NODE_NAME     U7C1 A50
 '@BASEBOARD_FAB2_LIB.BASEBOARD_FAB2(SCH_1):PAGE117_I9@MSTR_U_PROC.LBG_CORE_QAT_EXT_D(CHIPS)':
 'PCIEUP_2_RXP': CDS_PINID='PCIEUP_2_RXP';
NET_NAME
'P3E_CPU0_PE1_PCH_TXP<3>'
 '@BASEBOARD_FAB2_LIB.BASEBOARD_FAB2(SCH_1):P3E_CPU0_PE1_PCH_TXP'<3>:
 C_SIGNAL='@baseboard_fab2_lib.baseboard_fab2(sch_1):p3e_cpu0_pe1_pch_txp(3)';
NODE_NAME     C3P23 2
 '@BASEBOARD_FAB2_LIB.BASEBOARD_FAB2(SCH_1):PAGE107_I229@MSTR_DISCRETE.CAP(CHIPS)':
 'B': CDS_PINID='B';
NODE_NAME     U7C1 B51
 '@BASEBOARD_FAB2_LIB.BASEBOARD_FAB2(SCH_1):PAGE117_I9@MSTR_U_PROC.LBG_CORE_QAT_EXT_D(CHIPS)':
 'PCIEUP_3_RXP': CDS_PINID='PCIEUP_3_RXP';
NET_NAME
'P3E_CPU0_PE1_PCH_TXP<4>'
 '@BASEBOARD_FAB2_LIB.BASEBOARD_FAB2(SCH_1):P3E_CPU0_PE1_PCH_TXP'<4>:
 C_SIGNAL='@baseboard_fab2_lib.baseboard_fab2(sch_1):p3e_cpu0_pe1_pch_txp(4)';
NODE_NAME     C3P27 2
 '@BASEBOARD_FAB2_LIB.BASEBOARD_FAB2(SCH_1):PAGE107_I223@MSTR_DISCRETE.CAP(CHIPS)':
 'B': CDS_PINID='B';
NODE_NAME     U7C1 A52
 '@BASEBOARD_FAB2_LIB.BASEBOARD_FAB2(SCH_1):PAGE117_I9@MSTR_U_PROC.LBG_CORE_QAT_EXT_D(CHIPS)':
 'PCIEUP_4_RXP': CDS_PINID='PCIEUP_4_RXP';
NET_NAME
'P3E_CPU0_PE1_PCH_TXP<5>'
 '@BASEBOARD_FAB2_LIB.BASEBOARD_FAB2(SCH_1):P3E_CPU0_PE1_PCH_TXP'<5>:
 C_SIGNAL='@baseboard_fab2_lib.baseboard_fab2(sch_1):p3e_cpu0_pe1_pch_txp(5)';
NODE_NAME     C3P30 2
 '@BASEBOARD_FAB2_LIB.BASEBOARD_FAB2(SCH_1):PAGE107_I245@MSTR_DISCRETE.CAP(CHIPS)':
 'B': CDS_PINID='B';
NODE_NAME     U7C1 B53
 '@BASEBOARD_FAB2_LIB.BASEBOARD_FAB2(SCH_1):PAGE117_I9@MSTR_U_PROC.LBG_CORE_QAT_EXT_D(CHIPS)':
 'PCIEUP_5_RXP': CDS_PINID='PCIEUP_5_RXP';
NET_NAME
'P3E_CPU0_PE1_PCH_TXP<6>'
 '@BASEBOARD_FAB2_LIB.BASEBOARD_FAB2(SCH_1):P3E_CPU0_PE1_PCH_TXP'<6>:
 C_SIGNAL='@baseboard_fab2_lib.baseboard_fab2(sch_1):p3e_cpu0_pe1_pch_txp(6)';
NODE_NAME     C3P35 2
 '@BASEBOARD_FAB2_LIB.BASEBOARD_FAB2(SCH_1):PAGE107_I240@MSTR_DISCRETE.CAP(CHIPS)':
 'B': CDS_PINID='B';
NODE_NAME     U7C1 A54
 '@BASEBOARD_FAB2_LIB.BASEBOARD_FAB2(SCH_1):PAGE117_I9@MSTR_U_PROC.LBG_CORE_QAT_EXT_D(CHIPS)':
 'PCIEUP_6_RXP': CDS_PINID='PCIEUP_6_RXP';
NET_NAME
'P3E_CPU0_PE1_PCH_TXP<7>'
 '@BASEBOARD_FAB2_LIB.BASEBOARD_FAB2(SCH_1):P3E_CPU0_PE1_PCH_TXP'<7>:
 C_SIGNAL='@baseboard_fab2_lib.baseboard_fab2(sch_1):p3e_cpu0_pe1_pch_txp(7)';
NODE_NAME     C3P39 2
 '@BASEBOARD_FAB2_LIB.BASEBOARD_FAB2(SCH_1):PAGE107_I248@MSTR_DISCRETE.CAP(CHIPS)':
 'B': CDS_PINID='B';
NODE_NAME     U7C1 B55
 '@BASEBOARD_FAB2_LIB.BASEBOARD_FAB2(SCH_1):PAGE117_I9@MSTR_U_PROC.LBG_CORE_QAT_EXT_D(CHIPS)':
 'PCIEUP_7_RXP': CDS_PINID='PCIEUP_7_RXP';
NET_NAME
'P3E_CPU0_PE1_PCH_TXP<8>'
 '@BASEBOARD_FAB2_LIB.BASEBOARD_FAB2(SCH_1):P3E_CPU0_PE1_PCH_TXP'<8>:
 C_SIGNAL='@baseboard_fab2_lib.baseboard_fab2(sch_1):p3e_cpu0_pe1_pch_txp(8)';
NODE_NAME     U5D1 DR4
 '@BASEBOARD_FAB2_LIB.BASEBOARD_FAB2(SCH_1):PAGE30_I84@CHPSET_LIB.SKX_EXT_B(CHIPS)':
 'PE1_TX_DP'<8>: CDS_PINID='PE1_TX_DP(8)';
NODE_NAME     C6B20 1
 '@BASEBOARD_FAB2_LIB.BASEBOARD_FAB2(SCH_1):PAGE105_I173@MSTR_DISCRETE.CAP(CHIPS)':
 'A': CDS_PINID='A';
NODE_NAME     C843 1
 '@BASEBOARD_FAB2_LIB.BASEBOARD_FAB2(SCH_1):PAGE244_I47@MSTR_DISCRETE.CAP(CHIPS)':
 'A': CDS_PINID='A';
NET_NAME
'P3E_CPU0_PE1_PCH_TXP<9>'
 '@BASEBOARD_FAB2_LIB.BASEBOARD_FAB2(SCH_1):P3E_CPU0_PE1_PCH_TXP'<9>:
 C_SIGNAL='@baseboard_fab2_lib.baseboard_fab2(sch_1):p3e_cpu0_pe1_pch_txp(9)';
NODE_NAME     U5D1 DU2
 '@BASEBOARD_FAB2_LIB.BASEBOARD_FAB2(SCH_1):PAGE30_I84@CHPSET_LIB.SKX_EXT_B(CHIPS)':
 'PE1_TX_DP'<9>: CDS_PINID='PE1_TX_DP(9)';
NODE_NAME     C6B18 1
 '@BASEBOARD_FAB2_LIB.BASEBOARD_FAB2(SCH_1):PAGE105_I153@MSTR_DISCRETE.CAP(CHIPS)':
 'A': CDS_PINID='A';
NODE_NAME     C845 1
 '@BASEBOARD_FAB2_LIB.BASEBOARD_FAB2(SCH_1):PAGE244_I35@MSTR_DISCRETE.CAP(CHIPS)':
 'A': CDS_PINID='A';
NET_NAME
'P3E_CPU0_PE1_SS_C_TXN<0>'
 '@BASEBOARD_FAB2_LIB.BASEBOARD_FAB2(SCH_1):P3E_CPU0_PE1_SS_C_TXN'<0>:
 C_SIGNAL='@baseboard_fab2_lib.baseboard_fab2(sch_1):p3e_cpu0_pe1_ss_c_txn(0)';
NODE_NAME     J8G1 145
 '@BASEBOARD_FAB2_LIB.BASEBOARD_FAB2(SCH_1):PAGE109_I78@MSTR_SCONN.SCONN200_H68296001(CHIPS)':
 'IO145': CDS_PINID='IO145';
NODE_NAME     C3P12 2
 '@BASEBOARD_FAB2_LIB.BASEBOARD_FAB2(SCH_1):PAGE107_I481@MSTR_DISCRETE.CAP(CHIPS)':
 'B': CDS_PINID='B';
NET_NAME
'P3E_CPU0_PE1_SS_C_TXN<1>'
 '@BASEBOARD_FAB2_LIB.BASEBOARD_FAB2(SCH_1):P3E_CPU0_PE1_SS_C_TXN'<1>:
 C_SIGNAL='@baseboard_fab2_lib.baseboard_fab2(sch_1):p3e_cpu0_pe1_ss_c_txn(1)';
NODE_NAME     J8G1 139
 '@BASEBOARD_FAB2_LIB.BASEBOARD_FAB2(SCH_1):PAGE109_I78@MSTR_SCONN.SCONN200_H68296001(CHIPS)':
 'IO139': CDS_PINID='IO139';
NODE_NAME     C3P16 2
 '@BASEBOARD_FAB2_LIB.BASEBOARD_FAB2(SCH_1):PAGE107_I476@MSTR_DISCRETE.CAP(CHIPS)':
 'B': CDS_PINID='B';
NET_NAME
'P3E_CPU0_PE1_SS_C_TXN<2>'
 '@BASEBOARD_FAB2_LIB.BASEBOARD_FAB2(SCH_1):P3E_CPU0_PE1_SS_C_TXN'<2>:
 C_SIGNAL='@baseboard_fab2_lib.baseboard_fab2(sch_1):p3e_cpu0_pe1_ss_c_txn(2)';
NODE_NAME     J8G1 133
 '@BASEBOARD_FAB2_LIB.BASEBOARD_FAB2(SCH_1):PAGE109_I78@MSTR_SCONN.SCONN200_H68296001(CHIPS)':
 'IO133': CDS_PINID='IO133';
NODE_NAME     C3P21 2
 '@BASEBOARD_FAB2_LIB.BASEBOARD_FAB2(SCH_1):PAGE107_I480@MSTR_DISCRETE.CAP(CHIPS)':
 'B': CDS_PINID='B';
NET_NAME
'P3E_CPU0_PE1_SS_C_TXN<3>'
 '@BASEBOARD_FAB2_LIB.BASEBOARD_FAB2(SCH_1):P3E_CPU0_PE1_SS_C_TXN'<3>:
 C_SIGNAL='@baseboard_fab2_lib.baseboard_fab2(sch_1):p3e_cpu0_pe1_ss_c_txn(3)';
NODE_NAME     J8G1 127
 '@BASEBOARD_FAB2_LIB.BASEBOARD_FAB2(SCH_1):PAGE109_I78@MSTR_SCONN.SCONN200_H68296001(CHIPS)':
 'IO127': CDS_PINID='IO127';
NODE_NAME     C3P24 2
 '@BASEBOARD_FAB2_LIB.BASEBOARD_FAB2(SCH_1):PAGE107_I479@MSTR_DISCRETE.CAP(CHIPS)':
 'B': CDS_PINID='B';
NET_NAME
'P3E_CPU0_PE1_SS_C_TXN<4>'
 '@BASEBOARD_FAB2_LIB.BASEBOARD_FAB2(SCH_1):P3E_CPU0_PE1_SS_C_TXN'<4>:
 C_SIGNAL='@baseboard_fab2_lib.baseboard_fab2(sch_1):p3e_cpu0_pe1_ss_c_txn(4)';
NODE_NAME     J8G1 121
 '@BASEBOARD_FAB2_LIB.BASEBOARD_FAB2(SCH_1):PAGE109_I78@MSTR_SCONN.SCONN200_H68296001(CHIPS)':
 'IO121': CDS_PINID='IO121';
NODE_NAME     C3P29 2
 '@BASEBOARD_FAB2_LIB.BASEBOARD_FAB2(SCH_1):PAGE107_I478@MSTR_DISCRETE.CAP(CHIPS)':
 'B': CDS_PINID='B';
NET_NAME
'P3E_CPU0_PE1_SS_C_TXN<5>'
 '@BASEBOARD_FAB2_LIB.BASEBOARD_FAB2(SCH_1):P3E_CPU0_PE1_SS_C_TXN'<5>:
 C_SIGNAL='@baseboard_fab2_lib.baseboard_fab2(sch_1):p3e_cpu0_pe1_ss_c_txn(5)';
NODE_NAME     J8G1 115
 '@BASEBOARD_FAB2_LIB.BASEBOARD_FAB2(SCH_1):PAGE109_I78@MSTR_SCONN.SCONN200_H68296001(CHIPS)':
 'IO115': CDS_PINID='IO115';
NODE_NAME     C3P33 2
 '@BASEBOARD_FAB2_LIB.BASEBOARD_FAB2(SCH_1):PAGE107_I477@MSTR_DISCRETE.CAP(CHIPS)':
 'B': CDS_PINID='B';
NET_NAME
'P3E_CPU0_PE1_SS_C_TXN<6>'
 '@BASEBOARD_FAB2_LIB.BASEBOARD_FAB2(SCH_1):P3E_CPU0_PE1_SS_C_TXN'<6>:
 C_SIGNAL='@baseboard_fab2_lib.baseboard_fab2(sch_1):p3e_cpu0_pe1_ss_c_txn(6)';
NODE_NAME     J8G1 109
 '@BASEBOARD_FAB2_LIB.BASEBOARD_FAB2(SCH_1):PAGE109_I78@MSTR_SCONN.SCONN200_H68296001(CHIPS)':
 'IO109': CDS_PINID='IO109';
NODE_NAME     C3P36 2
 '@BASEBOARD_FAB2_LIB.BASEBOARD_FAB2(SCH_1):PAGE107_I475@MSTR_DISCRETE.CAP(CHIPS)':
 'B': CDS_PINID='B';
NET_NAME
'P3E_CPU0_PE1_SS_C_TXN<7>'
 '@BASEBOARD_FAB2_LIB.BASEBOARD_FAB2(SCH_1):P3E_CPU0_PE1_SS_C_TXN'<7>:
 C_SIGNAL='@baseboard_fab2_lib.baseboard_fab2(sch_1):p3e_cpu0_pe1_ss_c_txn(7)';
NODE_NAME     J8G1 105
 '@BASEBOARD_FAB2_LIB.BASEBOARD_FAB2(SCH_1):PAGE109_I78@MSTR_SCONN.SCONN200_H68296001(CHIPS)':
 'IO105': CDS_PINID='IO105';
NODE_NAME     C3P41 2
 '@BASEBOARD_FAB2_LIB.BASEBOARD_FAB2(SCH_1):PAGE107_I474@MSTR_DISCRETE.CAP(CHIPS)':
 'B': CDS_PINID='B';
NET_NAME
'P3E_CPU0_PE1_SS_C_TXP<0>'
 '@BASEBOARD_FAB2_LIB.BASEBOARD_FAB2(SCH_1):P3E_CPU0_PE1_SS_C_TXP'<0>:
 C_SIGNAL='@baseboard_fab2_lib.baseboard_fab2(sch_1):p3e_cpu0_pe1_ss_c_txp(0)';
NODE_NAME     J8G1 147
 '@BASEBOARD_FAB2_LIB.BASEBOARD_FAB2(SCH_1):PAGE109_I78@MSTR_SCONN.SCONN200_H68296001(CHIPS)':
 'IO147': CDS_PINID='IO147';
NODE_NAME     C3P10 2
 '@BASEBOARD_FAB2_LIB.BASEBOARD_FAB2(SCH_1):PAGE107_I482@MSTR_DISCRETE.CAP(CHIPS)':
 'B': CDS_PINID='B';
NET_NAME
'P3E_CPU0_PE1_SS_C_TXP<1>'
 '@BASEBOARD_FAB2_LIB.BASEBOARD_FAB2(SCH_1):P3E_CPU0_PE1_SS_C_TXP'<1>:
 C_SIGNAL='@baseboard_fab2_lib.baseboard_fab2(sch_1):p3e_cpu0_pe1_ss_c_txp(1)';
NODE_NAME     J8G1 141
 '@BASEBOARD_FAB2_LIB.BASEBOARD_FAB2(SCH_1):PAGE109_I78@MSTR_SCONN.SCONN200_H68296001(CHIPS)':
 'IO141': CDS_PINID='IO141';
NODE_NAME     C3P14 2
 '@BASEBOARD_FAB2_LIB.BASEBOARD_FAB2(SCH_1):PAGE107_I483@MSTR_DISCRETE.CAP(CHIPS)':
 'B': CDS_PINID='B';
NET_NAME
'P3E_CPU0_PE1_SS_C_TXP<2>'
 '@BASEBOARD_FAB2_LIB.BASEBOARD_FAB2(SCH_1):P3E_CPU0_PE1_SS_C_TXP'<2>:
 C_SIGNAL='@baseboard_fab2_lib.baseboard_fab2(sch_1):p3e_cpu0_pe1_ss_c_txp(2)';
NODE_NAME     J8G1 135
 '@BASEBOARD_FAB2_LIB.BASEBOARD_FAB2(SCH_1):PAGE109_I78@MSTR_SCONN.SCONN200_H68296001(CHIPS)':
 'IO135': CDS_PINID='IO135';
NODE_NAME     C3P19 2
 '@BASEBOARD_FAB2_LIB.BASEBOARD_FAB2(SCH_1):PAGE107_I485@MSTR_DISCRETE.CAP(CHIPS)':
 'B': CDS_PINID='B';
NET_NAME
'P3E_CPU0_PE1_SS_C_TXP<3>'
 '@BASEBOARD_FAB2_LIB.BASEBOARD_FAB2(SCH_1):P3E_CPU0_PE1_SS_C_TXP'<3>:
 C_SIGNAL='@baseboard_fab2_lib.baseboard_fab2(sch_1):p3e_cpu0_pe1_ss_c_txp(3)';
NODE_NAME     J8G1 129
 '@BASEBOARD_FAB2_LIB.BASEBOARD_FAB2(SCH_1):PAGE109_I78@MSTR_SCONN.SCONN200_H68296001(CHIPS)':
 'IO129': CDS_PINID='IO129';
NODE_NAME     C3P22 2
 '@BASEBOARD_FAB2_LIB.BASEBOARD_FAB2(SCH_1):PAGE107_I484@MSTR_DISCRETE.CAP(CHIPS)':
 'B': CDS_PINID='B';
NET_NAME
'P3E_CPU0_PE1_SS_C_TXP<4>'
 '@BASEBOARD_FAB2_LIB.BASEBOARD_FAB2(SCH_1):P3E_CPU0_PE1_SS_C_TXP'<4>:
 C_SIGNAL='@baseboard_fab2_lib.baseboard_fab2(sch_1):p3e_cpu0_pe1_ss_c_txp(4)';
NODE_NAME     J8G1 123
 '@BASEBOARD_FAB2_LIB.BASEBOARD_FAB2(SCH_1):PAGE109_I78@MSTR_SCONN.SCONN200_H68296001(CHIPS)':
 'IO123': CDS_PINID='IO123';
NODE_NAME     C3P26 2
 '@BASEBOARD_FAB2_LIB.BASEBOARD_FAB2(SCH_1):PAGE107_I487@MSTR_DISCRETE.CAP(CHIPS)':
 'B': CDS_PINID='B';
NET_NAME
'P3E_CPU0_PE1_SS_C_TXP<5>'
 '@BASEBOARD_FAB2_LIB.BASEBOARD_FAB2(SCH_1):P3E_CPU0_PE1_SS_C_TXP'<5>:
 C_SIGNAL='@baseboard_fab2_lib.baseboard_fab2(sch_1):p3e_cpu0_pe1_ss_c_txp(5)';
NODE_NAME     J8G1 117
 '@BASEBOARD_FAB2_LIB.BASEBOARD_FAB2(SCH_1):PAGE109_I78@MSTR_SCONN.SCONN200_H68296001(CHIPS)':
 'IO117': CDS_PINID='IO117';
NODE_NAME     C3P31 2
 '@BASEBOARD_FAB2_LIB.BASEBOARD_FAB2(SCH_1):PAGE107_I488@MSTR_DISCRETE.CAP(CHIPS)':
 'B': CDS_PINID='B';
NET_NAME
'P3E_CPU0_PE1_SS_C_TXP<6>'
 '@BASEBOARD_FAB2_LIB.BASEBOARD_FAB2(SCH_1):P3E_CPU0_PE1_SS_C_TXP'<6>:
 C_SIGNAL='@baseboard_fab2_lib.baseboard_fab2(sch_1):p3e_cpu0_pe1_ss_c_txp(6)';
NODE_NAME     J8G1 111
 '@BASEBOARD_FAB2_LIB.BASEBOARD_FAB2(SCH_1):PAGE109_I78@MSTR_SCONN.SCONN200_H68296001(CHIPS)':
 'IO111': CDS_PINID='IO111';
NODE_NAME     C3P34 2
 '@BASEBOARD_FAB2_LIB.BASEBOARD_FAB2(SCH_1):PAGE107_I489@MSTR_DISCRETE.CAP(CHIPS)':
 'B': CDS_PINID='B';
NET_NAME
'P3E_CPU0_PE1_SS_C_TXP<7>'
 '@BASEBOARD_FAB2_LIB.BASEBOARD_FAB2(SCH_1):P3E_CPU0_PE1_SS_C_TXP'<7>:
 C_SIGNAL='@baseboard_fab2_lib.baseboard_fab2(sch_1):p3e_cpu0_pe1_ss_c_txp(7)';
NODE_NAME     J8G1 103
 '@BASEBOARD_FAB2_LIB.BASEBOARD_FAB2(SCH_1):PAGE109_I78@MSTR_SCONN.SCONN200_H68296001(CHIPS)':
 'IO103': CDS_PINID='IO103';
NODE_NAME     C3P38 2
 '@BASEBOARD_FAB2_LIB.BASEBOARD_FAB2(SCH_1):PAGE107_I486@MSTR_DISCRETE.CAP(CHIPS)':
 'B': CDS_PINID='B';
NET_NAME
'P3E_CPU0_PE1_SS_RXN<0>'
 '@BASEBOARD_FAB2_LIB.BASEBOARD_FAB2(SCH_1):P3E_CPU0_PE1_SS_RXN'<0>:
 C_SIGNAL='@baseboard_fab2_lib.baseboard_fab2(sch_1):p3e_cpu0_pe1_ss_rxn(0)';
NODE_NAME     U5D1 CW8
 '@BASEBOARD_FAB2_LIB.BASEBOARD_FAB2(SCH_1):PAGE30_I84@CHPSET_LIB.SKX_EXT_B(CHIPS)':
 'PE1_RX_DN'<0>: CDS_PINID='PE1_RX_DN(0)';
NODE_NAME     C2U4 2
 '@BASEBOARD_FAB2_LIB.BASEBOARD_FAB2(SCH_1):PAGE107_I257@MSTR_DISCRETE.CAP(CHIPS)':
 'B': CDS_PINID='B';
NODE_NAME     R2U15 1
 '@BASEBOARD_FAB2_LIB.BASEBOARD_FAB2(SCH_1):PAGE107_I490@MSTR_DISCRETE.RES(CHIPS)':
 'A': CDS_PINID='A';
NET_NAME
'P3E_CPU0_PE1_SS_RXN<1>'
 '@BASEBOARD_FAB2_LIB.BASEBOARD_FAB2(SCH_1):P3E_CPU0_PE1_SS_RXN'<1>:
 C_SIGNAL='@baseboard_fab2_lib.baseboard_fab2(sch_1):p3e_cpu0_pe1_ss_rxn(1)';
NODE_NAME     U5D1 DA8
 '@BASEBOARD_FAB2_LIB.BASEBOARD_FAB2(SCH_1):PAGE30_I84@CHPSET_LIB.SKX_EXT_B(CHIPS)':
 'PE1_RX_DN'<1>: CDS_PINID='PE1_RX_DN(1)';
NODE_NAME     C2U6 2
 '@BASEBOARD_FAB2_LIB.BASEBOARD_FAB2(SCH_1):PAGE107_I260@MSTR_DISCRETE.CAP(CHIPS)':
 'B': CDS_PINID='B';
NODE_NAME     R2U17 1
 '@BASEBOARD_FAB2_LIB.BASEBOARD_FAB2(SCH_1):PAGE107_I492@MSTR_DISCRETE.RES(CHIPS)':
 'A': CDS_PINID='A';
NET_NAME
'P3E_CPU0_PE1_SS_RXN<2>'
 '@BASEBOARD_FAB2_LIB.BASEBOARD_FAB2(SCH_1):P3E_CPU0_PE1_SS_RXN'<2>:
 C_SIGNAL='@baseboard_fab2_lib.baseboard_fab2(sch_1):p3e_cpu0_pe1_ss_rxn(2)';
NODE_NAME     U5D1 DC8
 '@BASEBOARD_FAB2_LIB.BASEBOARD_FAB2(SCH_1):PAGE30_I84@CHPSET_LIB.SKX_EXT_B(CHIPS)':
 'PE1_RX_DN'<2>: CDS_PINID='PE1_RX_DN(2)';
NODE_NAME     C2U8 2
 '@BASEBOARD_FAB2_LIB.BASEBOARD_FAB2(SCH_1):PAGE107_I264@MSTR_DISCRETE.CAP(CHIPS)':
 'B': CDS_PINID='B';
NODE_NAME     R2U19 1
 '@BASEBOARD_FAB2_LIB.BASEBOARD_FAB2(SCH_1):PAGE107_I493@MSTR_DISCRETE.RES(CHIPS)':
 'A': CDS_PINID='A';
NET_NAME
'P3E_CPU0_PE1_SS_RXN<3>'
 '@BASEBOARD_FAB2_LIB.BASEBOARD_FAB2(SCH_1):P3E_CPU0_PE1_SS_RXN'<3>:
 C_SIGNAL='@baseboard_fab2_lib.baseboard_fab2(sch_1):p3e_cpu0_pe1_ss_rxn(3)';
NODE_NAME     U5D1 DC10
 '@BASEBOARD_FAB2_LIB.BASEBOARD_FAB2(SCH_1):PAGE30_I84@CHPSET_LIB.SKX_EXT_B(CHIPS)':
 'PE1_RX_DN'<3>: CDS_PINID='PE1_RX_DN(3)';
NODE_NAME     C2U10 2
 '@BASEBOARD_FAB2_LIB.BASEBOARD_FAB2(SCH_1):PAGE107_I267@MSTR_DISCRETE.CAP(CHIPS)':
 'B': CDS_PINID='B';
NODE_NAME     R2U21 1
 '@BASEBOARD_FAB2_LIB.BASEBOARD_FAB2(SCH_1):PAGE107_I491@MSTR_DISCRETE.RES(CHIPS)':
 'A': CDS_PINID='A';
NET_NAME
'P3E_CPU0_PE1_SS_RXN<4>'
 '@BASEBOARD_FAB2_LIB.BASEBOARD_FAB2(SCH_1):P3E_CPU0_PE1_SS_RXN'<4>:
 C_SIGNAL='@baseboard_fab2_lib.baseboard_fab2(sch_1):p3e_cpu0_pe1_ss_rxn(4)';
NODE_NAME     U5D1 DE10
 '@BASEBOARD_FAB2_LIB.BASEBOARD_FAB2(SCH_1):PAGE30_I84@CHPSET_LIB.SKX_EXT_B(CHIPS)':
 'PE1_RX_DN'<4>: CDS_PINID='PE1_RX_DN(4)';
NODE_NAME     C2U12 2
 '@BASEBOARD_FAB2_LIB.BASEBOARD_FAB2(SCH_1):PAGE107_I265@MSTR_DISCRETE.CAP(CHIPS)':
 'B': CDS_PINID='B';
NODE_NAME     R2U23 1
 '@BASEBOARD_FAB2_LIB.BASEBOARD_FAB2(SCH_1):PAGE107_I495@MSTR_DISCRETE.RES(CHIPS)':
 'A': CDS_PINID='A';
NET_NAME
'P3E_CPU0_PE1_SS_RXN<5>'
 '@BASEBOARD_FAB2_LIB.BASEBOARD_FAB2(SCH_1):P3E_CPU0_PE1_SS_RXN'<5>:
 C_SIGNAL='@baseboard_fab2_lib.baseboard_fab2(sch_1):p3e_cpu0_pe1_ss_rxn(5)';
NODE_NAME     U5D1 DH9
 '@BASEBOARD_FAB2_LIB.BASEBOARD_FAB2(SCH_1):PAGE30_I84@CHPSET_LIB.SKX_EXT_B(CHIPS)':
 'PE1_RX_DN'<5>: CDS_PINID='PE1_RX_DN(5)';
NODE_NAME     C2U14 2
 '@BASEBOARD_FAB2_LIB.BASEBOARD_FAB2(SCH_1):PAGE107_I287@MSTR_DISCRETE.CAP(CHIPS)':
 'B': CDS_PINID='B';
NODE_NAME     R2U25 1
 '@BASEBOARD_FAB2_LIB.BASEBOARD_FAB2(SCH_1):PAGE107_I496@MSTR_DISCRETE.RES(CHIPS)':
 'A': CDS_PINID='A';
NET_NAME
'P3E_CPU0_PE1_SS_RXN<6>'
 '@BASEBOARD_FAB2_LIB.BASEBOARD_FAB2(SCH_1):P3E_CPU0_PE1_SS_RXN'<6>:
 C_SIGNAL='@baseboard_fab2_lib.baseboard_fab2(sch_1):p3e_cpu0_pe1_ss_rxn(6)';
NODE_NAME     U5D1 DK9
 '@BASEBOARD_FAB2_LIB.BASEBOARD_FAB2(SCH_1):PAGE30_I84@CHPSET_LIB.SKX_EXT_B(CHIPS)':
 'PE1_RX_DN'<6>: CDS_PINID='PE1_RX_DN(6)';
NODE_NAME     C2U16 2
 '@BASEBOARD_FAB2_LIB.BASEBOARD_FAB2(SCH_1):PAGE107_I286@MSTR_DISCRETE.CAP(CHIPS)':
 'B': CDS_PINID='B';
NODE_NAME     R2U27 1
 '@BASEBOARD_FAB2_LIB.BASEBOARD_FAB2(SCH_1):PAGE107_I497@MSTR_DISCRETE.RES(CHIPS)':
 'A': CDS_PINID='A';
NET_NAME
'P3E_CPU0_PE1_SS_RXN<7>'
 '@BASEBOARD_FAB2_LIB.BASEBOARD_FAB2(SCH_1):P3E_CPU0_PE1_SS_RXN'<7>:
 C_SIGNAL='@baseboard_fab2_lib.baseboard_fab2(sch_1):p3e_cpu0_pe1_ss_rxn(7)';
NODE_NAME     U5D1 DM9
 '@BASEBOARD_FAB2_LIB.BASEBOARD_FAB2(SCH_1):PAGE30_I84@CHPSET_LIB.SKX_EXT_B(CHIPS)':
 'PE1_RX_DN'<7>: CDS_PINID='PE1_RX_DN(7)';
NODE_NAME     C2U18 2
 '@BASEBOARD_FAB2_LIB.BASEBOARD_FAB2(SCH_1):PAGE107_I294@MSTR_DISCRETE.CAP(CHIPS)':
 'B': CDS_PINID='B';
NODE_NAME     R2U29 1
 '@BASEBOARD_FAB2_LIB.BASEBOARD_FAB2(SCH_1):PAGE107_I494@MSTR_DISCRETE.RES(CHIPS)':
 'A': CDS_PINID='A';
NET_NAME
'P3E_CPU0_PE1_SS_RXP<0>'
 '@BASEBOARD_FAB2_LIB.BASEBOARD_FAB2(SCH_1):P3E_CPU0_PE1_SS_RXP'<0>:
 C_SIGNAL='@baseboard_fab2_lib.baseboard_fab2(sch_1):p3e_cpu0_pe1_ss_rxp(0)';
NODE_NAME     U5D1 CU8
 '@BASEBOARD_FAB2_LIB.BASEBOARD_FAB2(SCH_1):PAGE30_I84@CHPSET_LIB.SKX_EXT_B(CHIPS)':
 'PE1_RX_DP'<0>: CDS_PINID='PE1_RX_DP(0)';
NODE_NAME     C2U3 2
 '@BASEBOARD_FAB2_LIB.BASEBOARD_FAB2(SCH_1):PAGE107_I272@MSTR_DISCRETE.CAP(CHIPS)':
 'B': CDS_PINID='B';
NODE_NAME     R2U14 1
 '@BASEBOARD_FAB2_LIB.BASEBOARD_FAB2(SCH_1):PAGE107_I499@MSTR_DISCRETE.RES(CHIPS)':
 'A': CDS_PINID='A';
NET_NAME
'P3E_CPU0_PE1_SS_RXP<1>'
 '@BASEBOARD_FAB2_LIB.BASEBOARD_FAB2(SCH_1):P3E_CPU0_PE1_SS_RXP'<1>:
 C_SIGNAL='@baseboard_fab2_lib.baseboard_fab2(sch_1):p3e_cpu0_pe1_ss_rxp(1)';
NODE_NAME     U5D1 CY7
 '@BASEBOARD_FAB2_LIB.BASEBOARD_FAB2(SCH_1):PAGE30_I84@CHPSET_LIB.SKX_EXT_B(CHIPS)':
 'PE1_RX_DP'<1>: CDS_PINID='PE1_RX_DP(1)';
NODE_NAME     C2U5 2
 '@BASEBOARD_FAB2_LIB.BASEBOARD_FAB2(SCH_1):PAGE107_I274@MSTR_DISCRETE.CAP(CHIPS)':
 'B': CDS_PINID='B';
NODE_NAME     R2U16 1
 '@BASEBOARD_FAB2_LIB.BASEBOARD_FAB2(SCH_1):PAGE107_I501@MSTR_DISCRETE.RES(CHIPS)':
 'A': CDS_PINID='A';
NET_NAME
'P3E_CPU0_PE1_SS_RXP<2>'
 '@BASEBOARD_FAB2_LIB.BASEBOARD_FAB2(SCH_1):P3E_CPU0_PE1_SS_RXP'<2>:
 C_SIGNAL='@baseboard_fab2_lib.baseboard_fab2(sch_1):p3e_cpu0_pe1_ss_rxp(2)';
NODE_NAME     U5D1 DB9
 '@BASEBOARD_FAB2_LIB.BASEBOARD_FAB2(SCH_1):PAGE30_I84@CHPSET_LIB.SKX_EXT_B(CHIPS)':
 'PE1_RX_DP'<2>: CDS_PINID='PE1_RX_DP(2)';
NODE_NAME     C2U7 2
 '@BASEBOARD_FAB2_LIB.BASEBOARD_FAB2(SCH_1):PAGE107_I277@MSTR_DISCRETE.CAP(CHIPS)':
 'B': CDS_PINID='B';
NODE_NAME     R2U18 1
 '@BASEBOARD_FAB2_LIB.BASEBOARD_FAB2(SCH_1):PAGE107_I502@MSTR_DISCRETE.RES(CHIPS)':
 'A': CDS_PINID='A';
NET_NAME
'P3E_CPU0_PE1_SS_RXP<3>'
 '@BASEBOARD_FAB2_LIB.BASEBOARD_FAB2(SCH_1):P3E_CPU0_PE1_SS_RXP'<3>:
 C_SIGNAL='@baseboard_fab2_lib.baseboard_fab2(sch_1):p3e_cpu0_pe1_ss_rxp(3)';
NODE_NAME     U5D1 DA10
 '@BASEBOARD_FAB2_LIB.BASEBOARD_FAB2(SCH_1):PAGE30_I84@CHPSET_LIB.SKX_EXT_B(CHIPS)':
 'PE1_RX_DP'<3>: CDS_PINID='PE1_RX_DP(3)';
NODE_NAME     C2U9 2
 '@BASEBOARD_FAB2_LIB.BASEBOARD_FAB2(SCH_1):PAGE107_I279@MSTR_DISCRETE.CAP(CHIPS)':
 'B': CDS_PINID='B';
NODE_NAME     R2U20 1
 '@BASEBOARD_FAB2_LIB.BASEBOARD_FAB2(SCH_1):PAGE107_I503@MSTR_DISCRETE.RES(CHIPS)':
 'A': CDS_PINID='A';
NET_NAME
'P3E_CPU0_PE1_SS_RXP<4>'
 '@BASEBOARD_FAB2_LIB.BASEBOARD_FAB2(SCH_1):P3E_CPU0_PE1_SS_RXP'<4>:
 C_SIGNAL='@baseboard_fab2_lib.baseboard_fab2(sch_1):p3e_cpu0_pe1_ss_rxp(4)';
NODE_NAME     U5D1 DD9
 '@BASEBOARD_FAB2_LIB.BASEBOARD_FAB2(SCH_1):PAGE30_I84@CHPSET_LIB.SKX_EXT_B(CHIPS)':
 'PE1_RX_DP'<4>: CDS_PINID='PE1_RX_DP(4)';
NODE_NAME     C2U11 2
 '@BASEBOARD_FAB2_LIB.BASEBOARD_FAB2(SCH_1):PAGE107_I278@MSTR_DISCRETE.CAP(CHIPS)':
 'B': CDS_PINID='B';
NODE_NAME     R2U22 1
 '@BASEBOARD_FAB2_LIB.BASEBOARD_FAB2(SCH_1):PAGE107_I504@MSTR_DISCRETE.RES(CHIPS)':
 'A': CDS_PINID='A';
NET_NAME
'P3E_CPU0_PE1_SS_RXP<5>'
 '@BASEBOARD_FAB2_LIB.BASEBOARD_FAB2(SCH_1):P3E_CPU0_PE1_SS_RXP'<5>:
 C_SIGNAL='@baseboard_fab2_lib.baseboard_fab2(sch_1):p3e_cpu0_pe1_ss_rxp(5)';
NODE_NAME     U5D1 DF9
 '@BASEBOARD_FAB2_LIB.BASEBOARD_FAB2(SCH_1):PAGE30_I84@CHPSET_LIB.SKX_EXT_B(CHIPS)':
 'PE1_RX_DP'<5>: CDS_PINID='PE1_RX_DP(5)';
NODE_NAME     C2U13 2
 '@BASEBOARD_FAB2_LIB.BASEBOARD_FAB2(SCH_1):PAGE107_I297@MSTR_DISCRETE.CAP(CHIPS)':
 'B': CDS_PINID='B';
NODE_NAME     R2U24 1
 '@BASEBOARD_FAB2_LIB.BASEBOARD_FAB2(SCH_1):PAGE107_I505@MSTR_DISCRETE.RES(CHIPS)':
 'A': CDS_PINID='A';
NET_NAME
'P3E_CPU0_PE1_SS_RXP<6>'
 '@BASEBOARD_FAB2_LIB.BASEBOARD_FAB2(SCH_1):P3E_CPU0_PE1_SS_RXP'<6>:
 C_SIGNAL='@baseboard_fab2_lib.baseboard_fab2(sch_1):p3e_cpu0_pe1_ss_rxp(6)';
NODE_NAME     U5D1 DJ8
 '@BASEBOARD_FAB2_LIB.BASEBOARD_FAB2(SCH_1):PAGE30_I84@CHPSET_LIB.SKX_EXT_B(CHIPS)':
 'PE1_RX_DP'<6>: CDS_PINID='PE1_RX_DP(6)';
NODE_NAME     C2U15 2
 '@BASEBOARD_FAB2_LIB.BASEBOARD_FAB2(SCH_1):PAGE107_I296@MSTR_DISCRETE.CAP(CHIPS)':
 'B': CDS_PINID='B';
NODE_NAME     R2U26 1
 '@BASEBOARD_FAB2_LIB.BASEBOARD_FAB2(SCH_1):PAGE107_I498@MSTR_DISCRETE.RES(CHIPS)':
 'A': CDS_PINID='A';
NET_NAME
'P3E_CPU0_PE1_SS_RXP<7>'
 '@BASEBOARD_FAB2_LIB.BASEBOARD_FAB2(SCH_1):P3E_CPU0_PE1_SS_RXP'<7>:
 C_SIGNAL='@baseboard_fab2_lib.baseboard_fab2(sch_1):p3e_cpu0_pe1_ss_rxp(7)';
NODE_NAME     U5D1 DL10
 '@BASEBOARD_FAB2_LIB.BASEBOARD_FAB2(SCH_1):PAGE30_I84@CHPSET_LIB.SKX_EXT_B(CHIPS)':
 'PE1_RX_DP'<7>: CDS_PINID='PE1_RX_DP(7)';
NODE_NAME     C2U17 2
 '@BASEBOARD_FAB2_LIB.BASEBOARD_FAB2(SCH_1):PAGE107_I300@MSTR_DISCRETE.CAP(CHIPS)':
 'B': CDS_PINID='B';
NODE_NAME     R2U28 1
 '@BASEBOARD_FAB2_LIB.BASEBOARD_FAB2(SCH_1):PAGE107_I500@MSTR_DISCRETE.RES(CHIPS)':
 'A': CDS_PINID='A';
NET_NAME
'P3E_CPU0_PE1_SS_R_RXN<0>'
 '@BASEBOARD_FAB2_LIB.BASEBOARD_FAB2(SCH_1):P3E_CPU0_PE1_SS_R_RXN'<0>:
 C_SIGNAL='@baseboard_fab2_lib.baseboard_fab2(sch_1):p3e_cpu0_pe1_ss_r_rxn(0)';
NODE_NAME     J8G1 148
 '@BASEBOARD_FAB2_LIB.BASEBOARD_FAB2(SCH_1):PAGE109_I78@MSTR_SCONN.SCONN200_H68296001(CHIPS)':
 'IO148': CDS_PINID='IO148';
NODE_NAME     R2U15 2
 '@BASEBOARD_FAB2_LIB.BASEBOARD_FAB2(SCH_1):PAGE107_I490@MSTR_DISCRETE.RES(CHIPS)':
 'B': CDS_PINID='B';
NET_NAME
'P3E_CPU0_PE1_SS_R_RXN<1>'
 '@BASEBOARD_FAB2_LIB.BASEBOARD_FAB2(SCH_1):P3E_CPU0_PE1_SS_R_RXN'<1>:
 C_SIGNAL='@baseboard_fab2_lib.baseboard_fab2(sch_1):p3e_cpu0_pe1_ss_r_rxn(1)';
NODE_NAME     J8G1 142
 '@BASEBOARD_FAB2_LIB.BASEBOARD_FAB2(SCH_1):PAGE109_I78@MSTR_SCONN.SCONN200_H68296001(CHIPS)':
 'IO142': CDS_PINID='IO142';
NODE_NAME     R2U17 2
 '@BASEBOARD_FAB2_LIB.BASEBOARD_FAB2(SCH_1):PAGE107_I492@MSTR_DISCRETE.RES(CHIPS)':
 'B': CDS_PINID='B';
NET_NAME
'P3E_CPU0_PE1_SS_R_RXN<2>'
 '@BASEBOARD_FAB2_LIB.BASEBOARD_FAB2(SCH_1):P3E_CPU0_PE1_SS_R_RXN'<2>:
 C_SIGNAL='@baseboard_fab2_lib.baseboard_fab2(sch_1):p3e_cpu0_pe1_ss_r_rxn(2)';
NODE_NAME     J8G1 136
 '@BASEBOARD_FAB2_LIB.BASEBOARD_FAB2(SCH_1):PAGE109_I78@MSTR_SCONN.SCONN200_H68296001(CHIPS)':
 'IO136': CDS_PINID='IO136';
NODE_NAME     R2U19 2
 '@BASEBOARD_FAB2_LIB.BASEBOARD_FAB2(SCH_1):PAGE107_I493@MSTR_DISCRETE.RES(CHIPS)':
 'B': CDS_PINID='B';
NET_NAME
'P3E_CPU0_PE1_SS_R_RXN<3>'
 '@BASEBOARD_FAB2_LIB.BASEBOARD_FAB2(SCH_1):P3E_CPU0_PE1_SS_R_RXN'<3>:
 C_SIGNAL='@baseboard_fab2_lib.baseboard_fab2(sch_1):p3e_cpu0_pe1_ss_r_rxn(3)';
NODE_NAME     J8G1 130
 '@BASEBOARD_FAB2_LIB.BASEBOARD_FAB2(SCH_1):PAGE109_I78@MSTR_SCONN.SCONN200_H68296001(CHIPS)':
 'IO130': CDS_PINID='IO130';
NODE_NAME     R2U21 2
 '@BASEBOARD_FAB2_LIB.BASEBOARD_FAB2(SCH_1):PAGE107_I491@MSTR_DISCRETE.RES(CHIPS)':
 'B': CDS_PINID='B';
NET_NAME
'P3E_CPU0_PE1_SS_R_RXN<4>'
 '@BASEBOARD_FAB2_LIB.BASEBOARD_FAB2(SCH_1):P3E_CPU0_PE1_SS_R_RXN'<4>:
 C_SIGNAL='@baseboard_fab2_lib.baseboard_fab2(sch_1):p3e_cpu0_pe1_ss_r_rxn(4)';
NODE_NAME     J8G1 124
 '@BASEBOARD_FAB2_LIB.BASEBOARD_FAB2(SCH_1):PAGE109_I78@MSTR_SCONN.SCONN200_H68296001(CHIPS)':
 'IO124': CDS_PINID='IO124';
NODE_NAME     R2U23 2
 '@BASEBOARD_FAB2_LIB.BASEBOARD_FAB2(SCH_1):PAGE107_I495@MSTR_DISCRETE.RES(CHIPS)':
 'B': CDS_PINID='B';
NET_NAME
'P3E_CPU0_PE1_SS_R_RXN<5>'
 '@BASEBOARD_FAB2_LIB.BASEBOARD_FAB2(SCH_1):P3E_CPU0_PE1_SS_R_RXN'<5>:
 C_SIGNAL='@baseboard_fab2_lib.baseboard_fab2(sch_1):p3e_cpu0_pe1_ss_r_rxn(5)';
NODE_NAME     J8G1 118
 '@BASEBOARD_FAB2_LIB.BASEBOARD_FAB2(SCH_1):PAGE109_I78@MSTR_SCONN.SCONN200_H68296001(CHIPS)':
 'IO118': CDS_PINID='IO118';
NODE_NAME     R2U25 2
 '@BASEBOARD_FAB2_LIB.BASEBOARD_FAB2(SCH_1):PAGE107_I496@MSTR_DISCRETE.RES(CHIPS)':
 'B': CDS_PINID='B';
NET_NAME
'P3E_CPU0_PE1_SS_R_RXN<6>'
 '@BASEBOARD_FAB2_LIB.BASEBOARD_FAB2(SCH_1):P3E_CPU0_PE1_SS_R_RXN'<6>:
 C_SIGNAL='@baseboard_fab2_lib.baseboard_fab2(sch_1):p3e_cpu0_pe1_ss_r_rxn(6)';
NODE_NAME     J8G1 112
 '@BASEBOARD_FAB2_LIB.BASEBOARD_FAB2(SCH_1):PAGE109_I78@MSTR_SCONN.SCONN200_H68296001(CHIPS)':
 'IO112': CDS_PINID='IO112';
NODE_NAME     R2U27 2
 '@BASEBOARD_FAB2_LIB.BASEBOARD_FAB2(SCH_1):PAGE107_I497@MSTR_DISCRETE.RES(CHIPS)':
 'B': CDS_PINID='B';
NET_NAME
'P3E_CPU0_PE1_SS_R_RXN<7>'
 '@BASEBOARD_FAB2_LIB.BASEBOARD_FAB2(SCH_1):P3E_CPU0_PE1_SS_R_RXN'<7>:
 C_SIGNAL='@baseboard_fab2_lib.baseboard_fab2(sch_1):p3e_cpu0_pe1_ss_r_rxn(7)';
NODE_NAME     J8G1 106
 '@BASEBOARD_FAB2_LIB.BASEBOARD_FAB2(SCH_1):PAGE109_I78@MSTR_SCONN.SCONN200_H68296001(CHIPS)':
 'IO106': CDS_PINID='IO106';
NODE_NAME     R2U29 2
 '@BASEBOARD_FAB2_LIB.BASEBOARD_FAB2(SCH_1):PAGE107_I494@MSTR_DISCRETE.RES(CHIPS)':
 'B': CDS_PINID='B';
NET_NAME
'P3E_CPU0_PE1_SS_R_RXP<0>'
 '@BASEBOARD_FAB2_LIB.BASEBOARD_FAB2(SCH_1):P3E_CPU0_PE1_SS_R_RXP'<0>:
 C_SIGNAL='@baseboard_fab2_lib.baseboard_fab2(sch_1):p3e_cpu0_pe1_ss_r_rxp(0)';
NODE_NAME     J8G1 150
 '@BASEBOARD_FAB2_LIB.BASEBOARD_FAB2(SCH_1):PAGE109_I78@MSTR_SCONN.SCONN200_H68296001(CHIPS)':
 'IO150': CDS_PINID='IO150';
NODE_NAME     R2U14 2
 '@BASEBOARD_FAB2_LIB.BASEBOARD_FAB2(SCH_1):PAGE107_I499@MSTR_DISCRETE.RES(CHIPS)':
 'B': CDS_PINID='B';
NET_NAME
'P3E_CPU0_PE1_SS_R_RXP<1>'
 '@BASEBOARD_FAB2_LIB.BASEBOARD_FAB2(SCH_1):P3E_CPU0_PE1_SS_R_RXP'<1>:
 C_SIGNAL='@baseboard_fab2_lib.baseboard_fab2(sch_1):p3e_cpu0_pe1_ss_r_rxp(1)';
NODE_NAME     J8G1 144
 '@BASEBOARD_FAB2_LIB.BASEBOARD_FAB2(SCH_1):PAGE109_I78@MSTR_SCONN.SCONN200_H68296001(CHIPS)':
 'IO144': CDS_PINID='IO144';
NODE_NAME     R2U16 2
 '@BASEBOARD_FAB2_LIB.BASEBOARD_FAB2(SCH_1):PAGE107_I501@MSTR_DISCRETE.RES(CHIPS)':
 'B': CDS_PINID='B';
NET_NAME
'P3E_CPU0_PE1_SS_R_RXP<2>'
 '@BASEBOARD_FAB2_LIB.BASEBOARD_FAB2(SCH_1):P3E_CPU0_PE1_SS_R_RXP'<2>:
 C_SIGNAL='@baseboard_fab2_lib.baseboard_fab2(sch_1):p3e_cpu0_pe1_ss_r_rxp(2)';
NODE_NAME     J8G1 138
 '@BASEBOARD_FAB2_LIB.BASEBOARD_FAB2(SCH_1):PAGE109_I78@MSTR_SCONN.SCONN200_H68296001(CHIPS)':
 'IO138': CDS_PINID='IO138';
NODE_NAME     R2U18 2
 '@BASEBOARD_FAB2_LIB.BASEBOARD_FAB2(SCH_1):PAGE107_I502@MSTR_DISCRETE.RES(CHIPS)':
 'B': CDS_PINID='B';
NET_NAME
'P3E_CPU0_PE1_SS_R_RXP<3>'
 '@BASEBOARD_FAB2_LIB.BASEBOARD_FAB2(SCH_1):P3E_CPU0_PE1_SS_R_RXP'<3>:
 C_SIGNAL='@baseboard_fab2_lib.baseboard_fab2(sch_1):p3e_cpu0_pe1_ss_r_rxp(3)';
NODE_NAME     J8G1 132
 '@BASEBOARD_FAB2_LIB.BASEBOARD_FAB2(SCH_1):PAGE109_I78@MSTR_SCONN.SCONN200_H68296001(CHIPS)':
 'IO132': CDS_PINID='IO132';
NODE_NAME     R2U20 2
 '@BASEBOARD_FAB2_LIB.BASEBOARD_FAB2(SCH_1):PAGE107_I503@MSTR_DISCRETE.RES(CHIPS)':
 'B': CDS_PINID='B';
NET_NAME
'P3E_CPU0_PE1_SS_R_RXP<4>'
 '@BASEBOARD_FAB2_LIB.BASEBOARD_FAB2(SCH_1):P3E_CPU0_PE1_SS_R_RXP'<4>:
 C_SIGNAL='@baseboard_fab2_lib.baseboard_fab2(sch_1):p3e_cpu0_pe1_ss_r_rxp(4)';
NODE_NAME     J8G1 126
 '@BASEBOARD_FAB2_LIB.BASEBOARD_FAB2(SCH_1):PAGE109_I78@MSTR_SCONN.SCONN200_H68296001(CHIPS)':
 'IO126': CDS_PINID='IO126';
NODE_NAME     R2U22 2
 '@BASEBOARD_FAB2_LIB.BASEBOARD_FAB2(SCH_1):PAGE107_I504@MSTR_DISCRETE.RES(CHIPS)':
 'B': CDS_PINID='B';
NET_NAME
'P3E_CPU0_PE1_SS_R_RXP<5>'
 '@BASEBOARD_FAB2_LIB.BASEBOARD_FAB2(SCH_1):P3E_CPU0_PE1_SS_R_RXP'<5>:
 C_SIGNAL='@baseboard_fab2_lib.baseboard_fab2(sch_1):p3e_cpu0_pe1_ss_r_rxp(5)';
NODE_NAME     J8G1 120
 '@BASEBOARD_FAB2_LIB.BASEBOARD_FAB2(SCH_1):PAGE109_I78@MSTR_SCONN.SCONN200_H68296001(CHIPS)':
 'IO120': CDS_PINID='IO120';
NODE_NAME     R2U24 2
 '@BASEBOARD_FAB2_LIB.BASEBOARD_FAB2(SCH_1):PAGE107_I505@MSTR_DISCRETE.RES(CHIPS)':
 'B': CDS_PINID='B';
NET_NAME
'P3E_CPU0_PE1_SS_R_RXP<6>'
 '@BASEBOARD_FAB2_LIB.BASEBOARD_FAB2(SCH_1):P3E_CPU0_PE1_SS_R_RXP'<6>:
 C_SIGNAL='@baseboard_fab2_lib.baseboard_fab2(sch_1):p3e_cpu0_pe1_ss_r_rxp(6)';
NODE_NAME     J8G1 114
 '@BASEBOARD_FAB2_LIB.BASEBOARD_FAB2(SCH_1):PAGE109_I78@MSTR_SCONN.SCONN200_H68296001(CHIPS)':
 'IO114': CDS_PINID='IO114';
NODE_NAME     R2U26 2
 '@BASEBOARD_FAB2_LIB.BASEBOARD_FAB2(SCH_1):PAGE107_I498@MSTR_DISCRETE.RES(CHIPS)':
 'B': CDS_PINID='B';
NET_NAME
'P3E_CPU0_PE1_SS_R_RXP<7>'
 '@BASEBOARD_FAB2_LIB.BASEBOARD_FAB2(SCH_1):P3E_CPU0_PE1_SS_R_RXP'<7>:
 C_SIGNAL='@baseboard_fab2_lib.baseboard_fab2(sch_1):p3e_cpu0_pe1_ss_r_rxp(7)';
NODE_NAME     J8G1 108
 '@BASEBOARD_FAB2_LIB.BASEBOARD_FAB2(SCH_1):PAGE109_I78@MSTR_SCONN.SCONN200_H68296001(CHIPS)':
 'IO108': CDS_PINID='IO108';
NODE_NAME     R2U28 2
 '@BASEBOARD_FAB2_LIB.BASEBOARD_FAB2(SCH_1):PAGE107_I500@MSTR_DISCRETE.RES(CHIPS)':
 'B': CDS_PINID='B';
NET_NAME
'P3E_CPU0_PE1_SS_TXN<0>'
 '@BASEBOARD_FAB2_LIB.BASEBOARD_FAB2(SCH_1):P3E_CPU0_PE1_SS_TXN'<0>:
 C_SIGNAL='@baseboard_fab2_lib.baseboard_fab2(sch_1):p3e_cpu0_pe1_ss_txn(0)';
NODE_NAME     U5D1 DA2
 '@BASEBOARD_FAB2_LIB.BASEBOARD_FAB2(SCH_1):PAGE30_I84@CHPSET_LIB.SKX_EXT_B(CHIPS)':
 'PE1_TX_DN'<0>: CDS_PINID='PE1_TX_DN(0)';
NODE_NAME     C3P13 1
 '@BASEBOARD_FAB2_LIB.BASEBOARD_FAB2(SCH_1):PAGE107_I207@MSTR_DISCRETE.CAP(CHIPS)':
 'A': CDS_PINID='A';
NODE_NAME     C3P12 1
 '@BASEBOARD_FAB2_LIB.BASEBOARD_FAB2(SCH_1):PAGE107_I481@MSTR_DISCRETE.CAP(CHIPS)':
 'A': CDS_PINID='A';
NET_NAME
'P3E_CPU0_PE1_SS_TXN<1>'
 '@BASEBOARD_FAB2_LIB.BASEBOARD_FAB2(SCH_1):P3E_CPU0_PE1_SS_TXN'<1>:
 C_SIGNAL='@baseboard_fab2_lib.baseboard_fab2(sch_1):p3e_cpu0_pe1_ss_txn(1)';
NODE_NAME     U5D1 DC2
 '@BASEBOARD_FAB2_LIB.BASEBOARD_FAB2(SCH_1):PAGE30_I84@CHPSET_LIB.SKX_EXT_B(CHIPS)':
 'PE1_TX_DN'<1>: CDS_PINID='PE1_TX_DN(1)';
NODE_NAME     C3P17 1
 '@BASEBOARD_FAB2_LIB.BASEBOARD_FAB2(SCH_1):PAGE107_I208@MSTR_DISCRETE.CAP(CHIPS)':
 'A': CDS_PINID='A';
NODE_NAME     C3P16 1
 '@BASEBOARD_FAB2_LIB.BASEBOARD_FAB2(SCH_1):PAGE107_I476@MSTR_DISCRETE.CAP(CHIPS)':
 'A': CDS_PINID='A';
NET_NAME
'P3E_CPU0_PE1_SS_TXN<2>'
 '@BASEBOARD_FAB2_LIB.BASEBOARD_FAB2(SCH_1):P3E_CPU0_PE1_SS_TXN'<2>:
 C_SIGNAL='@baseboard_fab2_lib.baseboard_fab2(sch_1):p3e_cpu0_pe1_ss_txn(2)';
NODE_NAME     U5D1 DE2
 '@BASEBOARD_FAB2_LIB.BASEBOARD_FAB2(SCH_1):PAGE30_I84@CHPSET_LIB.SKX_EXT_B(CHIPS)':
 'PE1_TX_DN'<2>: CDS_PINID='PE1_TX_DN(2)';
NODE_NAME     C3P20 1
 '@BASEBOARD_FAB2_LIB.BASEBOARD_FAB2(SCH_1):PAGE107_I215@MSTR_DISCRETE.CAP(CHIPS)':
 'A': CDS_PINID='A';
NODE_NAME     C3P21 1
 '@BASEBOARD_FAB2_LIB.BASEBOARD_FAB2(SCH_1):PAGE107_I480@MSTR_DISCRETE.CAP(CHIPS)':
 'A': CDS_PINID='A';
NET_NAME
'P3E_CPU0_PE1_SS_TXN<3>'
 '@BASEBOARD_FAB2_LIB.BASEBOARD_FAB2(SCH_1):P3E_CPU0_PE1_SS_TXN'<3>:
 C_SIGNAL='@baseboard_fab2_lib.baseboard_fab2(sch_1):p3e_cpu0_pe1_ss_txn(3)';
NODE_NAME     U5D1 DE4
 '@BASEBOARD_FAB2_LIB.BASEBOARD_FAB2(SCH_1):PAGE30_I84@CHPSET_LIB.SKX_EXT_B(CHIPS)':
 'PE1_TX_DN'<3>: CDS_PINID='PE1_TX_DN(3)';
NODE_NAME     C3P25 1
 '@BASEBOARD_FAB2_LIB.BASEBOARD_FAB2(SCH_1):PAGE107_I216@MSTR_DISCRETE.CAP(CHIPS)':
 'A': CDS_PINID='A';
NODE_NAME     C3P24 1
 '@BASEBOARD_FAB2_LIB.BASEBOARD_FAB2(SCH_1):PAGE107_I479@MSTR_DISCRETE.CAP(CHIPS)':
 'A': CDS_PINID='A';
NET_NAME
'P3E_CPU0_PE1_SS_TXN<4>'
 '@BASEBOARD_FAB2_LIB.BASEBOARD_FAB2(SCH_1):P3E_CPU0_PE1_SS_TXN'<4>:
 C_SIGNAL='@baseboard_fab2_lib.baseboard_fab2(sch_1):p3e_cpu0_pe1_ss_txn(4)';
NODE_NAME     U5D1 DG4
 '@BASEBOARD_FAB2_LIB.BASEBOARD_FAB2(SCH_1):PAGE30_I84@CHPSET_LIB.SKX_EXT_B(CHIPS)':
 'PE1_TX_DN'<4>: CDS_PINID='PE1_TX_DN(4)';
NODE_NAME     C3P28 1
 '@BASEBOARD_FAB2_LIB.BASEBOARD_FAB2(SCH_1):PAGE107_I232@MSTR_DISCRETE.CAP(CHIPS)':
 'A': CDS_PINID='A';
NODE_NAME     C3P29 1
 '@BASEBOARD_FAB2_LIB.BASEBOARD_FAB2(SCH_1):PAGE107_I478@MSTR_DISCRETE.CAP(CHIPS)':
 'A': CDS_PINID='A';
NET_NAME
'P3E_CPU0_PE1_SS_TXN<5>'
 '@BASEBOARD_FAB2_LIB.BASEBOARD_FAB2(SCH_1):P3E_CPU0_PE1_SS_TXN'<5>:
 C_SIGNAL='@baseboard_fab2_lib.baseboard_fab2(sch_1):p3e_cpu0_pe1_ss_txn(5)';
NODE_NAME     U5D1 DK3
 '@BASEBOARD_FAB2_LIB.BASEBOARD_FAB2(SCH_1):PAGE30_I84@CHPSET_LIB.SKX_EXT_B(CHIPS)':
 'PE1_TX_DN'<5>: CDS_PINID='PE1_TX_DN(5)';
NODE_NAME     C3P32 1
 '@BASEBOARD_FAB2_LIB.BASEBOARD_FAB2(SCH_1):PAGE107_I234@MSTR_DISCRETE.CAP(CHIPS)':
 'A': CDS_PINID='A';
NODE_NAME     C3P33 1
 '@BASEBOARD_FAB2_LIB.BASEBOARD_FAB2(SCH_1):PAGE107_I477@MSTR_DISCRETE.CAP(CHIPS)':
 'A': CDS_PINID='A';
NET_NAME
'P3E_CPU0_PE1_SS_TXN<6>'
 '@BASEBOARD_FAB2_LIB.BASEBOARD_FAB2(SCH_1):P3E_CPU0_PE1_SS_TXN'<6>:
 C_SIGNAL='@baseboard_fab2_lib.baseboard_fab2(sch_1):p3e_cpu0_pe1_ss_txn(6)';
NODE_NAME     U5D1 DM3
 '@BASEBOARD_FAB2_LIB.BASEBOARD_FAB2(SCH_1):PAGE30_I84@CHPSET_LIB.SKX_EXT_B(CHIPS)':
 'PE1_TX_DN'<6>: CDS_PINID='PE1_TX_DN(6)';
NODE_NAME     C3P37 1
 '@BASEBOARD_FAB2_LIB.BASEBOARD_FAB2(SCH_1):PAGE107_I235@MSTR_DISCRETE.CAP(CHIPS)':
 'A': CDS_PINID='A';
NODE_NAME     C3P36 1
 '@BASEBOARD_FAB2_LIB.BASEBOARD_FAB2(SCH_1):PAGE107_I475@MSTR_DISCRETE.CAP(CHIPS)':
 'A': CDS_PINID='A';
NET_NAME
'P3E_CPU0_PE1_SS_TXN<7>'
 '@BASEBOARD_FAB2_LIB.BASEBOARD_FAB2(SCH_1):P3E_CPU0_PE1_SS_TXN'<7>:
 C_SIGNAL='@baseboard_fab2_lib.baseboard_fab2(sch_1):p3e_cpu0_pe1_ss_txn(7)';
NODE_NAME     U5D1 DN4
 '@BASEBOARD_FAB2_LIB.BASEBOARD_FAB2(SCH_1):PAGE30_I84@CHPSET_LIB.SKX_EXT_B(CHIPS)':
 'PE1_TX_DN'<7>: CDS_PINID='PE1_TX_DN(7)';
NODE_NAME     C3P40 1
 '@BASEBOARD_FAB2_LIB.BASEBOARD_FAB2(SCH_1):PAGE107_I241@MSTR_DISCRETE.CAP(CHIPS)':
 'A': CDS_PINID='A';
NODE_NAME     C3P41 1
 '@BASEBOARD_FAB2_LIB.BASEBOARD_FAB2(SCH_1):PAGE107_I474@MSTR_DISCRETE.CAP(CHIPS)':
 'A': CDS_PINID='A';
NET_NAME
'P3E_CPU0_PE1_SS_TXP<0>'
 '@BASEBOARD_FAB2_LIB.BASEBOARD_FAB2(SCH_1):P3E_CPU0_PE1_SS_TXP'<0>:
 C_SIGNAL='@baseboard_fab2_lib.baseboard_fab2(sch_1):p3e_cpu0_pe1_ss_txp(0)';
NODE_NAME     U5D1 CW2
 '@BASEBOARD_FAB2_LIB.BASEBOARD_FAB2(SCH_1):PAGE30_I84@CHPSET_LIB.SKX_EXT_B(CHIPS)':
 'PE1_TX_DP'<0>: CDS_PINID='PE1_TX_DP(0)';
NODE_NAME     C3P11 1
 '@BASEBOARD_FAB2_LIB.BASEBOARD_FAB2(SCH_1):PAGE107_I212@MSTR_DISCRETE.CAP(CHIPS)':
 'A': CDS_PINID='A';
NODE_NAME     C3P10 1
 '@BASEBOARD_FAB2_LIB.BASEBOARD_FAB2(SCH_1):PAGE107_I482@MSTR_DISCRETE.CAP(CHIPS)':
 'A': CDS_PINID='A';
NET_NAME
'P3E_CPU0_PE1_SS_TXP<1>'
 '@BASEBOARD_FAB2_LIB.BASEBOARD_FAB2(SCH_1):P3E_CPU0_PE1_SS_TXP'<1>:
 C_SIGNAL='@baseboard_fab2_lib.baseboard_fab2(sch_1):p3e_cpu0_pe1_ss_txp(1)';
NODE_NAME     U5D1 DB1
 '@BASEBOARD_FAB2_LIB.BASEBOARD_FAB2(SCH_1):PAGE30_I84@CHPSET_LIB.SKX_EXT_B(CHIPS)':
 'PE1_TX_DP'<1>: CDS_PINID='PE1_TX_DP(1)';
NODE_NAME     C3P15 1
 '@BASEBOARD_FAB2_LIB.BASEBOARD_FAB2(SCH_1):PAGE107_I226@MSTR_DISCRETE.CAP(CHIPS)':
 'A': CDS_PINID='A';
NODE_NAME     C3P14 1
 '@BASEBOARD_FAB2_LIB.BASEBOARD_FAB2(SCH_1):PAGE107_I483@MSTR_DISCRETE.CAP(CHIPS)':
 'A': CDS_PINID='A';
NET_NAME
'P3E_CPU0_PE1_SS_TXP<2>'
 '@BASEBOARD_FAB2_LIB.BASEBOARD_FAB2(SCH_1):P3E_CPU0_PE1_SS_TXP'<2>:
 C_SIGNAL='@baseboard_fab2_lib.baseboard_fab2(sch_1):p3e_cpu0_pe1_ss_txp(2)';
NODE_NAME     U5D1 DD3
 '@BASEBOARD_FAB2_LIB.BASEBOARD_FAB2(SCH_1):PAGE30_I84@CHPSET_LIB.SKX_EXT_B(CHIPS)':
 'PE1_TX_DP'<2>: CDS_PINID='PE1_TX_DP(2)';
NODE_NAME     C3P18 1
 '@BASEBOARD_FAB2_LIB.BASEBOARD_FAB2(SCH_1):PAGE107_I219@MSTR_DISCRETE.CAP(CHIPS)':
 'A': CDS_PINID='A';
NODE_NAME     C3P19 1
 '@BASEBOARD_FAB2_LIB.BASEBOARD_FAB2(SCH_1):PAGE107_I485@MSTR_DISCRETE.CAP(CHIPS)':
 'A': CDS_PINID='A';
NET_NAME
'P3E_CPU0_PE1_SS_TXP<3>'
 '@BASEBOARD_FAB2_LIB.BASEBOARD_FAB2(SCH_1):P3E_CPU0_PE1_SS_TXP'<3>:
 C_SIGNAL='@baseboard_fab2_lib.baseboard_fab2(sch_1):p3e_cpu0_pe1_ss_txp(3)';
NODE_NAME     U5D1 DC4
 '@BASEBOARD_FAB2_LIB.BASEBOARD_FAB2(SCH_1):PAGE30_I84@CHPSET_LIB.SKX_EXT_B(CHIPS)':
 'PE1_TX_DP'<3>: CDS_PINID='PE1_TX_DP(3)';
NODE_NAME     C3P23 1
 '@BASEBOARD_FAB2_LIB.BASEBOARD_FAB2(SCH_1):PAGE107_I229@MSTR_DISCRETE.CAP(CHIPS)':
 'A': CDS_PINID='A';
NODE_NAME     C3P22 1
 '@BASEBOARD_FAB2_LIB.BASEBOARD_FAB2(SCH_1):PAGE107_I484@MSTR_DISCRETE.CAP(CHIPS)':
 'A': CDS_PINID='A';
NET_NAME
'P3E_CPU0_PE1_SS_TXP<4>'
 '@BASEBOARD_FAB2_LIB.BASEBOARD_FAB2(SCH_1):P3E_CPU0_PE1_SS_TXP'<4>:
 C_SIGNAL='@baseboard_fab2_lib.baseboard_fab2(sch_1):p3e_cpu0_pe1_ss_txp(4)';
NODE_NAME     U5D1 DF3
 '@BASEBOARD_FAB2_LIB.BASEBOARD_FAB2(SCH_1):PAGE30_I84@CHPSET_LIB.SKX_EXT_B(CHIPS)':
 'PE1_TX_DP'<4>: CDS_PINID='PE1_TX_DP(4)';
NODE_NAME     C3P27 1
 '@BASEBOARD_FAB2_LIB.BASEBOARD_FAB2(SCH_1):PAGE107_I223@MSTR_DISCRETE.CAP(CHIPS)':
 'A': CDS_PINID='A';
NODE_NAME     C3P26 1
 '@BASEBOARD_FAB2_LIB.BASEBOARD_FAB2(SCH_1):PAGE107_I487@MSTR_DISCRETE.CAP(CHIPS)':
 'A': CDS_PINID='A';
NET_NAME
'P3E_CPU0_PE1_SS_TXP<5>'
 '@BASEBOARD_FAB2_LIB.BASEBOARD_FAB2(SCH_1):P3E_CPU0_PE1_SS_TXP'<5>:
 C_SIGNAL='@baseboard_fab2_lib.baseboard_fab2(sch_1):p3e_cpu0_pe1_ss_txp(5)';
NODE_NAME     U5D1 DH3
 '@BASEBOARD_FAB2_LIB.BASEBOARD_FAB2(SCH_1):PAGE30_I84@CHPSET_LIB.SKX_EXT_B(CHIPS)':
 'PE1_TX_DP'<5>: CDS_PINID='PE1_TX_DP(5)';
NODE_NAME     C3P30 1
 '@BASEBOARD_FAB2_LIB.BASEBOARD_FAB2(SCH_1):PAGE107_I245@MSTR_DISCRETE.CAP(CHIPS)':
 'A': CDS_PINID='A';
NODE_NAME     C3P31 1
 '@BASEBOARD_FAB2_LIB.BASEBOARD_FAB2(SCH_1):PAGE107_I488@MSTR_DISCRETE.CAP(CHIPS)':
 'A': CDS_PINID='A';
NET_NAME
'P3E_CPU0_PE1_SS_TXP<6>'
 '@BASEBOARD_FAB2_LIB.BASEBOARD_FAB2(SCH_1):P3E_CPU0_PE1_SS_TXP'<6>:
 C_SIGNAL='@baseboard_fab2_lib.baseboard_fab2(sch_1):p3e_cpu0_pe1_ss_txp(6)';
NODE_NAME     U5D1 DL2
 '@BASEBOARD_FAB2_LIB.BASEBOARD_FAB2(SCH_1):PAGE30_I84@CHPSET_LIB.SKX_EXT_B(CHIPS)':
 'PE1_TX_DP'<6>: CDS_PINID='PE1_TX_DP(6)';
NODE_NAME     C3P35 1
 '@BASEBOARD_FAB2_LIB.BASEBOARD_FAB2(SCH_1):PAGE107_I240@MSTR_DISCRETE.CAP(CHIPS)':
 'A': CDS_PINID='A';
NODE_NAME     C3P34 1
 '@BASEBOARD_FAB2_LIB.BASEBOARD_FAB2(SCH_1):PAGE107_I489@MSTR_DISCRETE.CAP(CHIPS)':
 'A': CDS_PINID='A';
NET_NAME
'P3E_CPU0_PE1_SS_TXP<7>'
 '@BASEBOARD_FAB2_LIB.BASEBOARD_FAB2(SCH_1):P3E_CPU0_PE1_SS_TXP'<7>:
 C_SIGNAL='@baseboard_fab2_lib.baseboard_fab2(sch_1):p3e_cpu0_pe1_ss_txp(7)';
NODE_NAME     U5D1 DP3
 '@BASEBOARD_FAB2_LIB.BASEBOARD_FAB2(SCH_1):PAGE30_I84@CHPSET_LIB.SKX_EXT_B(CHIPS)':
 'PE1_TX_DP'<7>: CDS_PINID='PE1_TX_DP(7)';
NODE_NAME     C3P39 1
 '@BASEBOARD_FAB2_LIB.BASEBOARD_FAB2(SCH_1):PAGE107_I248@MSTR_DISCRETE.CAP(CHIPS)':
 'A': CDS_PINID='A';
NODE_NAME     C3P38 1
 '@BASEBOARD_FAB2_LIB.BASEBOARD_FAB2(SCH_1):PAGE107_I486@MSTR_DISCRETE.CAP(CHIPS)':
 'A': CDS_PINID='A';
NET_NAME
'P3E_CPU0_PE2_SS_C_TXN<0>'
 '@BASEBOARD_FAB2_LIB.BASEBOARD_FAB2(SCH_1):P3E_CPU0_PE2_SS_C_TXN'<0>:
 C_SIGNAL='@baseboard_fab2_lib.baseboard_fab2(sch_1):p3e_cpu0_pe2_ss_c_txn(0)';
NODE_NAME     C8G10 2
 '@BASEBOARD_FAB2_LIB.BASEBOARD_FAB2(SCH_1):PAGE105_I96@MSTR_DISCRETE.CAP(CHIPS)':
 'B': CDS_PINID='B';
NODE_NAME     J8G1 151
 '@BASEBOARD_FAB2_LIB.BASEBOARD_FAB2(SCH_1):PAGE109_I78@MSTR_SCONN.SCONN200_H68296001(CHIPS)':
 'IO151': CDS_PINID='IO151';
NET_NAME
'P3E_CPU0_PE2_SS_C_TXN<10>'
 '@BASEBOARD_FAB2_LIB.BASEBOARD_FAB2(SCH_1):P3E_CPU0_PE2_SS_C_TXN'<10>:
 C_SIGNAL='@baseboard_fab2_lib.baseboard_fab2(sch_1):p3e_cpu0_pe2_ss_c_txn(10)';
NODE_NAME     C7G16 2
 '@BASEBOARD_FAB2_LIB.BASEBOARD_FAB2(SCH_1):PAGE105_I31@MSTR_DISCRETE.CAP(CHIPS)':
 'B': CDS_PINID='B';
NODE_NAME     CONX8 15
 '@BASEBOARD_FAB2_LIB.BASEBOARD_FAB2(SCH_1):PAGE245_I48@W_HDL.SMC-CONN60A-22-GP(CHIPS)':
 '15': CDS_PINID='\15\';
NET_NAME
'P3E_CPU0_PE2_SS_C_TXN<11>'
 '@BASEBOARD_FAB2_LIB.BASEBOARD_FAB2(SCH_1):P3E_CPU0_PE2_SS_C_TXN'<11>:
 C_SIGNAL='@baseboard_fab2_lib.baseboard_fab2(sch_1):p3e_cpu0_pe2_ss_c_txn(11)';
NODE_NAME     C7G13 2
 '@BASEBOARD_FAB2_LIB.BASEBOARD_FAB2(SCH_1):PAGE105_I13@MSTR_DISCRETE.CAP(CHIPS)':
 'B': CDS_PINID='B';
NODE_NAME     CONX8 23
 '@BASEBOARD_FAB2_LIB.BASEBOARD_FAB2(SCH_1):PAGE245_I48@W_HDL.SMC-CONN60A-22-GP(CHIPS)':
 '23': CDS_PINID='\23\';
NET_NAME
'P3E_CPU0_PE2_SS_C_TXN<12>'
 '@BASEBOARD_FAB2_LIB.BASEBOARD_FAB2(SCH_1):P3E_CPU0_PE2_SS_C_TXN'<12>:
 C_SIGNAL='@baseboard_fab2_lib.baseboard_fab2(sch_1):p3e_cpu0_pe2_ss_c_txn(12)';
NODE_NAME     C7G12 2
 '@BASEBOARD_FAB2_LIB.BASEBOARD_FAB2(SCH_1):PAGE105_I12@MSTR_DISCRETE.CAP(CHIPS)':
 'B': CDS_PINID='B';
NODE_NAME     CONX8 27
 '@BASEBOARD_FAB2_LIB.BASEBOARD_FAB2(SCH_1):PAGE245_I48@W_HDL.SMC-CONN60A-22-GP(CHIPS)':
 '27': CDS_PINID='\27\';
NET_NAME
'P3E_CPU0_PE2_SS_C_TXN<13>'
 '@BASEBOARD_FAB2_LIB.BASEBOARD_FAB2(SCH_1):P3E_CPU0_PE2_SS_C_TXN'<13>:
 C_SIGNAL='@baseboard_fab2_lib.baseboard_fab2(sch_1):p3e_cpu0_pe2_ss_c_txn(13)';
NODE_NAME     C7G10 2
 '@BASEBOARD_FAB2_LIB.BASEBOARD_FAB2(SCH_1):PAGE105_I8@MSTR_DISCRETE.CAP(CHIPS)':
 'B': CDS_PINID='B';
NODE_NAME     CONX8 33
 '@BASEBOARD_FAB2_LIB.BASEBOARD_FAB2(SCH_1):PAGE245_I48@W_HDL.SMC-CONN60A-22-GP(CHIPS)':
 '33': CDS_PINID='\33\';
NET_NAME
'P3E_CPU0_PE2_SS_C_TXN<14>'
 '@BASEBOARD_FAB2_LIB.BASEBOARD_FAB2(SCH_1):P3E_CPU0_PE2_SS_C_TXN'<14>:
 C_SIGNAL='@baseboard_fab2_lib.baseboard_fab2(sch_1):p3e_cpu0_pe2_ss_c_txn(14)';
NODE_NAME     C7G7 2
 '@BASEBOARD_FAB2_LIB.BASEBOARD_FAB2(SCH_1):PAGE105_I7@MSTR_DISCRETE.CAP(CHIPS)':
 'B': CDS_PINID='B';
NODE_NAME     CONX8 41
 '@BASEBOARD_FAB2_LIB.BASEBOARD_FAB2(SCH_1):PAGE245_I48@W_HDL.SMC-CONN60A-22-GP(CHIPS)':
 '41': CDS_PINID='\41\';
NET_NAME
'P3E_CPU0_PE2_SS_C_TXN<15>'
 '@BASEBOARD_FAB2_LIB.BASEBOARD_FAB2(SCH_1):P3E_CPU0_PE2_SS_C_TXN'<15>:
 C_SIGNAL='@baseboard_fab2_lib.baseboard_fab2(sch_1):p3e_cpu0_pe2_ss_c_txn(15)';
NODE_NAME     C7G6 2
 '@BASEBOARD_FAB2_LIB.BASEBOARD_FAB2(SCH_1):PAGE105_I6@MSTR_DISCRETE.CAP(CHIPS)':
 'B': CDS_PINID='B';
NODE_NAME     CONX8 45
 '@BASEBOARD_FAB2_LIB.BASEBOARD_FAB2(SCH_1):PAGE245_I48@W_HDL.SMC-CONN60A-22-GP(CHIPS)':
 '45': CDS_PINID='\45\';
NET_NAME
'P3E_CPU0_PE2_SS_C_TXN<1>'
 '@BASEBOARD_FAB2_LIB.BASEBOARD_FAB2(SCH_1):P3E_CPU0_PE2_SS_C_TXN'<1>:
 C_SIGNAL='@baseboard_fab2_lib.baseboard_fab2(sch_1):p3e_cpu0_pe2_ss_c_txn(1)';
NODE_NAME     C8G7 2
 '@BASEBOARD_FAB2_LIB.BASEBOARD_FAB2(SCH_1):PAGE105_I62@MSTR_DISCRETE.CAP(CHIPS)':
 'B': CDS_PINID='B';
NODE_NAME     J8G1 159
 '@BASEBOARD_FAB2_LIB.BASEBOARD_FAB2(SCH_1):PAGE109_I78@MSTR_SCONN.SCONN200_H68296001(CHIPS)':
 'IO159': CDS_PINID='IO159';
NET_NAME
'P3E_CPU0_PE2_SS_C_TXN<2>'
 '@BASEBOARD_FAB2_LIB.BASEBOARD_FAB2(SCH_1):P3E_CPU0_PE2_SS_C_TXN'<2>:
 C_SIGNAL='@baseboard_fab2_lib.baseboard_fab2(sch_1):p3e_cpu0_pe2_ss_c_txn(2)';
NODE_NAME     C8G6 2
 '@BASEBOARD_FAB2_LIB.BASEBOARD_FAB2(SCH_1):PAGE105_I61@MSTR_DISCRETE.CAP(CHIPS)':
 'B': CDS_PINID='B';
NODE_NAME     J8G1 163
 '@BASEBOARD_FAB2_LIB.BASEBOARD_FAB2(SCH_1):PAGE109_I78@MSTR_SCONN.SCONN200_H68296001(CHIPS)':
 'IO163': CDS_PINID='IO163';
NET_NAME
'P3E_CPU0_PE2_SS_C_TXN<3>'
 '@BASEBOARD_FAB2_LIB.BASEBOARD_FAB2(SCH_1):P3E_CPU0_PE2_SS_C_TXN'<3>:
 C_SIGNAL='@baseboard_fab2_lib.baseboard_fab2(sch_1):p3e_cpu0_pe2_ss_c_txn(3)';
NODE_NAME     C8G4 2
 '@BASEBOARD_FAB2_LIB.BASEBOARD_FAB2(SCH_1):PAGE105_I56@MSTR_DISCRETE.CAP(CHIPS)':
 'B': CDS_PINID='B';
NODE_NAME     J8G1 169
 '@BASEBOARD_FAB2_LIB.BASEBOARD_FAB2(SCH_1):PAGE109_I78@MSTR_SCONN.SCONN200_H68296001(CHIPS)':
 'IO169': CDS_PINID='IO169';
NET_NAME
'P3E_CPU0_PE2_SS_C_TXN<4>'
 '@BASEBOARD_FAB2_LIB.BASEBOARD_FAB2(SCH_1):P3E_CPU0_PE2_SS_C_TXN'<4>:
 C_SIGNAL='@baseboard_fab2_lib.baseboard_fab2(sch_1):p3e_cpu0_pe2_ss_c_txn(4)';
NODE_NAME     C8G2 2
 '@BASEBOARD_FAB2_LIB.BASEBOARD_FAB2(SCH_1):PAGE105_I58@MSTR_DISCRETE.CAP(CHIPS)':
 'B': CDS_PINID='B';
NODE_NAME     J8G1 175
 '@BASEBOARD_FAB2_LIB.BASEBOARD_FAB2(SCH_1):PAGE109_I78@MSTR_SCONN.SCONN200_H68296001(CHIPS)':
 'IO175': CDS_PINID='IO175';
NET_NAME
'P3E_CPU0_PE2_SS_C_TXN<5>'
 '@BASEBOARD_FAB2_LIB.BASEBOARD_FAB2(SCH_1):P3E_CPU0_PE2_SS_C_TXN'<5>:
 C_SIGNAL='@baseboard_fab2_lib.baseboard_fab2(sch_1):p3e_cpu0_pe2_ss_c_txn(5)';
NODE_NAME     C7G26 2
 '@BASEBOARD_FAB2_LIB.BASEBOARD_FAB2(SCH_1):PAGE105_I55@MSTR_DISCRETE.CAP(CHIPS)':
 'B': CDS_PINID='B';
NODE_NAME     J8G1 181
 '@BASEBOARD_FAB2_LIB.BASEBOARD_FAB2(SCH_1):PAGE109_I78@MSTR_SCONN.SCONN200_H68296001(CHIPS)':
 'IO181': CDS_PINID='IO181';
NET_NAME
'P3E_CPU0_PE2_SS_C_TXN<6>'
 '@BASEBOARD_FAB2_LIB.BASEBOARD_FAB2(SCH_1):P3E_CPU0_PE2_SS_C_TXN'<6>:
 C_SIGNAL='@baseboard_fab2_lib.baseboard_fab2(sch_1):p3e_cpu0_pe2_ss_c_txn(6)';
NODE_NAME     C7G24 2
 '@BASEBOARD_FAB2_LIB.BASEBOARD_FAB2(SCH_1):PAGE105_I1@MSTR_DISCRETE.CAP(CHIPS)':
 'B': CDS_PINID='B';
NODE_NAME     J8G1 187
 '@BASEBOARD_FAB2_LIB.BASEBOARD_FAB2(SCH_1):PAGE109_I78@MSTR_SCONN.SCONN200_H68296001(CHIPS)':
 'IO187': CDS_PINID='IO187';
NET_NAME
'P3E_CPU0_PE2_SS_C_TXN<7>'
 '@BASEBOARD_FAB2_LIB.BASEBOARD_FAB2(SCH_1):P3E_CPU0_PE2_SS_C_TXN'<7>:
 C_SIGNAL='@baseboard_fab2_lib.baseboard_fab2(sch_1):p3e_cpu0_pe2_ss_c_txn(7)';
NODE_NAME     C7G22 2
 '@BASEBOARD_FAB2_LIB.BASEBOARD_FAB2(SCH_1):PAGE105_I37@MSTR_DISCRETE.CAP(CHIPS)':
 'B': CDS_PINID='B';
NODE_NAME     J8G1 193
 '@BASEBOARD_FAB2_LIB.BASEBOARD_FAB2(SCH_1):PAGE109_I78@MSTR_SCONN.SCONN200_H68296001(CHIPS)':
 'IO193': CDS_PINID='IO193';
NET_NAME
'P3E_CPU0_PE2_SS_C_TXN<8>'
 '@BASEBOARD_FAB2_LIB.BASEBOARD_FAB2(SCH_1):P3E_CPU0_PE2_SS_C_TXN'<8>:
 C_SIGNAL='@baseboard_fab2_lib.baseboard_fab2(sch_1):p3e_cpu0_pe2_ss_c_txn(8)';
NODE_NAME     CONX8 3
 '@BASEBOARD_FAB2_LIB.BASEBOARD_FAB2(SCH_1):PAGE245_I48@W_HDL.SMC-CONN60A-22-GP(CHIPS)':
 '3': CDS_PINID='\3\';
NODE_NAME     C7G19 2
 '@BASEBOARD_FAB2_LIB.BASEBOARD_FAB2(SCH_1):PAGE105_I257@MSTR_DISCRETE.CAP(CHIPS)':
 'B': CDS_PINID='B';
NET_NAME
'P3E_CPU0_PE2_SS_C_TXN<9>'
 '@BASEBOARD_FAB2_LIB.BASEBOARD_FAB2(SCH_1):P3E_CPU0_PE2_SS_C_TXN'<9>:
 C_SIGNAL='@baseboard_fab2_lib.baseboard_fab2(sch_1):p3e_cpu0_pe2_ss_c_txn(9)';
NODE_NAME     C7G18 2
 '@BASEBOARD_FAB2_LIB.BASEBOARD_FAB2(SCH_1):PAGE105_I32@MSTR_DISCRETE.CAP(CHIPS)':
 'B': CDS_PINID='B';
NODE_NAME     CONX8 9
 '@BASEBOARD_FAB2_LIB.BASEBOARD_FAB2(SCH_1):PAGE245_I48@W_HDL.SMC-CONN60A-22-GP(CHIPS)':
 '9': CDS_PINID='\9\';
NET_NAME
'P3E_CPU0_PE2_SS_C_TXP<0>'
 '@BASEBOARD_FAB2_LIB.BASEBOARD_FAB2(SCH_1):P3E_CPU0_PE2_SS_C_TXP'<0>:
 C_SIGNAL='@baseboard_fab2_lib.baseboard_fab2(sch_1):p3e_cpu0_pe2_ss_c_txp(0)';
NODE_NAME     C8G9 2
 '@BASEBOARD_FAB2_LIB.BASEBOARD_FAB2(SCH_1):PAGE105_I93@MSTR_DISCRETE.CAP(CHIPS)':
 'B': CDS_PINID='B';
NODE_NAME     J8G1 153
 '@BASEBOARD_FAB2_LIB.BASEBOARD_FAB2(SCH_1):PAGE109_I78@MSTR_SCONN.SCONN200_H68296001(CHIPS)':
 'IO153': CDS_PINID='IO153';
NET_NAME
'P3E_CPU0_PE2_SS_C_TXP<10>'
 '@BASEBOARD_FAB2_LIB.BASEBOARD_FAB2(SCH_1):P3E_CPU0_PE2_SS_C_TXP'<10>:
 C_SIGNAL='@baseboard_fab2_lib.baseboard_fab2(sch_1):p3e_cpu0_pe2_ss_c_txp(10)';
NODE_NAME     C7G15 2
 '@BASEBOARD_FAB2_LIB.BASEBOARD_FAB2(SCH_1):PAGE105_I45@MSTR_DISCRETE.CAP(CHIPS)':
 'B': CDS_PINID='B';
NODE_NAME     CONX8 17
 '@BASEBOARD_FAB2_LIB.BASEBOARD_FAB2(SCH_1):PAGE245_I48@W_HDL.SMC-CONN60A-22-GP(CHIPS)':
 '17': CDS_PINID='\17\';
NET_NAME
'P3E_CPU0_PE2_SS_C_TXP<11>'
 '@BASEBOARD_FAB2_LIB.BASEBOARD_FAB2(SCH_1):P3E_CPU0_PE2_SS_C_TXP'<11>:
 C_SIGNAL='@baseboard_fab2_lib.baseboard_fab2(sch_1):p3e_cpu0_pe2_ss_c_txp(11)';
NODE_NAME     C7G14 2
 '@BASEBOARD_FAB2_LIB.BASEBOARD_FAB2(SCH_1):PAGE105_I28@MSTR_DISCRETE.CAP(CHIPS)':
 'B': CDS_PINID='B';
NODE_NAME     CONX8 21
 '@BASEBOARD_FAB2_LIB.BASEBOARD_FAB2(SCH_1):PAGE245_I48@W_HDL.SMC-CONN60A-22-GP(CHIPS)':
 '21': CDS_PINID='\21\';
NET_NAME
'P3E_CPU0_PE2_SS_C_TXP<12>'
 '@BASEBOARD_FAB2_LIB.BASEBOARD_FAB2(SCH_1):P3E_CPU0_PE2_SS_C_TXP'<12>:
 C_SIGNAL='@baseboard_fab2_lib.baseboard_fab2(sch_1):p3e_cpu0_pe2_ss_c_txp(12)';
NODE_NAME     C7G11 2
 '@BASEBOARD_FAB2_LIB.BASEBOARD_FAB2(SCH_1):PAGE105_I27@MSTR_DISCRETE.CAP(CHIPS)':
 'B': CDS_PINID='B';
NODE_NAME     CONX8 29
 '@BASEBOARD_FAB2_LIB.BASEBOARD_FAB2(SCH_1):PAGE245_I48@W_HDL.SMC-CONN60A-22-GP(CHIPS)':
 '29': CDS_PINID='\29\';
NET_NAME
'P3E_CPU0_PE2_SS_C_TXP<13>'
 '@BASEBOARD_FAB2_LIB.BASEBOARD_FAB2(SCH_1):P3E_CPU0_PE2_SS_C_TXP'<13>:
 C_SIGNAL='@baseboard_fab2_lib.baseboard_fab2(sch_1):p3e_cpu0_pe2_ss_c_txp(13)';
NODE_NAME     C7G9 2
 '@BASEBOARD_FAB2_LIB.BASEBOARD_FAB2(SCH_1):PAGE105_I21@MSTR_DISCRETE.CAP(CHIPS)':
 'B': CDS_PINID='B';
NODE_NAME     CONX8 35
 '@BASEBOARD_FAB2_LIB.BASEBOARD_FAB2(SCH_1):PAGE245_I48@W_HDL.SMC-CONN60A-22-GP(CHIPS)':
 '35': CDS_PINID='\35\';
NET_NAME
'P3E_CPU0_PE2_SS_C_TXP<14>'
 '@BASEBOARD_FAB2_LIB.BASEBOARD_FAB2(SCH_1):P3E_CPU0_PE2_SS_C_TXP'<14>:
 C_SIGNAL='@baseboard_fab2_lib.baseboard_fab2(sch_1):p3e_cpu0_pe2_ss_c_txp(14)';
NODE_NAME     C7G8 2
 '@BASEBOARD_FAB2_LIB.BASEBOARD_FAB2(SCH_1):PAGE105_I22@MSTR_DISCRETE.CAP(CHIPS)':
 'B': CDS_PINID='B';
NODE_NAME     CONX8 39
 '@BASEBOARD_FAB2_LIB.BASEBOARD_FAB2(SCH_1):PAGE245_I48@W_HDL.SMC-CONN60A-22-GP(CHIPS)':
 '39': CDS_PINID='\39\';
NET_NAME
'P3E_CPU0_PE2_SS_C_TXP<15>'
 '@BASEBOARD_FAB2_LIB.BASEBOARD_FAB2(SCH_1):P3E_CPU0_PE2_SS_C_TXP'<15>:
 C_SIGNAL='@baseboard_fab2_lib.baseboard_fab2(sch_1):p3e_cpu0_pe2_ss_c_txp(15)';
NODE_NAME     C7G5 2
 '@BASEBOARD_FAB2_LIB.BASEBOARD_FAB2(SCH_1):PAGE105_I20@MSTR_DISCRETE.CAP(CHIPS)':
 'B': CDS_PINID='B';
NODE_NAME     CONX8 47
 '@BASEBOARD_FAB2_LIB.BASEBOARD_FAB2(SCH_1):PAGE245_I48@W_HDL.SMC-CONN60A-22-GP(CHIPS)':
 '47': CDS_PINID='\47\';
NET_NAME
'P3E_CPU0_PE2_SS_C_TXP<1>'
 '@BASEBOARD_FAB2_LIB.BASEBOARD_FAB2(SCH_1):P3E_CPU0_PE2_SS_C_TXP'<1>:
 C_SIGNAL='@baseboard_fab2_lib.baseboard_fab2(sch_1):p3e_cpu0_pe2_ss_c_txp(1)';
NODE_NAME     C8G8 2
 '@BASEBOARD_FAB2_LIB.BASEBOARD_FAB2(SCH_1):PAGE105_I76@MSTR_DISCRETE.CAP(CHIPS)':
 'B': CDS_PINID='B';
NODE_NAME     J8G1 157
 '@BASEBOARD_FAB2_LIB.BASEBOARD_FAB2(SCH_1):PAGE109_I78@MSTR_SCONN.SCONN200_H68296001(CHIPS)':
 'IO157': CDS_PINID='IO157';
NET_NAME
'P3E_CPU0_PE2_SS_C_TXP<2>'
 '@BASEBOARD_FAB2_LIB.BASEBOARD_FAB2(SCH_1):P3E_CPU0_PE2_SS_C_TXP'<2>:
 C_SIGNAL='@baseboard_fab2_lib.baseboard_fab2(sch_1):p3e_cpu0_pe2_ss_c_txp(2)';
NODE_NAME     C8G5 2
 '@BASEBOARD_FAB2_LIB.BASEBOARD_FAB2(SCH_1):PAGE105_I75@MSTR_DISCRETE.CAP(CHIPS)':
 'B': CDS_PINID='B';
NODE_NAME     J8G1 165
 '@BASEBOARD_FAB2_LIB.BASEBOARD_FAB2(SCH_1):PAGE109_I78@MSTR_SCONN.SCONN200_H68296001(CHIPS)':
 'IO165': CDS_PINID='IO165';
NET_NAME
'P3E_CPU0_PE2_SS_C_TXP<3>'
 '@BASEBOARD_FAB2_LIB.BASEBOARD_FAB2(SCH_1):P3E_CPU0_PE2_SS_C_TXP'<3>:
 C_SIGNAL='@baseboard_fab2_lib.baseboard_fab2(sch_1):p3e_cpu0_pe2_ss_c_txp(3)';
NODE_NAME     C8G3 2
 '@BASEBOARD_FAB2_LIB.BASEBOARD_FAB2(SCH_1):PAGE105_I71@MSTR_DISCRETE.CAP(CHIPS)':
 'B': CDS_PINID='B';
NODE_NAME     J8G1 171
 '@BASEBOARD_FAB2_LIB.BASEBOARD_FAB2(SCH_1):PAGE109_I78@MSTR_SCONN.SCONN200_H68296001(CHIPS)':
 'IO171': CDS_PINID='IO171';
NET_NAME
'P3E_CPU0_PE2_SS_C_TXP<4>'
 '@BASEBOARD_FAB2_LIB.BASEBOARD_FAB2(SCH_1):P3E_CPU0_PE2_SS_C_TXP'<4>:
 C_SIGNAL='@baseboard_fab2_lib.baseboard_fab2(sch_1):p3e_cpu0_pe2_ss_c_txp(4)';
NODE_NAME     C8G1 2
 '@BASEBOARD_FAB2_LIB.BASEBOARD_FAB2(SCH_1):PAGE105_I70@MSTR_DISCRETE.CAP(CHIPS)':
 'B': CDS_PINID='B';
NODE_NAME     J8G1 177
 '@BASEBOARD_FAB2_LIB.BASEBOARD_FAB2(SCH_1):PAGE109_I78@MSTR_SCONN.SCONN200_H68296001(CHIPS)':
 'IO177': CDS_PINID='IO177';
NET_NAME
'P3E_CPU0_PE2_SS_C_TXP<5>'
 '@BASEBOARD_FAB2_LIB.BASEBOARD_FAB2(SCH_1):P3E_CPU0_PE2_SS_C_TXP'<5>:
 C_SIGNAL='@baseboard_fab2_lib.baseboard_fab2(sch_1):p3e_cpu0_pe2_ss_c_txp(5)';
NODE_NAME     C7G25 2
 '@BASEBOARD_FAB2_LIB.BASEBOARD_FAB2(SCH_1):PAGE105_I69@MSTR_DISCRETE.CAP(CHIPS)':
 'B': CDS_PINID='B';
NODE_NAME     J8G1 183
 '@BASEBOARD_FAB2_LIB.BASEBOARD_FAB2(SCH_1):PAGE109_I78@MSTR_SCONN.SCONN200_H68296001(CHIPS)':
 'IO183': CDS_PINID='IO183';
NET_NAME
'P3E_CPU0_PE2_SS_C_TXP<6>'
 '@BASEBOARD_FAB2_LIB.BASEBOARD_FAB2(SCH_1):P3E_CPU0_PE2_SS_C_TXP'<6>:
 C_SIGNAL='@baseboard_fab2_lib.baseboard_fab2(sch_1):p3e_cpu0_pe2_ss_c_txp(6)';
NODE_NAME     C7G23 2
 '@BASEBOARD_FAB2_LIB.BASEBOARD_FAB2(SCH_1):PAGE105_I52@MSTR_DISCRETE.CAP(CHIPS)':
 'B': CDS_PINID='B';
NODE_NAME     J8G1 189
 '@BASEBOARD_FAB2_LIB.BASEBOARD_FAB2(SCH_1):PAGE109_I78@MSTR_SCONN.SCONN200_H68296001(CHIPS)':
 'IO189': CDS_PINID='IO189';
NET_NAME
'P3E_CPU0_PE2_SS_C_TXP<7>'
 '@BASEBOARD_FAB2_LIB.BASEBOARD_FAB2(SCH_1):P3E_CPU0_PE2_SS_C_TXP'<7>:
 C_SIGNAL='@baseboard_fab2_lib.baseboard_fab2(sch_1):p3e_cpu0_pe2_ss_c_txp(7)';
NODE_NAME     C7G21 2
 '@BASEBOARD_FAB2_LIB.BASEBOARD_FAB2(SCH_1):PAGE105_I51@MSTR_DISCRETE.CAP(CHIPS)':
 'B': CDS_PINID='B';
NODE_NAME     J8G1 195
 '@BASEBOARD_FAB2_LIB.BASEBOARD_FAB2(SCH_1):PAGE109_I78@MSTR_SCONN.SCONN200_H68296001(CHIPS)':
 'IO195': CDS_PINID='IO195';
NET_NAME
'P3E_CPU0_PE2_SS_C_TXP<8>'
 '@BASEBOARD_FAB2_LIB.BASEBOARD_FAB2(SCH_1):P3E_CPU0_PE2_SS_C_TXP'<8>:
 C_SIGNAL='@baseboard_fab2_lib.baseboard_fab2(sch_1):p3e_cpu0_pe2_ss_c_txp(8)';
NODE_NAME     CONX8 5
 '@BASEBOARD_FAB2_LIB.BASEBOARD_FAB2(SCH_1):PAGE245_I48@W_HDL.SMC-CONN60A-22-GP(CHIPS)':
 '5': CDS_PINID='\5\';
NODE_NAME     C7G20 2
 '@BASEBOARD_FAB2_LIB.BASEBOARD_FAB2(SCH_1):PAGE105_I258@MSTR_DISCRETE.CAP(CHIPS)':
 'B': CDS_PINID='B';
NET_NAME
'P3E_CPU0_PE2_SS_C_TXP<9>'
 '@BASEBOARD_FAB2_LIB.BASEBOARD_FAB2(SCH_1):P3E_CPU0_PE2_SS_C_TXP'<9>:
 C_SIGNAL='@baseboard_fab2_lib.baseboard_fab2(sch_1):p3e_cpu0_pe2_ss_c_txp(9)';
NODE_NAME     C7G17 2
 '@BASEBOARD_FAB2_LIB.BASEBOARD_FAB2(SCH_1):PAGE105_I44@MSTR_DISCRETE.CAP(CHIPS)':
 'B': CDS_PINID='B';
NODE_NAME     CONX8 11
 '@BASEBOARD_FAB2_LIB.BASEBOARD_FAB2(SCH_1):PAGE245_I48@W_HDL.SMC-CONN60A-22-GP(CHIPS)':
 '11': CDS_PINID='\11\';
NET_NAME
'P3E_CPU0_PE2_SS_RXN<0>'
 '@BASEBOARD_FAB2_LIB.BASEBOARD_FAB2(SCH_1):P3E_CPU0_PE2_SS_RXN'<0>:
 C_SIGNAL='@baseboard_fab2_lib.baseboard_fab2(sch_1):p3e_cpu0_pe2_ss_rxn(0)';
NODE_NAME     U5D1 CT9
 '@BASEBOARD_FAB2_LIB.BASEBOARD_FAB2(SCH_1):PAGE31_I106@CHPSET_LIB.SKX_EXT_B(CHIPS)':
 'PE2_RX_DN'<0>: CDS_PINID='PE2_RX_DN(0)';
NODE_NAME     J8G1 154
 '@BASEBOARD_FAB2_LIB.BASEBOARD_FAB2(SCH_1):PAGE109_I78@MSTR_SCONN.SCONN200_H68296001(CHIPS)':
 'IO154': CDS_PINID='IO154';
NET_NAME
'P3E_CPU0_PE2_SS_RXN<10>'
 '@BASEBOARD_FAB2_LIB.BASEBOARD_FAB2(SCH_1):P3E_CPU0_PE2_SS_RXN'<10>:
 C_SIGNAL='@baseboard_fab2_lib.baseboard_fab2(sch_1):p3e_cpu0_pe2_ss_rxn(10)';
NODE_NAME     U5D1 BV7
 '@BASEBOARD_FAB2_LIB.BASEBOARD_FAB2(SCH_1):PAGE31_I106@CHPSET_LIB.SKX_EXT_B(CHIPS)':
 'PE2_RX_DN'<10>: CDS_PINID='PE2_RX_DN(10)';
NODE_NAME     CONX8 18
 '@BASEBOARD_FAB2_LIB.BASEBOARD_FAB2(SCH_1):PAGE245_I48@W_HDL.SMC-CONN60A-22-GP(CHIPS)':
 '18': CDS_PINID='\18\';
NET_NAME
'P3E_CPU0_PE2_SS_RXN<11>'
 '@BASEBOARD_FAB2_LIB.BASEBOARD_FAB2(SCH_1):P3E_CPU0_PE2_SS_RXN'<11>:
 C_SIGNAL='@baseboard_fab2_lib.baseboard_fab2(sch_1):p3e_cpu0_pe2_ss_rxn(11)';
NODE_NAME     U5D1 BT7
 '@BASEBOARD_FAB2_LIB.BASEBOARD_FAB2(SCH_1):PAGE31_I106@CHPSET_LIB.SKX_EXT_B(CHIPS)':
 'PE2_RX_DN'<11>: CDS_PINID='PE2_RX_DN(11)';
NODE_NAME     CONX8 24
 '@BASEBOARD_FAB2_LIB.BASEBOARD_FAB2(SCH_1):PAGE245_I48@W_HDL.SMC-CONN60A-22-GP(CHIPS)':
 '24': CDS_PINID='\24\';
NET_NAME
'P3E_CPU0_PE2_SS_RXN<12>'
 '@BASEBOARD_FAB2_LIB.BASEBOARD_FAB2(SCH_1):P3E_CPU0_PE2_SS_RXN'<12>:
 C_SIGNAL='@baseboard_fab2_lib.baseboard_fab2(sch_1):p3e_cpu0_pe2_ss_rxn(12)';
NODE_NAME     U5D1 BR8
 '@BASEBOARD_FAB2_LIB.BASEBOARD_FAB2(SCH_1):PAGE31_I106@CHPSET_LIB.SKX_EXT_B(CHIPS)':
 'PE2_RX_DN'<12>: CDS_PINID='PE2_RX_DN(12)';
NODE_NAME     CONX8 30
 '@BASEBOARD_FAB2_LIB.BASEBOARD_FAB2(SCH_1):PAGE245_I48@W_HDL.SMC-CONN60A-22-GP(CHIPS)':
 '30': CDS_PINID='\30\';
NET_NAME
'P3E_CPU0_PE2_SS_RXN<13>'
 '@BASEBOARD_FAB2_LIB.BASEBOARD_FAB2(SCH_1):P3E_CPU0_PE2_SS_RXN'<13>:
 C_SIGNAL='@baseboard_fab2_lib.baseboard_fab2(sch_1):p3e_cpu0_pe2_ss_rxn(13)';
NODE_NAME     U5D1 BN8
 '@BASEBOARD_FAB2_LIB.BASEBOARD_FAB2(SCH_1):PAGE31_I106@CHPSET_LIB.SKX_EXT_B(CHIPS)':
 'PE2_RX_DN'<13>: CDS_PINID='PE2_RX_DN(13)';
NODE_NAME     CONX8 38
 '@BASEBOARD_FAB2_LIB.BASEBOARD_FAB2(SCH_1):PAGE245_I48@W_HDL.SMC-CONN60A-22-GP(CHIPS)':
 '38': CDS_PINID='\38\';
NET_NAME
'P3E_CPU0_PE2_SS_RXN<14>'
 '@BASEBOARD_FAB2_LIB.BASEBOARD_FAB2(SCH_1):P3E_CPU0_PE2_SS_RXN'<14>:
 C_SIGNAL='@baseboard_fab2_lib.baseboard_fab2(sch_1):p3e_cpu0_pe2_ss_rxn(14)';
NODE_NAME     U5D1 BL8
 '@BASEBOARD_FAB2_LIB.BASEBOARD_FAB2(SCH_1):PAGE31_I106@CHPSET_LIB.SKX_EXT_B(CHIPS)':
 'PE2_RX_DN'<14>: CDS_PINID='PE2_RX_DN(14)';
NODE_NAME     CONX8 42
 '@BASEBOARD_FAB2_LIB.BASEBOARD_FAB2(SCH_1):PAGE245_I48@W_HDL.SMC-CONN60A-22-GP(CHIPS)':
 '42': CDS_PINID='\42\';
NET_NAME
'P3E_CPU0_PE2_SS_RXN<15>'
 '@BASEBOARD_FAB2_LIB.BASEBOARD_FAB2(SCH_1):P3E_CPU0_PE2_SS_RXN'<15>:
 C_SIGNAL='@baseboard_fab2_lib.baseboard_fab2(sch_1):p3e_cpu0_pe2_ss_rxn(15)';
NODE_NAME     U5D1 BK9
 '@BASEBOARD_FAB2_LIB.BASEBOARD_FAB2(SCH_1):PAGE31_I106@CHPSET_LIB.SKX_EXT_B(CHIPS)':
 'PE2_RX_DN'<15>: CDS_PINID='PE2_RX_DN(15)';
NODE_NAME     CONX8 48
 '@BASEBOARD_FAB2_LIB.BASEBOARD_FAB2(SCH_1):PAGE245_I48@W_HDL.SMC-CONN60A-22-GP(CHIPS)':
 '48': CDS_PINID='\48\';
NET_NAME
'P3E_CPU0_PE2_SS_RXN<1>'
 '@BASEBOARD_FAB2_LIB.BASEBOARD_FAB2(SCH_1):P3E_CPU0_PE2_SS_RXN'<1>:
 C_SIGNAL='@baseboard_fab2_lib.baseboard_fab2(sch_1):p3e_cpu0_pe2_ss_rxn(1)';
NODE_NAME     U5D1 CP9
 '@BASEBOARD_FAB2_LIB.BASEBOARD_FAB2(SCH_1):PAGE31_I106@CHPSET_LIB.SKX_EXT_B(CHIPS)':
 'PE2_RX_DN'<1>: CDS_PINID='PE2_RX_DN(1)';
NODE_NAME     J8G1 160
 '@BASEBOARD_FAB2_LIB.BASEBOARD_FAB2(SCH_1):PAGE109_I78@MSTR_SCONN.SCONN200_H68296001(CHIPS)':
 'IO160': CDS_PINID='IO160';
NET_NAME
'P3E_CPU0_PE2_SS_RXN<2>'
 '@BASEBOARD_FAB2_LIB.BASEBOARD_FAB2(SCH_1):P3E_CPU0_PE2_SS_RXN'<2>:
 C_SIGNAL='@baseboard_fab2_lib.baseboard_fab2(sch_1):p3e_cpu0_pe2_ss_rxn(2)';
NODE_NAME     U5D1 CP7
 '@BASEBOARD_FAB2_LIB.BASEBOARD_FAB2(SCH_1):PAGE31_I106@CHPSET_LIB.SKX_EXT_B(CHIPS)':
 'PE2_RX_DN'<2>: CDS_PINID='PE2_RX_DN(2)';
NODE_NAME     J8G1 166
 '@BASEBOARD_FAB2_LIB.BASEBOARD_FAB2(SCH_1):PAGE109_I78@MSTR_SCONN.SCONN200_H68296001(CHIPS)':
 'IO166': CDS_PINID='IO166';
NET_NAME
'P3E_CPU0_PE2_SS_RXN<3>'
 '@BASEBOARD_FAB2_LIB.BASEBOARD_FAB2(SCH_1):P3E_CPU0_PE2_SS_RXN'<3>:
 C_SIGNAL='@baseboard_fab2_lib.baseboard_fab2(sch_1):p3e_cpu0_pe2_ss_rxn(3)';
NODE_NAME     U5D1 CM7
 '@BASEBOARD_FAB2_LIB.BASEBOARD_FAB2(SCH_1):PAGE31_I106@CHPSET_LIB.SKX_EXT_B(CHIPS)':
 'PE2_RX_DN'<3>: CDS_PINID='PE2_RX_DN(3)';
NODE_NAME     J8G1 172
 '@BASEBOARD_FAB2_LIB.BASEBOARD_FAB2(SCH_1):PAGE109_I78@MSTR_SCONN.SCONN200_H68296001(CHIPS)':
 'IO172': CDS_PINID='IO172';
NET_NAME
'P3E_CPU0_PE2_SS_RXN<4>'
 '@BASEBOARD_FAB2_LIB.BASEBOARD_FAB2(SCH_1):P3E_CPU0_PE2_SS_RXN'<4>:
 C_SIGNAL='@baseboard_fab2_lib.baseboard_fab2(sch_1):p3e_cpu0_pe2_ss_rxn(4)';
NODE_NAME     U5D1 CK7
 '@BASEBOARD_FAB2_LIB.BASEBOARD_FAB2(SCH_1):PAGE31_I106@CHPSET_LIB.SKX_EXT_B(CHIPS)':
 'PE2_RX_DN'<4>: CDS_PINID='PE2_RX_DN(4)';
NODE_NAME     J8G1 178
 '@BASEBOARD_FAB2_LIB.BASEBOARD_FAB2(SCH_1):PAGE109_I78@MSTR_SCONN.SCONN200_H68296001(CHIPS)':
 'IO178': CDS_PINID='IO178';
NET_NAME
'P3E_CPU0_PE2_SS_RXN<5>'
 '@BASEBOARD_FAB2_LIB.BASEBOARD_FAB2(SCH_1):P3E_CPU0_PE2_SS_RXN'<5>:
 C_SIGNAL='@baseboard_fab2_lib.baseboard_fab2(sch_1):p3e_cpu0_pe2_ss_rxn(5)';
NODE_NAME     U5D1 CG8
 '@BASEBOARD_FAB2_LIB.BASEBOARD_FAB2(SCH_1):PAGE31_I106@CHPSET_LIB.SKX_EXT_B(CHIPS)':
 'PE2_RX_DN'<5>: CDS_PINID='PE2_RX_DN(5)';
NODE_NAME     J8G1 184
 '@BASEBOARD_FAB2_LIB.BASEBOARD_FAB2(SCH_1):PAGE109_I78@MSTR_SCONN.SCONN200_H68296001(CHIPS)':
 'IO184': CDS_PINID='IO184';
NET_NAME
'P3E_CPU0_PE2_SS_RXN<6>'
 '@BASEBOARD_FAB2_LIB.BASEBOARD_FAB2(SCH_1):P3E_CPU0_PE2_SS_RXN'<6>:
 C_SIGNAL='@baseboard_fab2_lib.baseboard_fab2(sch_1):p3e_cpu0_pe2_ss_rxn(6)';
NODE_NAME     U5D1 CE6
 '@BASEBOARD_FAB2_LIB.BASEBOARD_FAB2(SCH_1):PAGE31_I106@CHPSET_LIB.SKX_EXT_B(CHIPS)':
 'PE2_RX_DN'<6>: CDS_PINID='PE2_RX_DN(6)';
NODE_NAME     J8G1 192
 '@BASEBOARD_FAB2_LIB.BASEBOARD_FAB2(SCH_1):PAGE109_I78@MSTR_SCONN.SCONN200_H68296001(CHIPS)':
 'IO192': CDS_PINID='IO192';
NET_NAME
'P3E_CPU0_PE2_SS_RXN<7>'
 '@BASEBOARD_FAB2_LIB.BASEBOARD_FAB2(SCH_1):P3E_CPU0_PE2_SS_RXN'<7>:
 C_SIGNAL='@baseboard_fab2_lib.baseboard_fab2(sch_1):p3e_cpu0_pe2_ss_rxn(7)';
NODE_NAME     U5D1 CE8
 '@BASEBOARD_FAB2_LIB.BASEBOARD_FAB2(SCH_1):PAGE31_I106@CHPSET_LIB.SKX_EXT_B(CHIPS)':
 'PE2_RX_DN'<7>: CDS_PINID='PE2_RX_DN(7)';
NODE_NAME     J8G1 196
 '@BASEBOARD_FAB2_LIB.BASEBOARD_FAB2(SCH_1):PAGE109_I78@MSTR_SCONN.SCONN200_H68296001(CHIPS)':
 'IO196': CDS_PINID='IO196';
NET_NAME
'P3E_CPU0_PE2_SS_RXN<8>'
 '@BASEBOARD_FAB2_LIB.BASEBOARD_FAB2(SCH_1):P3E_CPU0_PE2_SS_RXN'<8>:
 C_SIGNAL='@baseboard_fab2_lib.baseboard_fab2(sch_1):p3e_cpu0_pe2_ss_rxn(8)';
NODE_NAME     U5D1 BY9
 '@BASEBOARD_FAB2_LIB.BASEBOARD_FAB2(SCH_1):PAGE31_I106@CHPSET_LIB.SKX_EXT_B(CHIPS)':
 'PE2_RX_DN'<8>: CDS_PINID='PE2_RX_DN(8)';
NODE_NAME     CONX8 6
 '@BASEBOARD_FAB2_LIB.BASEBOARD_FAB2(SCH_1):PAGE245_I48@W_HDL.SMC-CONN60A-22-GP(CHIPS)':
 '6': CDS_PINID='\6\';
NET_NAME
'P3E_CPU0_PE2_SS_RXN<9>'
 '@BASEBOARD_FAB2_LIB.BASEBOARD_FAB2(SCH_1):P3E_CPU0_PE2_SS_RXN'<9>:
 C_SIGNAL='@baseboard_fab2_lib.baseboard_fab2(sch_1):p3e_cpu0_pe2_ss_rxn(9)';
NODE_NAME     U5D1 BY7
 '@BASEBOARD_FAB2_LIB.BASEBOARD_FAB2(SCH_1):PAGE31_I106@CHPSET_LIB.SKX_EXT_B(CHIPS)':
 'PE2_RX_DN'<9>: CDS_PINID='PE2_RX_DN(9)';
NODE_NAME     CONX8 12
 '@BASEBOARD_FAB2_LIB.BASEBOARD_FAB2(SCH_1):PAGE245_I48@W_HDL.SMC-CONN60A-22-GP(CHIPS)':
 '12': CDS_PINID='\12\';
NET_NAME
'P3E_CPU0_PE2_SS_RXP<0>'
 '@BASEBOARD_FAB2_LIB.BASEBOARD_FAB2(SCH_1):P3E_CPU0_PE2_SS_RXP'<0>:
 C_SIGNAL='@baseboard_fab2_lib.baseboard_fab2(sch_1):p3e_cpu0_pe2_ss_rxp(0)';
NODE_NAME     U5D1 CR8
 '@BASEBOARD_FAB2_LIB.BASEBOARD_FAB2(SCH_1):PAGE31_I106@CHPSET_LIB.SKX_EXT_B(CHIPS)':
 'PE2_RX_DP'<0>: CDS_PINID='PE2_RX_DP(0)';
NODE_NAME     J8G1 156
 '@BASEBOARD_FAB2_LIB.BASEBOARD_FAB2(SCH_1):PAGE109_I78@MSTR_SCONN.SCONN200_H68296001(CHIPS)':
 'IO156': CDS_PINID='IO156';
NET_NAME
'P3E_CPU0_PE2_SS_RXP<10>'
 '@BASEBOARD_FAB2_LIB.BASEBOARD_FAB2(SCH_1):P3E_CPU0_PE2_SS_RXP'<10>:
 C_SIGNAL='@baseboard_fab2_lib.baseboard_fab2(sch_1):p3e_cpu0_pe2_ss_rxp(10)';
NODE_NAME     U5D1 BU6
 '@BASEBOARD_FAB2_LIB.BASEBOARD_FAB2(SCH_1):PAGE31_I106@CHPSET_LIB.SKX_EXT_B(CHIPS)':
 'PE2_RX_DP'<10>: CDS_PINID='PE2_RX_DP(10)';
NODE_NAME     CONX8 20
 '@BASEBOARD_FAB2_LIB.BASEBOARD_FAB2(SCH_1):PAGE245_I48@W_HDL.SMC-CONN60A-22-GP(CHIPS)':
 '20': CDS_PINID='\20\';
NET_NAME
'P3E_CPU0_PE2_SS_RXP<11>'
 '@BASEBOARD_FAB2_LIB.BASEBOARD_FAB2(SCH_1):P3E_CPU0_PE2_SS_RXP'<11>:
 C_SIGNAL='@baseboard_fab2_lib.baseboard_fab2(sch_1):p3e_cpu0_pe2_ss_rxp(11)';
NODE_NAME     U5D1 BP7
 '@BASEBOARD_FAB2_LIB.BASEBOARD_FAB2(SCH_1):PAGE31_I106@CHPSET_LIB.SKX_EXT_B(CHIPS)':
 'PE2_RX_DP'<11>: CDS_PINID='PE2_RX_DP(11)';
NODE_NAME     CONX8 26
 '@BASEBOARD_FAB2_LIB.BASEBOARD_FAB2(SCH_1):PAGE245_I48@W_HDL.SMC-CONN60A-22-GP(CHIPS)':
 '26': CDS_PINID='\26\';
NET_NAME
'P3E_CPU0_PE2_SS_RXP<12>'
 '@BASEBOARD_FAB2_LIB.BASEBOARD_FAB2(SCH_1):P3E_CPU0_PE2_SS_RXP'<12>:
 C_SIGNAL='@baseboard_fab2_lib.baseboard_fab2(sch_1):p3e_cpu0_pe2_ss_rxp(12)';
NODE_NAME     U5D1 BP9
 '@BASEBOARD_FAB2_LIB.BASEBOARD_FAB2(SCH_1):PAGE31_I106@CHPSET_LIB.SKX_EXT_B(CHIPS)':
 'PE2_RX_DP'<12>: CDS_PINID='PE2_RX_DP(12)';
NODE_NAME     CONX8 32
 '@BASEBOARD_FAB2_LIB.BASEBOARD_FAB2(SCH_1):PAGE245_I48@W_HDL.SMC-CONN60A-22-GP(CHIPS)':
 '32': CDS_PINID='\32\';
NET_NAME
'P3E_CPU0_PE2_SS_RXP<13>'
 '@BASEBOARD_FAB2_LIB.BASEBOARD_FAB2(SCH_1):P3E_CPU0_PE2_SS_RXP'<13>:
 C_SIGNAL='@baseboard_fab2_lib.baseboard_fab2(sch_1):p3e_cpu0_pe2_ss_rxp(13)';
NODE_NAME     U5D1 BM7
 '@BASEBOARD_FAB2_LIB.BASEBOARD_FAB2(SCH_1):PAGE31_I106@CHPSET_LIB.SKX_EXT_B(CHIPS)':
 'PE2_RX_DP'<13>: CDS_PINID='PE2_RX_DP(13)';
NODE_NAME     CONX8 36
 '@BASEBOARD_FAB2_LIB.BASEBOARD_FAB2(SCH_1):PAGE245_I48@W_HDL.SMC-CONN60A-22-GP(CHIPS)':
 '36': CDS_PINID='\36\';
NET_NAME
'P3E_CPU0_PE2_SS_RXP<14>'
 '@BASEBOARD_FAB2_LIB.BASEBOARD_FAB2(SCH_1):P3E_CPU0_PE2_SS_RXP'<14>:
 C_SIGNAL='@baseboard_fab2_lib.baseboard_fab2(sch_1):p3e_cpu0_pe2_ss_rxp(14)';
NODE_NAME     U5D1 BJ8
 '@BASEBOARD_FAB2_LIB.BASEBOARD_FAB2(SCH_1):PAGE31_I106@CHPSET_LIB.SKX_EXT_B(CHIPS)':
 'PE2_RX_DP'<14>: CDS_PINID='PE2_RX_DP(14)';
NODE_NAME     CONX8 44
 '@BASEBOARD_FAB2_LIB.BASEBOARD_FAB2(SCH_1):PAGE245_I48@W_HDL.SMC-CONN60A-22-GP(CHIPS)':
 '44': CDS_PINID='\44\';
NET_NAME
'P3E_CPU0_PE2_SS_RXP<15>'
 '@BASEBOARD_FAB2_LIB.BASEBOARD_FAB2(SCH_1):P3E_CPU0_PE2_SS_RXP'<15>:
 C_SIGNAL='@baseboard_fab2_lib.baseboard_fab2(sch_1):p3e_cpu0_pe2_ss_rxp(15)';
NODE_NAME     U5D1 BJ10
 '@BASEBOARD_FAB2_LIB.BASEBOARD_FAB2(SCH_1):PAGE31_I106@CHPSET_LIB.SKX_EXT_B(CHIPS)':
 'PE2_RX_DP'<15>: CDS_PINID='PE2_RX_DP(15)';
NODE_NAME     CONX8 50
 '@BASEBOARD_FAB2_LIB.BASEBOARD_FAB2(SCH_1):PAGE245_I48@W_HDL.SMC-CONN60A-22-GP(CHIPS)':
 '50': CDS_PINID='\50\';
NET_NAME
'P3E_CPU0_PE2_SS_RXP<1>'
 '@BASEBOARD_FAB2_LIB.BASEBOARD_FAB2(SCH_1):P3E_CPU0_PE2_SS_RXP'<1>:
 C_SIGNAL='@baseboard_fab2_lib.baseboard_fab2(sch_1):p3e_cpu0_pe2_ss_rxp(1)';
NODE_NAME     U5D1 CM9
 '@BASEBOARD_FAB2_LIB.BASEBOARD_FAB2(SCH_1):PAGE31_I106@CHPSET_LIB.SKX_EXT_B(CHIPS)':
 'PE2_RX_DP'<1>: CDS_PINID='PE2_RX_DP(1)';
NODE_NAME     J8G1 162
 '@BASEBOARD_FAB2_LIB.BASEBOARD_FAB2(SCH_1):PAGE109_I78@MSTR_SCONN.SCONN200_H68296001(CHIPS)':
 'IO162': CDS_PINID='IO162';
NET_NAME
'P3E_CPU0_PE2_SS_RXP<2>'
 '@BASEBOARD_FAB2_LIB.BASEBOARD_FAB2(SCH_1):P3E_CPU0_PE2_SS_RXP'<2>:
 C_SIGNAL='@baseboard_fab2_lib.baseboard_fab2(sch_1):p3e_cpu0_pe2_ss_rxp(2)';
NODE_NAME     U5D1 CN8
 '@BASEBOARD_FAB2_LIB.BASEBOARD_FAB2(SCH_1):PAGE31_I106@CHPSET_LIB.SKX_EXT_B(CHIPS)':
 'PE2_RX_DP'<2>: CDS_PINID='PE2_RX_DP(2)';
NODE_NAME     J8G1 168
 '@BASEBOARD_FAB2_LIB.BASEBOARD_FAB2(SCH_1):PAGE109_I78@MSTR_SCONN.SCONN200_H68296001(CHIPS)':
 'IO168': CDS_PINID='IO168';
NET_NAME
'P3E_CPU0_PE2_SS_RXP<3>'
 '@BASEBOARD_FAB2_LIB.BASEBOARD_FAB2(SCH_1):P3E_CPU0_PE2_SS_RXP'<3>:
 C_SIGNAL='@baseboard_fab2_lib.baseboard_fab2(sch_1):p3e_cpu0_pe2_ss_rxp(3)';
NODE_NAME     U5D1 CL6
 '@BASEBOARD_FAB2_LIB.BASEBOARD_FAB2(SCH_1):PAGE31_I106@CHPSET_LIB.SKX_EXT_B(CHIPS)':
 'PE2_RX_DP'<3>: CDS_PINID='PE2_RX_DP(3)';
NODE_NAME     J8G1 174
 '@BASEBOARD_FAB2_LIB.BASEBOARD_FAB2(SCH_1):PAGE109_I78@MSTR_SCONN.SCONN200_H68296001(CHIPS)':
 'IO174': CDS_PINID='IO174';
NET_NAME
'P3E_CPU0_PE2_SS_RXP<4>'
 '@BASEBOARD_FAB2_LIB.BASEBOARD_FAB2(SCH_1):P3E_CPU0_PE2_SS_RXP'<4>:
 C_SIGNAL='@baseboard_fab2_lib.baseboard_fab2(sch_1):p3e_cpu0_pe2_ss_rxp(4)';
NODE_NAME     U5D1 CH7
 '@BASEBOARD_FAB2_LIB.BASEBOARD_FAB2(SCH_1):PAGE31_I106@CHPSET_LIB.SKX_EXT_B(CHIPS)':
 'PE2_RX_DP'<4>: CDS_PINID='PE2_RX_DP(4)';
NODE_NAME     J8G1 180
 '@BASEBOARD_FAB2_LIB.BASEBOARD_FAB2(SCH_1):PAGE109_I78@MSTR_SCONN.SCONN200_H68296001(CHIPS)':
 'IO180': CDS_PINID='IO180';
NET_NAME
'P3E_CPU0_PE2_SS_RXP<5>'
 '@BASEBOARD_FAB2_LIB.BASEBOARD_FAB2(SCH_1):P3E_CPU0_PE2_SS_RXP'<5>:
 C_SIGNAL='@baseboard_fab2_lib.baseboard_fab2(sch_1):p3e_cpu0_pe2_ss_rxp(5)';
NODE_NAME     U5D1 CF7
 '@BASEBOARD_FAB2_LIB.BASEBOARD_FAB2(SCH_1):PAGE31_I106@CHPSET_LIB.SKX_EXT_B(CHIPS)':
 'PE2_RX_DP'<5>: CDS_PINID='PE2_RX_DP(5)';
NODE_NAME     J8G1 186
 '@BASEBOARD_FAB2_LIB.BASEBOARD_FAB2(SCH_1):PAGE109_I78@MSTR_SCONN.SCONN200_H68296001(CHIPS)':
 'IO186': CDS_PINID='IO186';
NET_NAME
'P3E_CPU0_PE2_SS_RXP<6>'
 '@BASEBOARD_FAB2_LIB.BASEBOARD_FAB2(SCH_1):P3E_CPU0_PE2_SS_RXP'<6>:
 C_SIGNAL='@baseboard_fab2_lib.baseboard_fab2(sch_1):p3e_cpu0_pe2_ss_rxp(6)';
NODE_NAME     U5D1 CD7
 '@BASEBOARD_FAB2_LIB.BASEBOARD_FAB2(SCH_1):PAGE31_I106@CHPSET_LIB.SKX_EXT_B(CHIPS)':
 'PE2_RX_DP'<6>: CDS_PINID='PE2_RX_DP(6)';
NODE_NAME     J8G1 190
 '@BASEBOARD_FAB2_LIB.BASEBOARD_FAB2(SCH_1):PAGE109_I78@MSTR_SCONN.SCONN200_H68296001(CHIPS)':
 'IO190': CDS_PINID='IO190';
NET_NAME
'P3E_CPU0_PE2_SS_RXP<7>'
 '@BASEBOARD_FAB2_LIB.BASEBOARD_FAB2(SCH_1):P3E_CPU0_PE2_SS_RXP'<7>:
 C_SIGNAL='@baseboard_fab2_lib.baseboard_fab2(sch_1):p3e_cpu0_pe2_ss_rxp(7)';
NODE_NAME     U5D1 CC8
 '@BASEBOARD_FAB2_LIB.BASEBOARD_FAB2(SCH_1):PAGE31_I106@CHPSET_LIB.SKX_EXT_B(CHIPS)':
 'PE2_RX_DP'<7>: CDS_PINID='PE2_RX_DP(7)';
NODE_NAME     J8G1 198
 '@BASEBOARD_FAB2_LIB.BASEBOARD_FAB2(SCH_1):PAGE109_I78@MSTR_SCONN.SCONN200_H68296001(CHIPS)':
 'IO198': CDS_PINID='IO198';
NET_NAME
'P3E_CPU0_PE2_SS_RXP<8>'
 '@BASEBOARD_FAB2_LIB.BASEBOARD_FAB2(SCH_1):P3E_CPU0_PE2_SS_RXP'<8>:
 C_SIGNAL='@baseboard_fab2_lib.baseboard_fab2(sch_1):p3e_cpu0_pe2_ss_rxp(8)';
NODE_NAME     U5D1 BV9
 '@BASEBOARD_FAB2_LIB.BASEBOARD_FAB2(SCH_1):PAGE31_I106@CHPSET_LIB.SKX_EXT_B(CHIPS)':
 'PE2_RX_DP'<8>: CDS_PINID='PE2_RX_DP(8)';
NODE_NAME     CONX8 8
 '@BASEBOARD_FAB2_LIB.BASEBOARD_FAB2(SCH_1):PAGE245_I48@W_HDL.SMC-CONN60A-22-GP(CHIPS)':
 '8': CDS_PINID='\8\';
NET_NAME
'P3E_CPU0_PE2_SS_RXP<9>'
 '@BASEBOARD_FAB2_LIB.BASEBOARD_FAB2(SCH_1):P3E_CPU0_PE2_SS_RXP'<9>:
 C_SIGNAL='@baseboard_fab2_lib.baseboard_fab2(sch_1):p3e_cpu0_pe2_ss_rxp(9)';
NODE_NAME     U5D1 BW8
 '@BASEBOARD_FAB2_LIB.BASEBOARD_FAB2(SCH_1):PAGE31_I106@CHPSET_LIB.SKX_EXT_B(CHIPS)':
 'PE2_RX_DP'<9>: CDS_PINID='PE2_RX_DP(9)';
NODE_NAME     CONX8 14
 '@BASEBOARD_FAB2_LIB.BASEBOARD_FAB2(SCH_1):PAGE245_I48@W_HDL.SMC-CONN60A-22-GP(CHIPS)':
 '14': CDS_PINID='\14\';
NET_NAME
'P3E_CPU0_PE2_SS_TXN<0>'
 '@BASEBOARD_FAB2_LIB.BASEBOARD_FAB2(SCH_1):P3E_CPU0_PE2_SS_TXN'<0>:
 C_SIGNAL='@baseboard_fab2_lib.baseboard_fab2(sch_1):p3e_cpu0_pe2_ss_txn(0)';
NODE_NAME     U5D1 CY3
 '@BASEBOARD_FAB2_LIB.BASEBOARD_FAB2(SCH_1):PAGE31_I106@CHPSET_LIB.SKX_EXT_B(CHIPS)':
 'PE2_TX_DN'<0>: CDS_PINID='PE2_TX_DN(0)';
NODE_NAME     C8G10 1
 '@BASEBOARD_FAB2_LIB.BASEBOARD_FAB2(SCH_1):PAGE105_I96@MSTR_DISCRETE.CAP(CHIPS)':
 'A': CDS_PINID='A';
NET_NAME
'P3E_CPU0_PE2_SS_TXN<10>'
 '@BASEBOARD_FAB2_LIB.BASEBOARD_FAB2(SCH_1):P3E_CPU0_PE2_SS_TXN'<10>:
 C_SIGNAL='@baseboard_fab2_lib.baseboard_fab2(sch_1):p3e_cpu0_pe2_ss_txn(10)';
NODE_NAME     U5D1 CA4
 '@BASEBOARD_FAB2_LIB.BASEBOARD_FAB2(SCH_1):PAGE31_I106@CHPSET_LIB.SKX_EXT_B(CHIPS)':
 'PE2_TX_DN'<10>: CDS_PINID='PE2_TX_DN(10)';
NODE_NAME     C7G16 1
 '@BASEBOARD_FAB2_LIB.BASEBOARD_FAB2(SCH_1):PAGE105_I31@MSTR_DISCRETE.CAP(CHIPS)':
 'A': CDS_PINID='A';
NET_NAME
'P3E_CPU0_PE2_SS_TXN<11>'
 '@BASEBOARD_FAB2_LIB.BASEBOARD_FAB2(SCH_1):P3E_CPU0_PE2_SS_TXN'<11>:
 C_SIGNAL='@baseboard_fab2_lib.baseboard_fab2(sch_1):p3e_cpu0_pe2_ss_txn(11)';
NODE_NAME     U5D1 BW4
 '@BASEBOARD_FAB2_LIB.BASEBOARD_FAB2(SCH_1):PAGE31_I106@CHPSET_LIB.SKX_EXT_B(CHIPS)':
 'PE2_TX_DN'<11>: CDS_PINID='PE2_TX_DN(11)';
NODE_NAME     C7G13 1
 '@BASEBOARD_FAB2_LIB.BASEBOARD_FAB2(SCH_1):PAGE105_I13@MSTR_DISCRETE.CAP(CHIPS)':
 'A': CDS_PINID='A';
NET_NAME
'P3E_CPU0_PE2_SS_TXN<12>'
 '@BASEBOARD_FAB2_LIB.BASEBOARD_FAB2(SCH_1):P3E_CPU0_PE2_SS_TXN'<12>:
 C_SIGNAL='@baseboard_fab2_lib.baseboard_fab2(sch_1):p3e_cpu0_pe2_ss_txn(12)';
NODE_NAME     U5D1 BU4
 '@BASEBOARD_FAB2_LIB.BASEBOARD_FAB2(SCH_1):PAGE31_I106@CHPSET_LIB.SKX_EXT_B(CHIPS)':
 'PE2_TX_DN'<12>: CDS_PINID='PE2_TX_DN(12)';
NODE_NAME     C7G12 1
 '@BASEBOARD_FAB2_LIB.BASEBOARD_FAB2(SCH_1):PAGE105_I12@MSTR_DISCRETE.CAP(CHIPS)':
 'A': CDS_PINID='A';
NET_NAME
'P3E_CPU0_PE2_SS_TXN<13>'
 '@BASEBOARD_FAB2_LIB.BASEBOARD_FAB2(SCH_1):P3E_CPU0_PE2_SS_TXN'<13>:
 C_SIGNAL='@baseboard_fab2_lib.baseboard_fab2(sch_1):p3e_cpu0_pe2_ss_txn(13)';
NODE_NAME     U5D1 BP5
 '@BASEBOARD_FAB2_LIB.BASEBOARD_FAB2(SCH_1):PAGE31_I106@CHPSET_LIB.SKX_EXT_B(CHIPS)':
 'PE2_TX_DN'<13>: CDS_PINID='PE2_TX_DN(13)';
NODE_NAME     C7G10 1
 '@BASEBOARD_FAB2_LIB.BASEBOARD_FAB2(SCH_1):PAGE105_I8@MSTR_DISCRETE.CAP(CHIPS)':
 'A': CDS_PINID='A';
NET_NAME
'P3E_CPU0_PE2_SS_TXN<14>'
 '@BASEBOARD_FAB2_LIB.BASEBOARD_FAB2(SCH_1):P3E_CPU0_PE2_SS_TXN'<14>:
 C_SIGNAL='@baseboard_fab2_lib.baseboard_fab2(sch_1):p3e_cpu0_pe2_ss_txn(14)';
NODE_NAME     U5D1 BL4
 '@BASEBOARD_FAB2_LIB.BASEBOARD_FAB2(SCH_1):PAGE31_I106@CHPSET_LIB.SKX_EXT_B(CHIPS)':
 'PE2_TX_DN'<14>: CDS_PINID='PE2_TX_DN(14)';
NODE_NAME     C7G7 1
 '@BASEBOARD_FAB2_LIB.BASEBOARD_FAB2(SCH_1):PAGE105_I7@MSTR_DISCRETE.CAP(CHIPS)':
 'A': CDS_PINID='A';
NET_NAME
'P3E_CPU0_PE2_SS_TXN<15>'
 '@BASEBOARD_FAB2_LIB.BASEBOARD_FAB2(SCH_1):P3E_CPU0_PE2_SS_TXN'<15>:
 C_SIGNAL='@baseboard_fab2_lib.baseboard_fab2(sch_1):p3e_cpu0_pe2_ss_txn(15)';
NODE_NAME     U5D1 BM5
 '@BASEBOARD_FAB2_LIB.BASEBOARD_FAB2(SCH_1):PAGE31_I106@CHPSET_LIB.SKX_EXT_B(CHIPS)':
 'PE2_TX_DN'<15>: CDS_PINID='PE2_TX_DN(15)';
NODE_NAME     C7G6 1
 '@BASEBOARD_FAB2_LIB.BASEBOARD_FAB2(SCH_1):PAGE105_I6@MSTR_DISCRETE.CAP(CHIPS)':
 'A': CDS_PINID='A';
NET_NAME
'P3E_CPU0_PE2_SS_TXN<1>'
 '@BASEBOARD_FAB2_LIB.BASEBOARD_FAB2(SCH_1):P3E_CPU0_PE2_SS_TXN'<1>:
 C_SIGNAL='@baseboard_fab2_lib.baseboard_fab2(sch_1):p3e_cpu0_pe2_ss_txn(1)';
NODE_NAME     U5D1 CV3
 '@BASEBOARD_FAB2_LIB.BASEBOARD_FAB2(SCH_1):PAGE31_I106@CHPSET_LIB.SKX_EXT_B(CHIPS)':
 'PE2_TX_DN'<1>: CDS_PINID='PE2_TX_DN(1)';
NODE_NAME     C8G7 1
 '@BASEBOARD_FAB2_LIB.BASEBOARD_FAB2(SCH_1):PAGE105_I62@MSTR_DISCRETE.CAP(CHIPS)':
 'A': CDS_PINID='A';
NET_NAME
'P3E_CPU0_PE2_SS_TXN<2>'
 '@BASEBOARD_FAB2_LIB.BASEBOARD_FAB2(SCH_1):P3E_CPU0_PE2_SS_TXN'<2>:
 C_SIGNAL='@baseboard_fab2_lib.baseboard_fab2(sch_1):p3e_cpu0_pe2_ss_txn(2)';
NODE_NAME     U5D1 CT1
 '@BASEBOARD_FAB2_LIB.BASEBOARD_FAB2(SCH_1):PAGE31_I106@CHPSET_LIB.SKX_EXT_B(CHIPS)':
 'PE2_TX_DN'<2>: CDS_PINID='PE2_TX_DN(2)';
NODE_NAME     C8G6 1
 '@BASEBOARD_FAB2_LIB.BASEBOARD_FAB2(SCH_1):PAGE105_I61@MSTR_DISCRETE.CAP(CHIPS)':
 'A': CDS_PINID='A';
NET_NAME
'P3E_CPU0_PE2_SS_TXN<3>'
 '@BASEBOARD_FAB2_LIB.BASEBOARD_FAB2(SCH_1):P3E_CPU0_PE2_SS_TXN'<3>:
 C_SIGNAL='@baseboard_fab2_lib.baseboard_fab2(sch_1):p3e_cpu0_pe2_ss_txn(3)';
NODE_NAME     U5D1 CT3
 '@BASEBOARD_FAB2_LIB.BASEBOARD_FAB2(SCH_1):PAGE31_I106@CHPSET_LIB.SKX_EXT_B(CHIPS)':
 'PE2_TX_DN'<3>: CDS_PINID='PE2_TX_DN(3)';
NODE_NAME     C8G4 1
 '@BASEBOARD_FAB2_LIB.BASEBOARD_FAB2(SCH_1):PAGE105_I56@MSTR_DISCRETE.CAP(CHIPS)':
 'A': CDS_PINID='A';
NET_NAME
'P3E_CPU0_PE2_SS_TXN<4>'
 '@BASEBOARD_FAB2_LIB.BASEBOARD_FAB2(SCH_1):P3E_CPU0_PE2_SS_TXN'<4>:
 C_SIGNAL='@baseboard_fab2_lib.baseboard_fab2(sch_1):p3e_cpu0_pe2_ss_txn(4)';
NODE_NAME     U5D1 CM1
 '@BASEBOARD_FAB2_LIB.BASEBOARD_FAB2(SCH_1):PAGE31_I106@CHPSET_LIB.SKX_EXT_B(CHIPS)':
 'PE2_TX_DN'<4>: CDS_PINID='PE2_TX_DN(4)';
NODE_NAME     C8G2 1
 '@BASEBOARD_FAB2_LIB.BASEBOARD_FAB2(SCH_1):PAGE105_I58@MSTR_DISCRETE.CAP(CHIPS)':
 'A': CDS_PINID='A';
NET_NAME
'P3E_CPU0_PE2_SS_TXN<5>'
 '@BASEBOARD_FAB2_LIB.BASEBOARD_FAB2(SCH_1):P3E_CPU0_PE2_SS_TXN'<5>:
 C_SIGNAL='@baseboard_fab2_lib.baseboard_fab2(sch_1):p3e_cpu0_pe2_ss_txn(5)';
NODE_NAME     U5D1 CL2
 '@BASEBOARD_FAB2_LIB.BASEBOARD_FAB2(SCH_1):PAGE31_I106@CHPSET_LIB.SKX_EXT_B(CHIPS)':
 'PE2_TX_DN'<5>: CDS_PINID='PE2_TX_DN(5)';
NODE_NAME     C7G26 1
 '@BASEBOARD_FAB2_LIB.BASEBOARD_FAB2(SCH_1):PAGE105_I55@MSTR_DISCRETE.CAP(CHIPS)':
 'A': CDS_PINID='A';
NET_NAME
'P3E_CPU0_PE2_SS_TXN<6>'
 '@BASEBOARD_FAB2_LIB.BASEBOARD_FAB2(SCH_1):P3E_CPU0_PE2_SS_TXN'<6>:
 C_SIGNAL='@baseboard_fab2_lib.baseboard_fab2(sch_1):p3e_cpu0_pe2_ss_txn(6)';
NODE_NAME     U5D1 CG2
 '@BASEBOARD_FAB2_LIB.BASEBOARD_FAB2(SCH_1):PAGE31_I106@CHPSET_LIB.SKX_EXT_B(CHIPS)':
 'PE2_TX_DN'<6>: CDS_PINID='PE2_TX_DN(6)';
NODE_NAME     C7G24 1
 '@BASEBOARD_FAB2_LIB.BASEBOARD_FAB2(SCH_1):PAGE105_I1@MSTR_DISCRETE.CAP(CHIPS)':
 'A': CDS_PINID='A';
NET_NAME
'P3E_CPU0_PE2_SS_TXN<7>'
 '@BASEBOARD_FAB2_LIB.BASEBOARD_FAB2(SCH_1):P3E_CPU0_PE2_SS_TXN'<7>:
 C_SIGNAL='@baseboard_fab2_lib.baseboard_fab2(sch_1):p3e_cpu0_pe2_ss_txn(7)';
NODE_NAME     U5D1 CF3
 '@BASEBOARD_FAB2_LIB.BASEBOARD_FAB2(SCH_1):PAGE31_I106@CHPSET_LIB.SKX_EXT_B(CHIPS)':
 'PE2_TX_DN'<7>: CDS_PINID='PE2_TX_DN(7)';
NODE_NAME     C7G22 1
 '@BASEBOARD_FAB2_LIB.BASEBOARD_FAB2(SCH_1):PAGE105_I37@MSTR_DISCRETE.CAP(CHIPS)':
 'A': CDS_PINID='A';
NET_NAME
'P3E_CPU0_PE2_SS_TXN<8>'
 '@BASEBOARD_FAB2_LIB.BASEBOARD_FAB2(SCH_1):P3E_CPU0_PE2_SS_TXN'<8>:
 C_SIGNAL='@baseboard_fab2_lib.baseboard_fab2(sch_1):p3e_cpu0_pe2_ss_txn(8)';
NODE_NAME     U5D1 CC2
 '@BASEBOARD_FAB2_LIB.BASEBOARD_FAB2(SCH_1):PAGE31_I106@CHPSET_LIB.SKX_EXT_B(CHIPS)':
 'PE2_TX_DN'<8>: CDS_PINID='PE2_TX_DN(8)';
NODE_NAME     C7G19 1
 '@BASEBOARD_FAB2_LIB.BASEBOARD_FAB2(SCH_1):PAGE105_I257@MSTR_DISCRETE.CAP(CHIPS)':
 'A': CDS_PINID='A';
NET_NAME
'P3E_CPU0_PE2_SS_TXN<9>'
 '@BASEBOARD_FAB2_LIB.BASEBOARD_FAB2(SCH_1):P3E_CPU0_PE2_SS_TXN'<9>:
 C_SIGNAL='@baseboard_fab2_lib.baseboard_fab2(sch_1):p3e_cpu0_pe2_ss_txn(9)';
NODE_NAME     U5D1 CB3
 '@BASEBOARD_FAB2_LIB.BASEBOARD_FAB2(SCH_1):PAGE31_I106@CHPSET_LIB.SKX_EXT_B(CHIPS)':
 'PE2_TX_DN'<9>: CDS_PINID='PE2_TX_DN(9)';
NODE_NAME     C7G18 1
 '@BASEBOARD_FAB2_LIB.BASEBOARD_FAB2(SCH_1):PAGE105_I32@MSTR_DISCRETE.CAP(CHIPS)':
 'A': CDS_PINID='A';
NET_NAME
'P3E_CPU0_PE2_SS_TXP<0>'
 '@BASEBOARD_FAB2_LIB.BASEBOARD_FAB2(SCH_1):P3E_CPU0_PE2_SS_TXP'<0>:
 C_SIGNAL='@baseboard_fab2_lib.baseboard_fab2(sch_1):p3e_cpu0_pe2_ss_txp(0)';
NODE_NAME     U5D1 CW4
 '@BASEBOARD_FAB2_LIB.BASEBOARD_FAB2(SCH_1):PAGE31_I106@CHPSET_LIB.SKX_EXT_B(CHIPS)':
 'PE2_TX_DP'<0>: CDS_PINID='PE2_TX_DP(0)';
NODE_NAME     C8G9 1
 '@BASEBOARD_FAB2_LIB.BASEBOARD_FAB2(SCH_1):PAGE105_I93@MSTR_DISCRETE.CAP(CHIPS)':
 'A': CDS_PINID='A';
NET_NAME
'P3E_CPU0_PE2_SS_TXP<10>'
 '@BASEBOARD_FAB2_LIB.BASEBOARD_FAB2(SCH_1):P3E_CPU0_PE2_SS_TXP'<10>:
 C_SIGNAL='@baseboard_fab2_lib.baseboard_fab2(sch_1):p3e_cpu0_pe2_ss_txp(10)';
NODE_NAME     U5D1 BY5
 '@BASEBOARD_FAB2_LIB.BASEBOARD_FAB2(SCH_1):PAGE31_I106@CHPSET_LIB.SKX_EXT_B(CHIPS)':
 'PE2_TX_DP'<10>: CDS_PINID='PE2_TX_DP(10)';
NODE_NAME     C7G15 1
 '@BASEBOARD_FAB2_LIB.BASEBOARD_FAB2(SCH_1):PAGE105_I45@MSTR_DISCRETE.CAP(CHIPS)':
 'A': CDS_PINID='A';
NET_NAME
'P3E_CPU0_PE2_SS_TXP<11>'
 '@BASEBOARD_FAB2_LIB.BASEBOARD_FAB2(SCH_1):P3E_CPU0_PE2_SS_TXP'<11>:
 C_SIGNAL='@baseboard_fab2_lib.baseboard_fab2(sch_1):p3e_cpu0_pe2_ss_txp(11)';
NODE_NAME     U5D1 BV3
 '@BASEBOARD_FAB2_LIB.BASEBOARD_FAB2(SCH_1):PAGE31_I106@CHPSET_LIB.SKX_EXT_B(CHIPS)':
 'PE2_TX_DP'<11>: CDS_PINID='PE2_TX_DP(11)';
NODE_NAME     C7G14 1
 '@BASEBOARD_FAB2_LIB.BASEBOARD_FAB2(SCH_1):PAGE105_I28@MSTR_DISCRETE.CAP(CHIPS)':
 'A': CDS_PINID='A';
NET_NAME
'P3E_CPU0_PE2_SS_TXP<12>'
 '@BASEBOARD_FAB2_LIB.BASEBOARD_FAB2(SCH_1):P3E_CPU0_PE2_SS_TXP'<12>:
 C_SIGNAL='@baseboard_fab2_lib.baseboard_fab2(sch_1):p3e_cpu0_pe2_ss_txp(12)';
NODE_NAME     U5D1 BR4
 '@BASEBOARD_FAB2_LIB.BASEBOARD_FAB2(SCH_1):PAGE31_I106@CHPSET_LIB.SKX_EXT_B(CHIPS)':
 'PE2_TX_DP'<12>: CDS_PINID='PE2_TX_DP(12)';
NODE_NAME     C7G11 1
 '@BASEBOARD_FAB2_LIB.BASEBOARD_FAB2(SCH_1):PAGE105_I27@MSTR_DISCRETE.CAP(CHIPS)':
 'A': CDS_PINID='A';
NET_NAME
'P3E_CPU0_PE2_SS_TXP<13>'
 '@BASEBOARD_FAB2_LIB.BASEBOARD_FAB2(SCH_1):P3E_CPU0_PE2_SS_TXP'<13>:
 C_SIGNAL='@baseboard_fab2_lib.baseboard_fab2(sch_1):p3e_cpu0_pe2_ss_txp(13)';
NODE_NAME     U5D1 BN4
 '@BASEBOARD_FAB2_LIB.BASEBOARD_FAB2(SCH_1):PAGE31_I106@CHPSET_LIB.SKX_EXT_B(CHIPS)':
 'PE2_TX_DP'<13>: CDS_PINID='PE2_TX_DP(13)';
NODE_NAME     C7G9 1
 '@BASEBOARD_FAB2_LIB.BASEBOARD_FAB2(SCH_1):PAGE105_I21@MSTR_DISCRETE.CAP(CHIPS)':
 'A': CDS_PINID='A';
NET_NAME
'P3E_CPU0_PE2_SS_TXP<14>'
 '@BASEBOARD_FAB2_LIB.BASEBOARD_FAB2(SCH_1):P3E_CPU0_PE2_SS_TXP'<14>:
 C_SIGNAL='@baseboard_fab2_lib.baseboard_fab2(sch_1):p3e_cpu0_pe2_ss_txp(14)';
NODE_NAME     U5D1 BM3
 '@BASEBOARD_FAB2_LIB.BASEBOARD_FAB2(SCH_1):PAGE31_I106@CHPSET_LIB.SKX_EXT_B(CHIPS)':
 'PE2_TX_DP'<14>: CDS_PINID='PE2_TX_DP(14)';
NODE_NAME     C7G8 1
 '@BASEBOARD_FAB2_LIB.BASEBOARD_FAB2(SCH_1):PAGE105_I22@MSTR_DISCRETE.CAP(CHIPS)':
 'A': CDS_PINID='A';
NET_NAME
'P3E_CPU0_PE2_SS_TXP<15>'
 '@BASEBOARD_FAB2_LIB.BASEBOARD_FAB2(SCH_1):P3E_CPU0_PE2_SS_TXP'<15>:
 C_SIGNAL='@baseboard_fab2_lib.baseboard_fab2(sch_1):p3e_cpu0_pe2_ss_txp(15)';
NODE_NAME     U5D1 BK5
 '@BASEBOARD_FAB2_LIB.BASEBOARD_FAB2(SCH_1):PAGE31_I106@CHPSET_LIB.SKX_EXT_B(CHIPS)':
 'PE2_TX_DP'<15>: CDS_PINID='PE2_TX_DP(15)';
NODE_NAME     C7G5 1
 '@BASEBOARD_FAB2_LIB.BASEBOARD_FAB2(SCH_1):PAGE105_I20@MSTR_DISCRETE.CAP(CHIPS)':
 'A': CDS_PINID='A';
NET_NAME
'P3E_CPU0_PE2_SS_TXP<1>'
 '@BASEBOARD_FAB2_LIB.BASEBOARD_FAB2(SCH_1):P3E_CPU0_PE2_SS_TXP'<1>:
 C_SIGNAL='@baseboard_fab2_lib.baseboard_fab2(sch_1):p3e_cpu0_pe2_ss_txp(1)';
NODE_NAME     U5D1 CU2
 '@BASEBOARD_FAB2_LIB.BASEBOARD_FAB2(SCH_1):PAGE31_I106@CHPSET_LIB.SKX_EXT_B(CHIPS)':
 'PE2_TX_DP'<1>: CDS_PINID='PE2_TX_DP(1)';
NODE_NAME     C8G8 1
 '@BASEBOARD_FAB2_LIB.BASEBOARD_FAB2(SCH_1):PAGE105_I76@MSTR_DISCRETE.CAP(CHIPS)':
 'A': CDS_PINID='A';
NET_NAME
'P3E_CPU0_PE2_SS_TXP<2>'
 '@BASEBOARD_FAB2_LIB.BASEBOARD_FAB2(SCH_1):P3E_CPU0_PE2_SS_TXP'<2>:
 C_SIGNAL='@baseboard_fab2_lib.baseboard_fab2(sch_1):p3e_cpu0_pe2_ss_txp(2)';
NODE_NAME     U5D1 CR2
 '@BASEBOARD_FAB2_LIB.BASEBOARD_FAB2(SCH_1):PAGE31_I106@CHPSET_LIB.SKX_EXT_B(CHIPS)':
 'PE2_TX_DP'<2>: CDS_PINID='PE2_TX_DP(2)';
NODE_NAME     C8G5 1
 '@BASEBOARD_FAB2_LIB.BASEBOARD_FAB2(SCH_1):PAGE105_I75@MSTR_DISCRETE.CAP(CHIPS)':
 'A': CDS_PINID='A';
NET_NAME
'P3E_CPU0_PE2_SS_TXP<3>'
 '@BASEBOARD_FAB2_LIB.BASEBOARD_FAB2(SCH_1):P3E_CPU0_PE2_SS_TXP'<3>:
 C_SIGNAL='@baseboard_fab2_lib.baseboard_fab2(sch_1):p3e_cpu0_pe2_ss_txp(3)';
NODE_NAME     U5D1 CP3
 '@BASEBOARD_FAB2_LIB.BASEBOARD_FAB2(SCH_1):PAGE31_I106@CHPSET_LIB.SKX_EXT_B(CHIPS)':
 'PE2_TX_DP'<3>: CDS_PINID='PE2_TX_DP(3)';
NODE_NAME     C8G3 1
 '@BASEBOARD_FAB2_LIB.BASEBOARD_FAB2(SCH_1):PAGE105_I71@MSTR_DISCRETE.CAP(CHIPS)':
 'A': CDS_PINID='A';
NET_NAME
'P3E_CPU0_PE2_SS_TXP<4>'
 '@BASEBOARD_FAB2_LIB.BASEBOARD_FAB2(SCH_1):P3E_CPU0_PE2_SS_TXP'<4>:
 C_SIGNAL='@baseboard_fab2_lib.baseboard_fab2(sch_1):p3e_cpu0_pe2_ss_txp(4)';
NODE_NAME     U5D1 CK1
 '@BASEBOARD_FAB2_LIB.BASEBOARD_FAB2(SCH_1):PAGE31_I106@CHPSET_LIB.SKX_EXT_B(CHIPS)':
 'PE2_TX_DP'<4>: CDS_PINID='PE2_TX_DP(4)';
NODE_NAME     C8G1 1
 '@BASEBOARD_FAB2_LIB.BASEBOARD_FAB2(SCH_1):PAGE105_I70@MSTR_DISCRETE.CAP(CHIPS)':
 'A': CDS_PINID='A';
NET_NAME
'P3E_CPU0_PE2_SS_TXP<5>'
 '@BASEBOARD_FAB2_LIB.BASEBOARD_FAB2(SCH_1):P3E_CPU0_PE2_SS_TXP'<5>:
 C_SIGNAL='@baseboard_fab2_lib.baseboard_fab2(sch_1):p3e_cpu0_pe2_ss_txp(5)';
NODE_NAME     U5D1 CK3
 '@BASEBOARD_FAB2_LIB.BASEBOARD_FAB2(SCH_1):PAGE31_I106@CHPSET_LIB.SKX_EXT_B(CHIPS)':
 'PE2_TX_DP'<5>: CDS_PINID='PE2_TX_DP(5)';
NODE_NAME     C7G25 1
 '@BASEBOARD_FAB2_LIB.BASEBOARD_FAB2(SCH_1):PAGE105_I69@MSTR_DISCRETE.CAP(CHIPS)':
 'A': CDS_PINID='A';
NET_NAME
'P3E_CPU0_PE2_SS_TXP<6>'
 '@BASEBOARD_FAB2_LIB.BASEBOARD_FAB2(SCH_1):P3E_CPU0_PE2_SS_TXP'<6>:
 C_SIGNAL='@baseboard_fab2_lib.baseboard_fab2(sch_1):p3e_cpu0_pe2_ss_txp(6)';
NODE_NAME     U5D1 CE2
 '@BASEBOARD_FAB2_LIB.BASEBOARD_FAB2(SCH_1):PAGE31_I106@CHPSET_LIB.SKX_EXT_B(CHIPS)':
 'PE2_TX_DP'<6>: CDS_PINID='PE2_TX_DP(6)';
NODE_NAME     C7G23 1
 '@BASEBOARD_FAB2_LIB.BASEBOARD_FAB2(SCH_1):PAGE105_I52@MSTR_DISCRETE.CAP(CHIPS)':
 'A': CDS_PINID='A';
NET_NAME
'P3E_CPU0_PE2_SS_TXP<7>'
 '@BASEBOARD_FAB2_LIB.BASEBOARD_FAB2(SCH_1):P3E_CPU0_PE2_SS_TXP'<7>:
 C_SIGNAL='@baseboard_fab2_lib.baseboard_fab2(sch_1):p3e_cpu0_pe2_ss_txp(7)';
NODE_NAME     U5D1 CE4
 '@BASEBOARD_FAB2_LIB.BASEBOARD_FAB2(SCH_1):PAGE31_I106@CHPSET_LIB.SKX_EXT_B(CHIPS)':
 'PE2_TX_DP'<7>: CDS_PINID='PE2_TX_DP(7)';
NODE_NAME     C7G21 1
 '@BASEBOARD_FAB2_LIB.BASEBOARD_FAB2(SCH_1):PAGE105_I51@MSTR_DISCRETE.CAP(CHIPS)':
 'A': CDS_PINID='A';
NET_NAME
'P3E_CPU0_PE2_SS_TXP<8>'
 '@BASEBOARD_FAB2_LIB.BASEBOARD_FAB2(SCH_1):P3E_CPU0_PE2_SS_TXP'<8>:
 C_SIGNAL='@baseboard_fab2_lib.baseboard_fab2(sch_1):p3e_cpu0_pe2_ss_txp(8)';
NODE_NAME     U5D1 CD3
 '@BASEBOARD_FAB2_LIB.BASEBOARD_FAB2(SCH_1):PAGE31_I106@CHPSET_LIB.SKX_EXT_B(CHIPS)':
 'PE2_TX_DP'<8>: CDS_PINID='PE2_TX_DP(8)';
NODE_NAME     C7G20 1
 '@BASEBOARD_FAB2_LIB.BASEBOARD_FAB2(SCH_1):PAGE105_I258@MSTR_DISCRETE.CAP(CHIPS)':
 'A': CDS_PINID='A';
NET_NAME
'P3E_CPU0_PE2_SS_TXP<9>'
 '@BASEBOARD_FAB2_LIB.BASEBOARD_FAB2(SCH_1):P3E_CPU0_PE2_SS_TXP'<9>:
 C_SIGNAL='@baseboard_fab2_lib.baseboard_fab2(sch_1):p3e_cpu0_pe2_ss_txp(9)';
NODE_NAME     U5D1 BY3
 '@BASEBOARD_FAB2_LIB.BASEBOARD_FAB2(SCH_1):PAGE31_I106@CHPSET_LIB.SKX_EXT_B(CHIPS)':
 'PE2_TX_DP'<9>: CDS_PINID='PE2_TX_DP(9)';
NODE_NAME     C7G17 1
 '@BASEBOARD_FAB2_LIB.BASEBOARD_FAB2(SCH_1):PAGE105_I44@MSTR_DISCRETE.CAP(CHIPS)':
 'A': CDS_PINID='A';
NET_NAME
'P3E_CPU0_PE3_OCP_RXN<0>'
 '@BASEBOARD_FAB2_LIB.BASEBOARD_FAB2(SCH_1):P3E_CPU0_PE3_OCP_RXN'<0>:
 C_SIGNAL='@baseboard_fab2_lib.baseboard_fab2(sch_1):p3e_cpu0_pe3_ocp_rxn(0)';
NODE_NAME     U5D1 EA18
 '@BASEBOARD_FAB2_LIB.BASEBOARD_FAB2(SCH_1):PAGE32_I89@CHPSET_LIB.SKX_EXT_B(CHIPS)':
 'PE3_RX_DN'<0>: CDS_PINID='PE3_RX_DN(0)';
NODE_NAME     J8E3 63
 '@BASEBOARD_FAB2_LIB.BASEBOARD_FAB2(SCH_1):PAGE187_I119@MSTR_SCONN.SCONN80_E67482007(CHIPS)':
 'IO63': CDS_PINID='IO63';
NET_NAME
'P3E_CPU0_PE3_OCP_RXN<10>'
 '@BASEBOARD_FAB2_LIB.BASEBOARD_FAB2(SCH_1):P3E_CPU0_PE3_OCP_RXN'<10>:
 C_SIGNAL='@baseboard_fab2_lib.baseboard_fab2(sch_1):p3e_cpu0_pe3_ocp_rxn(10)';
NODE_NAME     U5D1 DG12
 '@BASEBOARD_FAB2_LIB.BASEBOARD_FAB2(SCH_1):PAGE32_I89@CHPSET_LIB.SKX_EXT_B(CHIPS)':
 'PE3_RX_DN'<10>: CDS_PINID='PE3_RX_DN(10)';
NODE_NAME     J9B3 101
 '@BASEBOARD_FAB2_LIB.BASEBOARD_FAB2(SCH_1):PAGE186_I336@MSTR_SCONN.SCONN120_A28699018(CHIPS)':
 'IO101': CDS_PINID='IO101';
NET_NAME
'P3E_CPU0_PE3_OCP_RXN<11>'
 '@BASEBOARD_FAB2_LIB.BASEBOARD_FAB2(SCH_1):P3E_CPU0_PE3_OCP_RXN'<11>:
 C_SIGNAL='@baseboard_fab2_lib.baseboard_fab2(sch_1):p3e_cpu0_pe3_ocp_rxn(11)';
NODE_NAME     U5D1 DG10
 '@BASEBOARD_FAB2_LIB.BASEBOARD_FAB2(SCH_1):PAGE32_I89@CHPSET_LIB.SKX_EXT_B(CHIPS)':
 'PE3_RX_DN'<11>: CDS_PINID='PE3_RX_DN(11)';
NODE_NAME     J9B3 93
 '@BASEBOARD_FAB2_LIB.BASEBOARD_FAB2(SCH_1):PAGE186_I336@MSTR_SCONN.SCONN120_A28699018(CHIPS)':
 'IO93': CDS_PINID='IO93';
NET_NAME
'P3E_CPU0_PE3_OCP_RXN<12>'
 '@BASEBOARD_FAB2_LIB.BASEBOARD_FAB2(SCH_1):P3E_CPU0_PE3_OCP_RXN'<12>:
 C_SIGNAL='@baseboard_fab2_lib.baseboard_fab2(sch_1):p3e_cpu0_pe3_ocp_rxn(12)';
NODE_NAME     U5D1 DD13
 '@BASEBOARD_FAB2_LIB.BASEBOARD_FAB2(SCH_1):PAGE32_I89@CHPSET_LIB.SKX_EXT_B(CHIPS)':
 'PE3_RX_DN'<12>: CDS_PINID='PE3_RX_DN(12)';
NODE_NAME     J9B3 85
 '@BASEBOARD_FAB2_LIB.BASEBOARD_FAB2(SCH_1):PAGE186_I336@MSTR_SCONN.SCONN120_A28699018(CHIPS)':
 'IO85': CDS_PINID='IO85';
NET_NAME
'P3E_CPU0_PE3_OCP_RXN<13>'
 '@BASEBOARD_FAB2_LIB.BASEBOARD_FAB2(SCH_1):P3E_CPU0_PE3_OCP_RXN'<13>:
 C_SIGNAL='@baseboard_fab2_lib.baseboard_fab2(sch_1):p3e_cpu0_pe3_ocp_rxn(13)';
NODE_NAME     U5D1 DB11
 '@BASEBOARD_FAB2_LIB.BASEBOARD_FAB2(SCH_1):PAGE32_I89@CHPSET_LIB.SKX_EXT_B(CHIPS)':
 'PE3_RX_DN'<13>: CDS_PINID='PE3_RX_DN(13)';
NODE_NAME     J9B3 77
 '@BASEBOARD_FAB2_LIB.BASEBOARD_FAB2(SCH_1):PAGE186_I336@MSTR_SCONN.SCONN120_A28699018(CHIPS)':
 'IO77': CDS_PINID='IO77';
NET_NAME
'P3E_CPU0_PE3_OCP_RXN<14>'
 '@BASEBOARD_FAB2_LIB.BASEBOARD_FAB2(SCH_1):P3E_CPU0_PE3_OCP_RXN'<14>:
 C_SIGNAL='@baseboard_fab2_lib.baseboard_fab2(sch_1):p3e_cpu0_pe3_ocp_rxn(14)';
NODE_NAME     U5D1 CY11
 '@BASEBOARD_FAB2_LIB.BASEBOARD_FAB2(SCH_1):PAGE32_I89@CHPSET_LIB.SKX_EXT_B(CHIPS)':
 'PE3_RX_DN'<14>: CDS_PINID='PE3_RX_DN(14)';
NODE_NAME     J9B3 69
 '@BASEBOARD_FAB2_LIB.BASEBOARD_FAB2(SCH_1):PAGE186_I336@MSTR_SCONN.SCONN120_A28699018(CHIPS)':
 'IO69': CDS_PINID='IO69';
NET_NAME
'P3E_CPU0_PE3_OCP_RXN<15>'
 '@BASEBOARD_FAB2_LIB.BASEBOARD_FAB2(SCH_1):P3E_CPU0_PE3_OCP_RXN'<15>:
 C_SIGNAL='@baseboard_fab2_lib.baseboard_fab2(sch_1):p3e_cpu0_pe3_ocp_rxn(15)';
NODE_NAME     U5D1 CV9
 '@BASEBOARD_FAB2_LIB.BASEBOARD_FAB2(SCH_1):PAGE32_I89@CHPSET_LIB.SKX_EXT_B(CHIPS)':
 'PE3_RX_DN'<15>: CDS_PINID='PE3_RX_DN(15)';
NODE_NAME     J9B3 61
 '@BASEBOARD_FAB2_LIB.BASEBOARD_FAB2(SCH_1):PAGE186_I336@MSTR_SCONN.SCONN120_A28699018(CHIPS)':
 'IO61': CDS_PINID='IO61';
NET_NAME
'P3E_CPU0_PE3_OCP_RXN<1>'
 '@BASEBOARD_FAB2_LIB.BASEBOARD_FAB2(SCH_1):P3E_CPU0_PE3_OCP_RXN'<1>:
 C_SIGNAL='@baseboard_fab2_lib.baseboard_fab2(sch_1):p3e_cpu0_pe3_ocp_rxn(1)';
NODE_NAME     U5D1 DW18
 '@BASEBOARD_FAB2_LIB.BASEBOARD_FAB2(SCH_1):PAGE32_I89@CHPSET_LIB.SKX_EXT_B(CHIPS)':
 'PE3_RX_DN'<1>: CDS_PINID='PE3_RX_DN(1)';
NODE_NAME     J8E3 55
 '@BASEBOARD_FAB2_LIB.BASEBOARD_FAB2(SCH_1):PAGE187_I119@MSTR_SCONN.SCONN80_E67482007(CHIPS)':
 'IO55': CDS_PINID='IO55';
NET_NAME
'P3E_CPU0_PE3_OCP_RXN<2>'
 '@BASEBOARD_FAB2_LIB.BASEBOARD_FAB2(SCH_1):P3E_CPU0_PE3_OCP_RXN'<2>:
 C_SIGNAL='@baseboard_fab2_lib.baseboard_fab2(sch_1):p3e_cpu0_pe3_ocp_rxn(2)';
NODE_NAME     U5D1 DW16
 '@BASEBOARD_FAB2_LIB.BASEBOARD_FAB2(SCH_1):PAGE32_I89@CHPSET_LIB.SKX_EXT_B(CHIPS)':
 'PE3_RX_DN'<2>: CDS_PINID='PE3_RX_DN(2)';
NODE_NAME     J8E3 47
 '@BASEBOARD_FAB2_LIB.BASEBOARD_FAB2(SCH_1):PAGE187_I119@MSTR_SCONN.SCONN80_E67482007(CHIPS)':
 'IO47': CDS_PINID='IO47';
NET_NAME
'P3E_CPU0_PE3_OCP_RXN<3>'
 '@BASEBOARD_FAB2_LIB.BASEBOARD_FAB2(SCH_1):P3E_CPU0_PE3_OCP_RXN'<3>:
 C_SIGNAL='@baseboard_fab2_lib.baseboard_fab2(sch_1):p3e_cpu0_pe3_ocp_rxn(3)';
NODE_NAME     U5D1 DT19
 '@BASEBOARD_FAB2_LIB.BASEBOARD_FAB2(SCH_1):PAGE32_I89@CHPSET_LIB.SKX_EXT_B(CHIPS)':
 'PE3_RX_DN'<3>: CDS_PINID='PE3_RX_DN(3)';
NODE_NAME     J8E3 39
 '@BASEBOARD_FAB2_LIB.BASEBOARD_FAB2(SCH_1):PAGE187_I119@MSTR_SCONN.SCONN80_E67482007(CHIPS)':
 'IO39': CDS_PINID='IO39';
NET_NAME
'P3E_CPU0_PE3_OCP_RXN<4>'
 '@BASEBOARD_FAB2_LIB.BASEBOARD_FAB2(SCH_1):P3E_CPU0_PE3_OCP_RXN'<4>:
 C_SIGNAL='@baseboard_fab2_lib.baseboard_fab2(sch_1):p3e_cpu0_pe3_ocp_rxn(4)';
NODE_NAME     U5D1 DR16
 '@BASEBOARD_FAB2_LIB.BASEBOARD_FAB2(SCH_1):PAGE32_I89@CHPSET_LIB.SKX_EXT_B(CHIPS)':
 'PE3_RX_DN'<4>: CDS_PINID='PE3_RX_DN(4)';
NODE_NAME     J8E3 29
 '@BASEBOARD_FAB2_LIB.BASEBOARD_FAB2(SCH_1):PAGE187_I119@MSTR_SCONN.SCONN80_E67482007(CHIPS)':
 'IO29': CDS_PINID='IO29';
NET_NAME
'P3E_CPU0_PE3_OCP_RXN<5>'
 '@BASEBOARD_FAB2_LIB.BASEBOARD_FAB2(SCH_1):P3E_CPU0_PE3_OCP_RXN'<5>:
 C_SIGNAL='@baseboard_fab2_lib.baseboard_fab2(sch_1):p3e_cpu0_pe3_ocp_rxn(5)';
NODE_NAME     U5D1 DR14
 '@BASEBOARD_FAB2_LIB.BASEBOARD_FAB2(SCH_1):PAGE32_I89@CHPSET_LIB.SKX_EXT_B(CHIPS)':
 'PE3_RX_DN'<5>: CDS_PINID='PE3_RX_DN(5)';
NODE_NAME     J8E3 21
 '@BASEBOARD_FAB2_LIB.BASEBOARD_FAB2(SCH_1):PAGE187_I119@MSTR_SCONN.SCONN80_E67482007(CHIPS)':
 'IO21': CDS_PINID='IO21';
NET_NAME
'P3E_CPU0_PE3_OCP_RXN<6>'
 '@BASEBOARD_FAB2_LIB.BASEBOARD_FAB2(SCH_1):P3E_CPU0_PE3_OCP_RXN'<6>:
 C_SIGNAL='@baseboard_fab2_lib.baseboard_fab2(sch_1):p3e_cpu0_pe3_ocp_rxn(6)';
NODE_NAME     U5D1 DN14
 '@BASEBOARD_FAB2_LIB.BASEBOARD_FAB2(SCH_1):PAGE32_I89@CHPSET_LIB.SKX_EXT_B(CHIPS)':
 'PE3_RX_DN'<6>: CDS_PINID='PE3_RX_DN(6)';
NODE_NAME     J8E3 13
 '@BASEBOARD_FAB2_LIB.BASEBOARD_FAB2(SCH_1):PAGE187_I119@MSTR_SCONN.SCONN80_E67482007(CHIPS)':
 'IO13': CDS_PINID='IO13';
NET_NAME
'P3E_CPU0_PE3_OCP_RXN<7>'
 '@BASEBOARD_FAB2_LIB.BASEBOARD_FAB2(SCH_1):P3E_CPU0_PE3_OCP_RXN'<7>:
 C_SIGNAL='@baseboard_fab2_lib.baseboard_fab2(sch_1):p3e_cpu0_pe3_ocp_rxn(7)';
NODE_NAME     U5D1 DL14
 '@BASEBOARD_FAB2_LIB.BASEBOARD_FAB2(SCH_1):PAGE32_I89@CHPSET_LIB.SKX_EXT_B(CHIPS)':
 'PE3_RX_DN'<7>: CDS_PINID='PE3_RX_DN(7)';
NODE_NAME     J8E3 7
 '@BASEBOARD_FAB2_LIB.BASEBOARD_FAB2(SCH_1):PAGE187_I119@MSTR_SCONN.SCONN80_E67482007(CHIPS)':
 'IO7': CDS_PINID='IO7';
NET_NAME
'P3E_CPU0_PE3_OCP_RXN<8>'
 '@BASEBOARD_FAB2_LIB.BASEBOARD_FAB2(SCH_1):P3E_CPU0_PE3_OCP_RXN'<8>:
 C_SIGNAL='@baseboard_fab2_lib.baseboard_fab2(sch_1):p3e_cpu0_pe3_ocp_rxn(8)';
NODE_NAME     U5D1 DL12
 '@BASEBOARD_FAB2_LIB.BASEBOARD_FAB2(SCH_1):PAGE32_I89@CHPSET_LIB.SKX_EXT_B(CHIPS)':
 'PE3_RX_DN'<8>: CDS_PINID='PE3_RX_DN(8)';
NODE_NAME     J9B3 117
 '@BASEBOARD_FAB2_LIB.BASEBOARD_FAB2(SCH_1):PAGE186_I336@MSTR_SCONN.SCONN120_A28699018(CHIPS)':
 'IO117': CDS_PINID='IO117';
NET_NAME
'P3E_CPU0_PE3_OCP_RXN<9>'
 '@BASEBOARD_FAB2_LIB.BASEBOARD_FAB2(SCH_1):P3E_CPU0_PE3_OCP_RXN'<9>:
 C_SIGNAL='@baseboard_fab2_lib.baseboard_fab2(sch_1):p3e_cpu0_pe3_ocp_rxn(9)';
NODE_NAME     U5D1 DJ12
 '@BASEBOARD_FAB2_LIB.BASEBOARD_FAB2(SCH_1):PAGE32_I89@CHPSET_LIB.SKX_EXT_B(CHIPS)':
 'PE3_RX_DN'<9>: CDS_PINID='PE3_RX_DN(9)';
NODE_NAME     J9B3 109
 '@BASEBOARD_FAB2_LIB.BASEBOARD_FAB2(SCH_1):PAGE186_I336@MSTR_SCONN.SCONN120_A28699018(CHIPS)':
 'IO109': CDS_PINID='IO109';
NET_NAME
'P3E_CPU0_PE3_OCP_RXP<0>'
 '@BASEBOARD_FAB2_LIB.BASEBOARD_FAB2(SCH_1):P3E_CPU0_PE3_OCP_RXP'<0>:
 C_SIGNAL='@baseboard_fab2_lib.baseboard_fab2(sch_1):p3e_cpu0_pe3_ocp_rxp(0)';
NODE_NAME     U5D1 DY17
 '@BASEBOARD_FAB2_LIB.BASEBOARD_FAB2(SCH_1):PAGE32_I89@CHPSET_LIB.SKX_EXT_B(CHIPS)':
 'PE3_RX_DP'<0>: CDS_PINID='PE3_RX_DP(0)';
NODE_NAME     J8E3 61
 '@BASEBOARD_FAB2_LIB.BASEBOARD_FAB2(SCH_1):PAGE187_I119@MSTR_SCONN.SCONN80_E67482007(CHIPS)':
 'IO61': CDS_PINID='IO61';
NET_NAME
'P3E_CPU0_PE3_OCP_RXP<10>'
 '@BASEBOARD_FAB2_LIB.BASEBOARD_FAB2(SCH_1):P3E_CPU0_PE3_OCP_RXP'<10>:
 C_SIGNAL='@baseboard_fab2_lib.baseboard_fab2(sch_1):p3e_cpu0_pe3_ocp_rxp(10)';
NODE_NAME     U5D1 DE12
 '@BASEBOARD_FAB2_LIB.BASEBOARD_FAB2(SCH_1):PAGE32_I89@CHPSET_LIB.SKX_EXT_B(CHIPS)':
 'PE3_RX_DP'<10>: CDS_PINID='PE3_RX_DP(10)';
NODE_NAME     J9B3 99
 '@BASEBOARD_FAB2_LIB.BASEBOARD_FAB2(SCH_1):PAGE186_I336@MSTR_SCONN.SCONN120_A28699018(CHIPS)':
 'IO99': CDS_PINID='IO99';
NET_NAME
'P3E_CPU0_PE3_OCP_RXP<11>'
 '@BASEBOARD_FAB2_LIB.BASEBOARD_FAB2(SCH_1):P3E_CPU0_PE3_OCP_RXP'<11>:
 C_SIGNAL='@baseboard_fab2_lib.baseboard_fab2(sch_1):p3e_cpu0_pe3_ocp_rxp(11)';
NODE_NAME     U5D1 DF11
 '@BASEBOARD_FAB2_LIB.BASEBOARD_FAB2(SCH_1):PAGE32_I89@CHPSET_LIB.SKX_EXT_B(CHIPS)':
 'PE3_RX_DP'<11>: CDS_PINID='PE3_RX_DP(11)';
NODE_NAME     J9B3 91
 '@BASEBOARD_FAB2_LIB.BASEBOARD_FAB2(SCH_1):PAGE186_I336@MSTR_SCONN.SCONN120_A28699018(CHIPS)':
 'IO91': CDS_PINID='IO91';
NET_NAME
'P3E_CPU0_PE3_OCP_RXP<12>'
 '@BASEBOARD_FAB2_LIB.BASEBOARD_FAB2(SCH_1):P3E_CPU0_PE3_OCP_RXP'<12>:
 C_SIGNAL='@baseboard_fab2_lib.baseboard_fab2(sch_1):p3e_cpu0_pe3_ocp_rxp(12)';
NODE_NAME     U5D1 DC12
 '@BASEBOARD_FAB2_LIB.BASEBOARD_FAB2(SCH_1):PAGE32_I89@CHPSET_LIB.SKX_EXT_B(CHIPS)':
 'PE3_RX_DP'<12>: CDS_PINID='PE3_RX_DP(12)';
NODE_NAME     J9B3 83
 '@BASEBOARD_FAB2_LIB.BASEBOARD_FAB2(SCH_1):PAGE186_I336@MSTR_SCONN.SCONN120_A28699018(CHIPS)':
 'IO83': CDS_PINID='IO83';
NET_NAME
'P3E_CPU0_PE3_OCP_RXP<13>'
 '@BASEBOARD_FAB2_LIB.BASEBOARD_FAB2(SCH_1):P3E_CPU0_PE3_OCP_RXP'<13>:
 C_SIGNAL='@baseboard_fab2_lib.baseboard_fab2(sch_1):p3e_cpu0_pe3_ocp_rxp(13)';
NODE_NAME     U5D1 DA12
 '@BASEBOARD_FAB2_LIB.BASEBOARD_FAB2(SCH_1):PAGE32_I89@CHPSET_LIB.SKX_EXT_B(CHIPS)':
 'PE3_RX_DP'<13>: CDS_PINID='PE3_RX_DP(13)';
NODE_NAME     J9B3 75
 '@BASEBOARD_FAB2_LIB.BASEBOARD_FAB2(SCH_1):PAGE186_I336@MSTR_SCONN.SCONN120_A28699018(CHIPS)':
 'IO75': CDS_PINID='IO75';
NET_NAME
'P3E_CPU0_PE3_OCP_RXP<14>'
 '@BASEBOARD_FAB2_LIB.BASEBOARD_FAB2(SCH_1):P3E_CPU0_PE3_OCP_RXP'<14>:
 C_SIGNAL='@baseboard_fab2_lib.baseboard_fab2(sch_1):p3e_cpu0_pe3_ocp_rxp(14)';
NODE_NAME     U5D1 CW10
 '@BASEBOARD_FAB2_LIB.BASEBOARD_FAB2(SCH_1):PAGE32_I89@CHPSET_LIB.SKX_EXT_B(CHIPS)':
 'PE3_RX_DP'<14>: CDS_PINID='PE3_RX_DP(14)';
NODE_NAME     J9B3 67
 '@BASEBOARD_FAB2_LIB.BASEBOARD_FAB2(SCH_1):PAGE186_I336@MSTR_SCONN.SCONN120_A28699018(CHIPS)':
 'IO67': CDS_PINID='IO67';
NET_NAME
'P3E_CPU0_PE3_OCP_RXP<15>'
 '@BASEBOARD_FAB2_LIB.BASEBOARD_FAB2(SCH_1):P3E_CPU0_PE3_OCP_RXP'<15>:
 C_SIGNAL='@baseboard_fab2_lib.baseboard_fab2(sch_1):p3e_cpu0_pe3_ocp_rxp(15)';
NODE_NAME     U5D1 CU10
 '@BASEBOARD_FAB2_LIB.BASEBOARD_FAB2(SCH_1):PAGE32_I89@CHPSET_LIB.SKX_EXT_B(CHIPS)':
 'PE3_RX_DP'<15>: CDS_PINID='PE3_RX_DP(15)';
NODE_NAME     J9B3 59
 '@BASEBOARD_FAB2_LIB.BASEBOARD_FAB2(SCH_1):PAGE186_I336@MSTR_SCONN.SCONN120_A28699018(CHIPS)':
 'IO59': CDS_PINID='IO59';
NET_NAME
'P3E_CPU0_PE3_OCP_RXP<1>'
 '@BASEBOARD_FAB2_LIB.BASEBOARD_FAB2(SCH_1):P3E_CPU0_PE3_OCP_RXP'<1>:
 C_SIGNAL='@baseboard_fab2_lib.baseboard_fab2(sch_1):p3e_cpu0_pe3_ocp_rxp(1)';
NODE_NAME     U5D1 DU18
 '@BASEBOARD_FAB2_LIB.BASEBOARD_FAB2(SCH_1):PAGE32_I89@CHPSET_LIB.SKX_EXT_B(CHIPS)':
 'PE3_RX_DP'<1>: CDS_PINID='PE3_RX_DP(1)';
NODE_NAME     J8E3 53
 '@BASEBOARD_FAB2_LIB.BASEBOARD_FAB2(SCH_1):PAGE187_I119@MSTR_SCONN.SCONN80_E67482007(CHIPS)':
 'IO53': CDS_PINID='IO53';
NET_NAME
'P3E_CPU0_PE3_OCP_RXP<2>'
 '@BASEBOARD_FAB2_LIB.BASEBOARD_FAB2(SCH_1):P3E_CPU0_PE3_OCP_RXP'<2>:
 C_SIGNAL='@baseboard_fab2_lib.baseboard_fab2(sch_1):p3e_cpu0_pe3_ocp_rxp(2)';
NODE_NAME     U5D1 DV17
 '@BASEBOARD_FAB2_LIB.BASEBOARD_FAB2(SCH_1):PAGE32_I89@CHPSET_LIB.SKX_EXT_B(CHIPS)':
 'PE3_RX_DP'<2>: CDS_PINID='PE3_RX_DP(2)';
NODE_NAME     J8E3 45
 '@BASEBOARD_FAB2_LIB.BASEBOARD_FAB2(SCH_1):PAGE187_I119@MSTR_SCONN.SCONN80_E67482007(CHIPS)':
 'IO45': CDS_PINID='IO45';
NET_NAME
'P3E_CPU0_PE3_OCP_RXP<3>'
 '@BASEBOARD_FAB2_LIB.BASEBOARD_FAB2(SCH_1):P3E_CPU0_PE3_OCP_RXP'<3>:
 C_SIGNAL='@baseboard_fab2_lib.baseboard_fab2(sch_1):p3e_cpu0_pe3_ocp_rxp(3)';
NODE_NAME     U5D1 DR18
 '@BASEBOARD_FAB2_LIB.BASEBOARD_FAB2(SCH_1):PAGE32_I89@CHPSET_LIB.SKX_EXT_B(CHIPS)':
 'PE3_RX_DP'<3>: CDS_PINID='PE3_RX_DP(3)';
NODE_NAME     J8E3 37
 '@BASEBOARD_FAB2_LIB.BASEBOARD_FAB2(SCH_1):PAGE187_I119@MSTR_SCONN.SCONN80_E67482007(CHIPS)':
 'IO37': CDS_PINID='IO37';
NET_NAME
'P3E_CPU0_PE3_OCP_RXP<4>'
 '@BASEBOARD_FAB2_LIB.BASEBOARD_FAB2(SCH_1):P3E_CPU0_PE3_OCP_RXP'<4>:
 C_SIGNAL='@baseboard_fab2_lib.baseboard_fab2(sch_1):p3e_cpu0_pe3_ocp_rxp(4)';
NODE_NAME     U5D1 DN16
 '@BASEBOARD_FAB2_LIB.BASEBOARD_FAB2(SCH_1):PAGE32_I89@CHPSET_LIB.SKX_EXT_B(CHIPS)':
 'PE3_RX_DP'<4>: CDS_PINID='PE3_RX_DP(4)';
NODE_NAME     J8E3 31
 '@BASEBOARD_FAB2_LIB.BASEBOARD_FAB2(SCH_1):PAGE187_I119@MSTR_SCONN.SCONN80_E67482007(CHIPS)':
 'IO31': CDS_PINID='IO31';
NET_NAME
'P3E_CPU0_PE3_OCP_RXP<5>'
 '@BASEBOARD_FAB2_LIB.BASEBOARD_FAB2(SCH_1):P3E_CPU0_PE3_OCP_RXP'<5>:
 C_SIGNAL='@baseboard_fab2_lib.baseboard_fab2(sch_1):p3e_cpu0_pe3_ocp_rxp(5)';
NODE_NAME     U5D1 DP15
 '@BASEBOARD_FAB2_LIB.BASEBOARD_FAB2(SCH_1):PAGE32_I89@CHPSET_LIB.SKX_EXT_B(CHIPS)':
 'PE3_RX_DP'<5>: CDS_PINID='PE3_RX_DP(5)';
NODE_NAME     J8E3 23
 '@BASEBOARD_FAB2_LIB.BASEBOARD_FAB2(SCH_1):PAGE187_I119@MSTR_SCONN.SCONN80_E67482007(CHIPS)':
 'IO23': CDS_PINID='IO23';
NET_NAME
'P3E_CPU0_PE3_OCP_RXP<6>'
 '@BASEBOARD_FAB2_LIB.BASEBOARD_FAB2(SCH_1):P3E_CPU0_PE3_OCP_RXP'<6>:
 C_SIGNAL='@baseboard_fab2_lib.baseboard_fab2(sch_1):p3e_cpu0_pe3_ocp_rxp(6)';
NODE_NAME     U5D1 DM13
 '@BASEBOARD_FAB2_LIB.BASEBOARD_FAB2(SCH_1):PAGE32_I89@CHPSET_LIB.SKX_EXT_B(CHIPS)':
 'PE3_RX_DP'<6>: CDS_PINID='PE3_RX_DP(6)';
NODE_NAME     J8E3 15
 '@BASEBOARD_FAB2_LIB.BASEBOARD_FAB2(SCH_1):PAGE187_I119@MSTR_SCONN.SCONN80_E67482007(CHIPS)':
 'IO15': CDS_PINID='IO15';
NET_NAME
'P3E_CPU0_PE3_OCP_RXP<7>'
 '@BASEBOARD_FAB2_LIB.BASEBOARD_FAB2(SCH_1):P3E_CPU0_PE3_OCP_RXP'<7>:
 C_SIGNAL='@baseboard_fab2_lib.baseboard_fab2(sch_1):p3e_cpu0_pe3_ocp_rxp(7)';
NODE_NAME     U5D1 DJ14
 '@BASEBOARD_FAB2_LIB.BASEBOARD_FAB2(SCH_1):PAGE32_I89@CHPSET_LIB.SKX_EXT_B(CHIPS)':
 'PE3_RX_DP'<7>: CDS_PINID='PE3_RX_DP(7)';
NODE_NAME     J8E3 5
 '@BASEBOARD_FAB2_LIB.BASEBOARD_FAB2(SCH_1):PAGE187_I119@MSTR_SCONN.SCONN80_E67482007(CHIPS)':
 'IO5': CDS_PINID='IO5';
NET_NAME
'P3E_CPU0_PE3_OCP_RXP<8>'
 '@BASEBOARD_FAB2_LIB.BASEBOARD_FAB2(SCH_1):P3E_CPU0_PE3_OCP_RXP'<8>:
 C_SIGNAL='@baseboard_fab2_lib.baseboard_fab2(sch_1):p3e_cpu0_pe3_ocp_rxp(8)';
NODE_NAME     U5D1 DK13
 '@BASEBOARD_FAB2_LIB.BASEBOARD_FAB2(SCH_1):PAGE32_I89@CHPSET_LIB.SKX_EXT_B(CHIPS)':
 'PE3_RX_DP'<8>: CDS_PINID='PE3_RX_DP(8)';
NODE_NAME     J9B3 115
 '@BASEBOARD_FAB2_LIB.BASEBOARD_FAB2(SCH_1):PAGE186_I336@MSTR_SCONN.SCONN120_A28699018(CHIPS)':
 'IO115': CDS_PINID='IO115';
NET_NAME
'P3E_CPU0_PE3_OCP_RXP<9>'
 '@BASEBOARD_FAB2_LIB.BASEBOARD_FAB2(SCH_1):P3E_CPU0_PE3_OCP_RXP'<9>:
 C_SIGNAL='@baseboard_fab2_lib.baseboard_fab2(sch_1):p3e_cpu0_pe3_ocp_rxp(9)';
NODE_NAME     U5D1 DH11
 '@BASEBOARD_FAB2_LIB.BASEBOARD_FAB2(SCH_1):PAGE32_I89@CHPSET_LIB.SKX_EXT_B(CHIPS)':
 'PE3_RX_DP'<9>: CDS_PINID='PE3_RX_DP(9)';
NODE_NAME     J9B3 107
 '@BASEBOARD_FAB2_LIB.BASEBOARD_FAB2(SCH_1):PAGE186_I336@MSTR_SCONN.SCONN120_A28699018(CHIPS)':
 'IO107': CDS_PINID='IO107';
NET_NAME
'P3E_CPU0_PE3_OCP_TXN<0>'
 '@BASEBOARD_FAB2_LIB.BASEBOARD_FAB2(SCH_1):P3E_CPU0_PE3_OCP_TXN'<0>:
 C_SIGNAL='@baseboard_fab2_lib.baseboard_fab2(sch_1):p3e_cpu0_pe3_ocp_txn(0)';
NODE_NAME     U5D1 EE14
 '@BASEBOARD_FAB2_LIB.BASEBOARD_FAB2(SCH_1):PAGE32_I89@CHPSET_LIB.SKX_EXT_B(CHIPS)':
 'PE3_TX_DN'<0>: CDS_PINID='PE3_TX_DN(0)';
NODE_NAME     C1R1 1
 '@BASEBOARD_FAB2_LIB.BASEBOARD_FAB2(SCH_1):PAGE106_I29@MSTR_DISCRETE.CAP(CHIPS)':
 'A': CDS_PINID='A';
NET_NAME
'P3E_CPU0_PE3_OCP_TXN<10>'
 '@BASEBOARD_FAB2_LIB.BASEBOARD_FAB2(SCH_1):P3E_CPU0_PE3_OCP_TXN'<10>:
 C_SIGNAL='@baseboard_fab2_lib.baseboard_fab2(sch_1):p3e_cpu0_pe3_ocp_txn(10)';
NODE_NAME     U5D1 DL6
 '@BASEBOARD_FAB2_LIB.BASEBOARD_FAB2(SCH_1):PAGE32_I89@CHPSET_LIB.SKX_EXT_B(CHIPS)':
 'PE3_TX_DN'<10>: CDS_PINID='PE3_TX_DN(10)';
NODE_NAME     C1M17 1
 '@BASEBOARD_FAB2_LIB.BASEBOARD_FAB2(SCH_1):PAGE106_I92@MSTR_DISCRETE.CAP(CHIPS)':
 'A': CDS_PINID='A';
NET_NAME
'P3E_CPU0_PE3_OCP_TXN<11>'
 '@BASEBOARD_FAB2_LIB.BASEBOARD_FAB2(SCH_1):P3E_CPU0_PE3_OCP_TXN'<11>:
 C_SIGNAL='@baseboard_fab2_lib.baseboard_fab2(sch_1):p3e_cpu0_pe3_ocp_txn(11)';
NODE_NAME     U5D1 DJ4
 '@BASEBOARD_FAB2_LIB.BASEBOARD_FAB2(SCH_1):PAGE32_I89@CHPSET_LIB.SKX_EXT_B(CHIPS)':
 'PE3_TX_DN'<11>: CDS_PINID='PE3_TX_DN(11)';
NODE_NAME     C1M15 1
 '@BASEBOARD_FAB2_LIB.BASEBOARD_FAB2(SCH_1):PAGE106_I95@MSTR_DISCRETE.CAP(CHIPS)':
 'A': CDS_PINID='A';
NET_NAME
'P3E_CPU0_PE3_OCP_TXN<12>'
 '@BASEBOARD_FAB2_LIB.BASEBOARD_FAB2(SCH_1):P3E_CPU0_PE3_OCP_TXN'<12>:
 C_SIGNAL='@baseboard_fab2_lib.baseboard_fab2(sch_1):p3e_cpu0_pe3_ocp_txn(12)';
NODE_NAME     U5D1 DJ6
 '@BASEBOARD_FAB2_LIB.BASEBOARD_FAB2(SCH_1):PAGE32_I89@CHPSET_LIB.SKX_EXT_B(CHIPS)':
 'PE3_TX_DN'<12>: CDS_PINID='PE3_TX_DN(12)';
NODE_NAME     C1M13 1
 '@BASEBOARD_FAB2_LIB.BASEBOARD_FAB2(SCH_1):PAGE106_I111@MSTR_DISCRETE.CAP(CHIPS)':
 'A': CDS_PINID='A';
NET_NAME
'P3E_CPU0_PE3_OCP_TXN<13>'
 '@BASEBOARD_FAB2_LIB.BASEBOARD_FAB2(SCH_1):P3E_CPU0_PE3_OCP_TXN'<13>:
 C_SIGNAL='@baseboard_fab2_lib.baseboard_fab2(sch_1):p3e_cpu0_pe3_ocp_txn(13)';
NODE_NAME     U5D1 DD5
 '@BASEBOARD_FAB2_LIB.BASEBOARD_FAB2(SCH_1):PAGE32_I89@CHPSET_LIB.SKX_EXT_B(CHIPS)':
 'PE3_TX_DN'<13>: CDS_PINID='PE3_TX_DN(13)';
NODE_NAME     C1M11 1
 '@BASEBOARD_FAB2_LIB.BASEBOARD_FAB2(SCH_1):PAGE106_I117@MSTR_DISCRETE.CAP(CHIPS)':
 'A': CDS_PINID='A';
NET_NAME
'P3E_CPU0_PE3_OCP_TXN<14>'
 '@BASEBOARD_FAB2_LIB.BASEBOARD_FAB2(SCH_1):P3E_CPU0_PE3_OCP_TXN'<14>:
 C_SIGNAL='@baseboard_fab2_lib.baseboard_fab2(sch_1):p3e_cpu0_pe3_ocp_txn(14)';
NODE_NAME     U5D1 DB5
 '@BASEBOARD_FAB2_LIB.BASEBOARD_FAB2(SCH_1):PAGE32_I89@CHPSET_LIB.SKX_EXT_B(CHIPS)':
 'PE3_TX_DN'<14>: CDS_PINID='PE3_TX_DN(14)';
NODE_NAME     C1M9 1
 '@BASEBOARD_FAB2_LIB.BASEBOARD_FAB2(SCH_1):PAGE106_I114@MSTR_DISCRETE.CAP(CHIPS)':
 'A': CDS_PINID='A';
NET_NAME
'P3E_CPU0_PE3_OCP_TXN<15>'
 '@BASEBOARD_FAB2_LIB.BASEBOARD_FAB2(SCH_1):P3E_CPU0_PE3_OCP_TXN'<15>:
 C_SIGNAL='@baseboard_fab2_lib.baseboard_fab2(sch_1):p3e_cpu0_pe3_ocp_txn(15)';
NODE_NAME     U5D1 CY5
 '@BASEBOARD_FAB2_LIB.BASEBOARD_FAB2(SCH_1):PAGE32_I89@CHPSET_LIB.SKX_EXT_B(CHIPS)':
 'PE3_TX_DN'<15>: CDS_PINID='PE3_TX_DN(15)';
NODE_NAME     C1M7 1
 '@BASEBOARD_FAB2_LIB.BASEBOARD_FAB2(SCH_1):PAGE106_I122@MSTR_DISCRETE.CAP(CHIPS)':
 'A': CDS_PINID='A';
NET_NAME
'P3E_CPU0_PE3_OCP_TXN<1>'
 '@BASEBOARD_FAB2_LIB.BASEBOARD_FAB2(SCH_1):P3E_CPU0_PE3_OCP_TXN'<1>:
 C_SIGNAL='@baseboard_fab2_lib.baseboard_fab2(sch_1):p3e_cpu0_pe3_ocp_txn(1)';
NODE_NAME     U5D1 EE12
 '@BASEBOARD_FAB2_LIB.BASEBOARD_FAB2(SCH_1):PAGE32_I89@CHPSET_LIB.SKX_EXT_B(CHIPS)':
 'PE3_TX_DN'<1>: CDS_PINID='PE3_TX_DN(1)';
NODE_NAME     C1R3 1
 '@BASEBOARD_FAB2_LIB.BASEBOARD_FAB2(SCH_1):PAGE106_I37@MSTR_DISCRETE.CAP(CHIPS)':
 'A': CDS_PINID='A';
NET_NAME
'P3E_CPU0_PE3_OCP_TXN<2>'
 '@BASEBOARD_FAB2_LIB.BASEBOARD_FAB2(SCH_1):P3E_CPU0_PE3_OCP_TXN'<2>:
 C_SIGNAL='@baseboard_fab2_lib.baseboard_fab2(sch_1):p3e_cpu0_pe3_ocp_txn(2)';
NODE_NAME     U5D1 EC12
 '@BASEBOARD_FAB2_LIB.BASEBOARD_FAB2(SCH_1):PAGE32_I89@CHPSET_LIB.SKX_EXT_B(CHIPS)':
 'PE3_TX_DN'<2>: CDS_PINID='PE3_TX_DN(2)';
NODE_NAME     C1R5 1
 '@BASEBOARD_FAB2_LIB.BASEBOARD_FAB2(SCH_1):PAGE106_I59@MSTR_DISCRETE.CAP(CHIPS)':
 'A': CDS_PINID='A';
NET_NAME
'P3E_CPU0_PE3_OCP_TXN<3>'
 '@BASEBOARD_FAB2_LIB.BASEBOARD_FAB2(SCH_1):P3E_CPU0_PE3_OCP_TXN'<3>:
 C_SIGNAL='@baseboard_fab2_lib.baseboard_fab2(sch_1):p3e_cpu0_pe3_ocp_txn(3)';
NODE_NAME     U5D1 DY11
 '@BASEBOARD_FAB2_LIB.BASEBOARD_FAB2(SCH_1):PAGE32_I89@CHPSET_LIB.SKX_EXT_B(CHIPS)':
 'PE3_TX_DN'<3>: CDS_PINID='PE3_TX_DN(3)';
NODE_NAME     C1R7 1
 '@BASEBOARD_FAB2_LIB.BASEBOARD_FAB2(SCH_1):PAGE106_I70@MSTR_DISCRETE.CAP(CHIPS)':
 'A': CDS_PINID='A';
NET_NAME
'P3E_CPU0_PE3_OCP_TXN<4>'
 '@BASEBOARD_FAB2_LIB.BASEBOARD_FAB2(SCH_1):P3E_CPU0_PE3_OCP_TXN'<4>:
 C_SIGNAL='@baseboard_fab2_lib.baseboard_fab2(sch_1):p3e_cpu0_pe3_ocp_txn(4)';
NODE_NAME     U5D1 EB9
 '@BASEBOARD_FAB2_LIB.BASEBOARD_FAB2(SCH_1):PAGE32_I89@CHPSET_LIB.SKX_EXT_B(CHIPS)':
 'PE3_TX_DN'<4>: CDS_PINID='PE3_TX_DN(4)';
NODE_NAME     C1R9 1
 '@BASEBOARD_FAB2_LIB.BASEBOARD_FAB2(SCH_1):PAGE106_I134@MSTR_DISCRETE.CAP(CHIPS)':
 'A': CDS_PINID='A';
NET_NAME
'P3E_CPU0_PE3_OCP_TXN<5>'
 '@BASEBOARD_FAB2_LIB.BASEBOARD_FAB2(SCH_1):P3E_CPU0_PE3_OCP_TXN'<5>:
 C_SIGNAL='@baseboard_fab2_lib.baseboard_fab2(sch_1):p3e_cpu0_pe3_ocp_txn(5)';
NODE_NAME     U5D1 DW10
 '@BASEBOARD_FAB2_LIB.BASEBOARD_FAB2(SCH_1):PAGE32_I89@CHPSET_LIB.SKX_EXT_B(CHIPS)':
 'PE3_TX_DN'<5>: CDS_PINID='PE3_TX_DN(5)';
NODE_NAME     C2R13 1
 '@BASEBOARD_FAB2_LIB.BASEBOARD_FAB2(SCH_1):PAGE106_I137@MSTR_DISCRETE.CAP(CHIPS)':
 'A': CDS_PINID='A';
NET_NAME
'P3E_CPU0_PE3_OCP_TXN<6>'
 '@BASEBOARD_FAB2_LIB.BASEBOARD_FAB2(SCH_1):P3E_CPU0_PE3_OCP_TXN'<6>:
 C_SIGNAL='@baseboard_fab2_lib.baseboard_fab2(sch_1):p3e_cpu0_pe3_ocp_txn(6)';
NODE_NAME     U5D1 DU8
 '@BASEBOARD_FAB2_LIB.BASEBOARD_FAB2(SCH_1):PAGE32_I89@CHPSET_LIB.SKX_EXT_B(CHIPS)':
 'PE3_TX_DN'<6>: CDS_PINID='PE3_TX_DN(6)';
NODE_NAME     C2R7 1
 '@BASEBOARD_FAB2_LIB.BASEBOARD_FAB2(SCH_1):PAGE106_I123@MSTR_DISCRETE.CAP(CHIPS)':
 'A': CDS_PINID='A';
NET_NAME
'P3E_CPU0_PE3_OCP_TXN<7>'
 '@BASEBOARD_FAB2_LIB.BASEBOARD_FAB2(SCH_1):P3E_CPU0_PE3_OCP_TXN'<7>:
 C_SIGNAL='@baseboard_fab2_lib.baseboard_fab2(sch_1):p3e_cpu0_pe3_ocp_txn(7)';
NODE_NAME     U5D1 DR8
 '@BASEBOARD_FAB2_LIB.BASEBOARD_FAB2(SCH_1):PAGE32_I89@CHPSET_LIB.SKX_EXT_B(CHIPS)':
 'PE3_TX_DN'<7>: CDS_PINID='PE3_TX_DN(7)';
NODE_NAME     C2R9 1
 '@BASEBOARD_FAB2_LIB.BASEBOARD_FAB2(SCH_1):PAGE106_I147@MSTR_DISCRETE.CAP(CHIPS)':
 'A': CDS_PINID='A';
NET_NAME
'P3E_CPU0_PE3_OCP_TXN<8>'
 '@BASEBOARD_FAB2_LIB.BASEBOARD_FAB2(SCH_1):P3E_CPU0_PE3_OCP_TXN'<8>:
 C_SIGNAL='@baseboard_fab2_lib.baseboard_fab2(sch_1):p3e_cpu0_pe3_ocp_txn(8)';
NODE_NAME     U5D1 DM7
 '@BASEBOARD_FAB2_LIB.BASEBOARD_FAB2(SCH_1):PAGE32_I89@CHPSET_LIB.SKX_EXT_B(CHIPS)':
 'PE3_TX_DN'<8>: CDS_PINID='PE3_TX_DN(8)';
NODE_NAME     C2M15 1
 '@BASEBOARD_FAB2_LIB.BASEBOARD_FAB2(SCH_1):PAGE106_I86@MSTR_DISCRETE.CAP(CHIPS)':
 'A': CDS_PINID='A';
NET_NAME
'P3E_CPU0_PE3_OCP_TXN<9>'
 '@BASEBOARD_FAB2_LIB.BASEBOARD_FAB2(SCH_1):P3E_CPU0_PE3_OCP_TXN'<9>:
 C_SIGNAL='@baseboard_fab2_lib.baseboard_fab2(sch_1):p3e_cpu0_pe3_ocp_txn(9)';
NODE_NAME     U5D1 DP5
 '@BASEBOARD_FAB2_LIB.BASEBOARD_FAB2(SCH_1):PAGE32_I89@CHPSET_LIB.SKX_EXT_B(CHIPS)':
 'PE3_TX_DN'<9>: CDS_PINID='PE3_TX_DN(9)';
NODE_NAME     C1M19 1
 '@BASEBOARD_FAB2_LIB.BASEBOARD_FAB2(SCH_1):PAGE106_I90@MSTR_DISCRETE.CAP(CHIPS)':
 'A': CDS_PINID='A';
NET_NAME
'P3E_CPU0_PE3_OCP_TXP<0>'
 '@BASEBOARD_FAB2_LIB.BASEBOARD_FAB2(SCH_1):P3E_CPU0_PE3_OCP_TXP'<0>:
 C_SIGNAL='@baseboard_fab2_lib.baseboard_fab2(sch_1):p3e_cpu0_pe3_ocp_txp(0)';
NODE_NAME     U5D1 EC14
 '@BASEBOARD_FAB2_LIB.BASEBOARD_FAB2(SCH_1):PAGE32_I89@CHPSET_LIB.SKX_EXT_B(CHIPS)':
 'PE3_TX_DP'<0>: CDS_PINID='PE3_TX_DP(0)';
NODE_NAME     C1R2 1
 '@BASEBOARD_FAB2_LIB.BASEBOARD_FAB2(SCH_1):PAGE106_I10@MSTR_DISCRETE.CAP(CHIPS)':
 'A': CDS_PINID='A';
NET_NAME
'P3E_CPU0_PE3_OCP_TXP<10>'
 '@BASEBOARD_FAB2_LIB.BASEBOARD_FAB2(SCH_1):P3E_CPU0_PE3_OCP_TXP'<10>:
 C_SIGNAL='@baseboard_fab2_lib.baseboard_fab2(sch_1):p3e_cpu0_pe3_ocp_txp(10)';
NODE_NAME     U5D1 DK5
 '@BASEBOARD_FAB2_LIB.BASEBOARD_FAB2(SCH_1):PAGE32_I89@CHPSET_LIB.SKX_EXT_B(CHIPS)':
 'PE3_TX_DP'<10>: CDS_PINID='PE3_TX_DP(10)';
NODE_NAME     C1M16 1
 '@BASEBOARD_FAB2_LIB.BASEBOARD_FAB2(SCH_1):PAGE106_I82@MSTR_DISCRETE.CAP(CHIPS)':
 'A': CDS_PINID='A';
NET_NAME
'P3E_CPU0_PE3_OCP_TXP<11>'
 '@BASEBOARD_FAB2_LIB.BASEBOARD_FAB2(SCH_1):P3E_CPU0_PE3_OCP_TXP'<11>:
 C_SIGNAL='@baseboard_fab2_lib.baseboard_fab2(sch_1):p3e_cpu0_pe3_ocp_txp(11)';
NODE_NAME     U5D1 DH5
 '@BASEBOARD_FAB2_LIB.BASEBOARD_FAB2(SCH_1):PAGE32_I89@CHPSET_LIB.SKX_EXT_B(CHIPS)':
 'PE3_TX_DP'<11>: CDS_PINID='PE3_TX_DP(11)';
NODE_NAME     C1M14 1
 '@BASEBOARD_FAB2_LIB.BASEBOARD_FAB2(SCH_1):PAGE106_I85@MSTR_DISCRETE.CAP(CHIPS)':
 'A': CDS_PINID='A';
NET_NAME
'P3E_CPU0_PE3_OCP_TXP<12>'
 '@BASEBOARD_FAB2_LIB.BASEBOARD_FAB2(SCH_1):P3E_CPU0_PE3_OCP_TXP'<12>:
 C_SIGNAL='@baseboard_fab2_lib.baseboard_fab2(sch_1):p3e_cpu0_pe3_ocp_txp(12)';
NODE_NAME     U5D1 DG6
 '@BASEBOARD_FAB2_LIB.BASEBOARD_FAB2(SCH_1):PAGE32_I89@CHPSET_LIB.SKX_EXT_B(CHIPS)':
 'PE3_TX_DP'<12>: CDS_PINID='PE3_TX_DP(12)';
NODE_NAME     C1M12 1
 '@BASEBOARD_FAB2_LIB.BASEBOARD_FAB2(SCH_1):PAGE106_I100@MSTR_DISCRETE.CAP(CHIPS)':
 'A': CDS_PINID='A';
NET_NAME
'P3E_CPU0_PE3_OCP_TXP<13>'
 '@BASEBOARD_FAB2_LIB.BASEBOARD_FAB2(SCH_1):P3E_CPU0_PE3_OCP_TXP'<13>:
 C_SIGNAL='@baseboard_fab2_lib.baseboard_fab2(sch_1):p3e_cpu0_pe3_ocp_txp(13)';
NODE_NAME     U5D1 DC6
 '@BASEBOARD_FAB2_LIB.BASEBOARD_FAB2(SCH_1):PAGE32_I89@CHPSET_LIB.SKX_EXT_B(CHIPS)':
 'PE3_TX_DP'<13>: CDS_PINID='PE3_TX_DP(13)';
NODE_NAME     C1M10 1
 '@BASEBOARD_FAB2_LIB.BASEBOARD_FAB2(SCH_1):PAGE106_I102@MSTR_DISCRETE.CAP(CHIPS)':
 'A': CDS_PINID='A';
NET_NAME
'P3E_CPU0_PE3_OCP_TXP<14>'
 '@BASEBOARD_FAB2_LIB.BASEBOARD_FAB2(SCH_1):P3E_CPU0_PE3_OCP_TXP'<14>:
 C_SIGNAL='@baseboard_fab2_lib.baseboard_fab2(sch_1):p3e_cpu0_pe3_ocp_txp(14)';
NODE_NAME     U5D1 DA4
 '@BASEBOARD_FAB2_LIB.BASEBOARD_FAB2(SCH_1):PAGE32_I89@CHPSET_LIB.SKX_EXT_B(CHIPS)':
 'PE3_TX_DP'<14>: CDS_PINID='PE3_TX_DP(14)';
NODE_NAME     C1M8 1
 '@BASEBOARD_FAB2_LIB.BASEBOARD_FAB2(SCH_1):PAGE106_I105@MSTR_DISCRETE.CAP(CHIPS)':
 'A': CDS_PINID='A';
NET_NAME
'P3E_CPU0_PE3_OCP_TXP<15>'
 '@BASEBOARD_FAB2_LIB.BASEBOARD_FAB2(SCH_1):P3E_CPU0_PE3_OCP_TXP'<15>:
 C_SIGNAL='@baseboard_fab2_lib.baseboard_fab2(sch_1):p3e_cpu0_pe3_ocp_txp(15)';
NODE_NAME     U5D1 CV5
 '@BASEBOARD_FAB2_LIB.BASEBOARD_FAB2(SCH_1):PAGE32_I89@CHPSET_LIB.SKX_EXT_B(CHIPS)':
 'PE3_TX_DP'<15>: CDS_PINID='PE3_TX_DP(15)';
NODE_NAME     C1M6 1
 '@BASEBOARD_FAB2_LIB.BASEBOARD_FAB2(SCH_1):PAGE106_I109@MSTR_DISCRETE.CAP(CHIPS)':
 'A': CDS_PINID='A';
NET_NAME
'P3E_CPU0_PE3_OCP_TXP<1>'
 '@BASEBOARD_FAB2_LIB.BASEBOARD_FAB2(SCH_1):P3E_CPU0_PE3_OCP_TXP'<1>:
 C_SIGNAL='@baseboard_fab2_lib.baseboard_fab2(sch_1):p3e_cpu0_pe3_ocp_txp(1)';
NODE_NAME     U5D1 ED13
 '@BASEBOARD_FAB2_LIB.BASEBOARD_FAB2(SCH_1):PAGE32_I89@CHPSET_LIB.SKX_EXT_B(CHIPS)':
 'PE3_TX_DP'<1>: CDS_PINID='PE3_TX_DP(1)';
NODE_NAME     C1R4 1
 '@BASEBOARD_FAB2_LIB.BASEBOARD_FAB2(SCH_1):PAGE106_I26@MSTR_DISCRETE.CAP(CHIPS)':
 'A': CDS_PINID='A';
NET_NAME
'P3E_CPU0_PE3_OCP_TXP<2>'
 '@BASEBOARD_FAB2_LIB.BASEBOARD_FAB2(SCH_1):P3E_CPU0_PE3_OCP_TXP'<2>:
 C_SIGNAL='@baseboard_fab2_lib.baseboard_fab2(sch_1):p3e_cpu0_pe3_ocp_txp(2)';
NODE_NAME     U5D1 EB11
 '@BASEBOARD_FAB2_LIB.BASEBOARD_FAB2(SCH_1):PAGE32_I89@CHPSET_LIB.SKX_EXT_B(CHIPS)':
 'PE3_TX_DP'<2>: CDS_PINID='PE3_TX_DP(2)';
NODE_NAME     C1R6 1
 '@BASEBOARD_FAB2_LIB.BASEBOARD_FAB2(SCH_1):PAGE106_I40@MSTR_DISCRETE.CAP(CHIPS)':
 'A': CDS_PINID='A';
NET_NAME
'P3E_CPU0_PE3_OCP_TXP<3>'
 '@BASEBOARD_FAB2_LIB.BASEBOARD_FAB2(SCH_1):P3E_CPU0_PE3_OCP_TXP'<3>:
 C_SIGNAL='@baseboard_fab2_lib.baseboard_fab2(sch_1):p3e_cpu0_pe3_ocp_txp(3)';
NODE_NAME     U5D1 EA10
 '@BASEBOARD_FAB2_LIB.BASEBOARD_FAB2(SCH_1):PAGE32_I89@CHPSET_LIB.SKX_EXT_B(CHIPS)':
 'PE3_TX_DP'<3>: CDS_PINID='PE3_TX_DP(3)';
NODE_NAME     C1R8 1
 '@BASEBOARD_FAB2_LIB.BASEBOARD_FAB2(SCH_1):PAGE106_I55@MSTR_DISCRETE.CAP(CHIPS)':
 'A': CDS_PINID='A';
NET_NAME
'P3E_CPU0_PE3_OCP_TXP<4>'
 '@BASEBOARD_FAB2_LIB.BASEBOARD_FAB2(SCH_1):P3E_CPU0_PE3_OCP_TXP'<4>:
 C_SIGNAL='@baseboard_fab2_lib.baseboard_fab2(sch_1):p3e_cpu0_pe3_ocp_txp(4)';
NODE_NAME     U5D1 DY9
 '@BASEBOARD_FAB2_LIB.BASEBOARD_FAB2(SCH_1):PAGE32_I89@CHPSET_LIB.SKX_EXT_B(CHIPS)':
 'PE3_TX_DP'<4>: CDS_PINID='PE3_TX_DP(4)';
NODE_NAME     C1R10 1
 '@BASEBOARD_FAB2_LIB.BASEBOARD_FAB2(SCH_1):PAGE106_I128@MSTR_DISCRETE.CAP(CHIPS)':
 'A': CDS_PINID='A';
NET_NAME
'P3E_CPU0_PE3_OCP_TXP<5>'
 '@BASEBOARD_FAB2_LIB.BASEBOARD_FAB2(SCH_1):P3E_CPU0_PE3_OCP_TXP'<5>:
 C_SIGNAL='@baseboard_fab2_lib.baseboard_fab2(sch_1):p3e_cpu0_pe3_ocp_txp(5)';
NODE_NAME     U5D1 DV9
 '@BASEBOARD_FAB2_LIB.BASEBOARD_FAB2(SCH_1):PAGE32_I89@CHPSET_LIB.SKX_EXT_B(CHIPS)':
 'PE3_TX_DP'<5>: CDS_PINID='PE3_TX_DP(5)';
NODE_NAME     C2R14 1
 '@BASEBOARD_FAB2_LIB.BASEBOARD_FAB2(SCH_1):PAGE106_I130@MSTR_DISCRETE.CAP(CHIPS)':
 'A': CDS_PINID='A';
NET_NAME
'P3E_CPU0_PE3_OCP_TXP<6>'
 '@BASEBOARD_FAB2_LIB.BASEBOARD_FAB2(SCH_1):P3E_CPU0_PE3_OCP_TXP'<6>:
 C_SIGNAL='@baseboard_fab2_lib.baseboard_fab2(sch_1):p3e_cpu0_pe3_ocp_txp(6)';
NODE_NAME     U5D1 DT9
 '@BASEBOARD_FAB2_LIB.BASEBOARD_FAB2(SCH_1):PAGE32_I89@CHPSET_LIB.SKX_EXT_B(CHIPS)':
 'PE3_TX_DP'<6>: CDS_PINID='PE3_TX_DP(6)';
NODE_NAME     C2R8 1
 '@BASEBOARD_FAB2_LIB.BASEBOARD_FAB2(SCH_1):PAGE106_I141@MSTR_DISCRETE.CAP(CHIPS)':
 'A': CDS_PINID='A';
NET_NAME
'P3E_CPU0_PE3_OCP_TXP<7>'
 '@BASEBOARD_FAB2_LIB.BASEBOARD_FAB2(SCH_1):P3E_CPU0_PE3_OCP_TXP'<7>:
 C_SIGNAL='@baseboard_fab2_lib.baseboard_fab2(sch_1):p3e_cpu0_pe3_ocp_txp(7)';
NODE_NAME     U5D1 DP7
 '@BASEBOARD_FAB2_LIB.BASEBOARD_FAB2(SCH_1):PAGE32_I89@CHPSET_LIB.SKX_EXT_B(CHIPS)':
 'PE3_TX_DP'<7>: CDS_PINID='PE3_TX_DP(7)';
NODE_NAME     C2R10 1
 '@BASEBOARD_FAB2_LIB.BASEBOARD_FAB2(SCH_1):PAGE106_I142@MSTR_DISCRETE.CAP(CHIPS)':
 'A': CDS_PINID='A';
NET_NAME
'P3E_CPU0_PE3_OCP_TXP<8>'
 '@BASEBOARD_FAB2_LIB.BASEBOARD_FAB2(SCH_1):P3E_CPU0_PE3_OCP_TXP'<8>:
 C_SIGNAL='@baseboard_fab2_lib.baseboard_fab2(sch_1):p3e_cpu0_pe3_ocp_txp(8)';
NODE_NAME     U5D1 DN6
 '@BASEBOARD_FAB2_LIB.BASEBOARD_FAB2(SCH_1):PAGE32_I89@CHPSET_LIB.SKX_EXT_B(CHIPS)':
 'PE3_TX_DP'<8>: CDS_PINID='PE3_TX_DP(8)';
NODE_NAME     C2M14 1
 '@BASEBOARD_FAB2_LIB.BASEBOARD_FAB2(SCH_1):PAGE106_I76@MSTR_DISCRETE.CAP(CHIPS)':
 'A': CDS_PINID='A';
NET_NAME
'P3E_CPU0_PE3_OCP_TXP<9>'
 '@BASEBOARD_FAB2_LIB.BASEBOARD_FAB2(SCH_1):P3E_CPU0_PE3_OCP_TXP'<9>:
 C_SIGNAL='@baseboard_fab2_lib.baseboard_fab2(sch_1):p3e_cpu0_pe3_ocp_txp(9)';
NODE_NAME     U5D1 DM5
 '@BASEBOARD_FAB2_LIB.BASEBOARD_FAB2(SCH_1):PAGE32_I89@CHPSET_LIB.SKX_EXT_B(CHIPS)':
 'PE3_TX_DP'<9>: CDS_PINID='PE3_TX_DP(9)';
NODE_NAME     C1M18 1
 '@BASEBOARD_FAB2_LIB.BASEBOARD_FAB2(SCH_1):PAGE106_I78@MSTR_DISCRETE.CAP(CHIPS)':
 'A': CDS_PINID='A';
NET_NAME
'P3E_CPU1_PE3_MP_C_TXN<0>'
 '@BASEBOARD_FAB2_LIB.BASEBOARD_FAB2(SCH_1):P3E_CPU1_PE3_MP_C_TXN'<0>:
 C_SIGNAL='@baseboard_fab2_lib.baseboard_fab2(sch_1):p3e_cpu1_pe3_mp_c_txn(0)';
NODE_NAME     C1F20 1
 '@BASEBOARD_FAB2_LIB.BASEBOARD_FAB2(SCH_1):PAGE181_I86@MSTR_DISCRETE.CAP(CHIPS)':
 'A': CDS_PINID='A';
NODE_NAME     J1F1 B8
 '@BASEBOARD_FAB2_LIB.BASEBOARD_FAB2(SCH_1):PAGE181_I134@W_HDL.DM-FCI-CONN76-8R-GP-U-01(CHIPS)':
 'PCIE_TX_DP0': CDS_PINID='PCIE_TX_DP0';
NET_NAME
'P3E_CPU1_PE3_MP_C_TXN<10>'
 '@BASEBOARD_FAB2_LIB.BASEBOARD_FAB2(SCH_1):P3E_CPU1_PE3_MP_C_TXN'<10>:
 C_SIGNAL='@baseboard_fab2_lib.baseboard_fab2(sch_1):p3e_cpu1_pe3_mp_c_txn(10)';
NODE_NAME     C9N2 1
 '@BASEBOARD_FAB2_LIB.BASEBOARD_FAB2(SCH_1):PAGE182_I36@MSTR_DISCRETE.CAP(CHIPS)':
 'A': CDS_PINID='A';
NODE_NAME     J1C1 I8
 '@BASEBOARD_FAB2_LIB.BASEBOARD_FAB2(SCH_1):PAGE182_I79@W_HDL.DM-FCI-CONN76-8R-GP-U-01(CHIPS)':
 'PCIE_TX_DN2': CDS_PINID='PCIE_TX_DN2';
NET_NAME
'P3E_CPU1_PE3_MP_C_TXN<11>'
 '@BASEBOARD_FAB2_LIB.BASEBOARD_FAB2(SCH_1):P3E_CPU1_PE3_MP_C_TXN'<11>:
 C_SIGNAL='@baseboard_fab2_lib.baseboard_fab2(sch_1):p3e_cpu1_pe3_mp_c_txn(11)';
NODE_NAME     C9N3 1
 '@BASEBOARD_FAB2_LIB.BASEBOARD_FAB2(SCH_1):PAGE182_I47@MSTR_DISCRETE.CAP(CHIPS)':
 'A': CDS_PINID='A';
NODE_NAME     J1C1 A7
 '@BASEBOARD_FAB2_LIB.BASEBOARD_FAB2(SCH_1):PAGE182_I79@W_HDL.DM-FCI-CONN76-8R-GP-U-01(CHIPS)':
 'PCIE_TX_DP3': CDS_PINID='PCIE_TX_DP3';
NET_NAME
'P3E_CPU1_PE3_MP_C_TXN<12>'
 '@BASEBOARD_FAB2_LIB.BASEBOARD_FAB2(SCH_1):P3E_CPU1_PE3_MP_C_TXN'<12>:
 C_SIGNAL='@baseboard_fab2_lib.baseboard_fab2(sch_1):p3e_cpu1_pe3_mp_c_txn(12)';
NODE_NAME     C9N16 1
 '@BASEBOARD_FAB2_LIB.BASEBOARD_FAB2(SCH_1):PAGE182_I46@MSTR_DISCRETE.CAP(CHIPS)':
 'A': CDS_PINID='A';
NODE_NAME     J1C1 D7
 '@BASEBOARD_FAB2_LIB.BASEBOARD_FAB2(SCH_1):PAGE182_I79@W_HDL.DM-FCI-CONN76-8R-GP-U-01(CHIPS)':
 'PCIE_TX_DP4': CDS_PINID='PCIE_TX_DP4';
NET_NAME
'P3E_CPU1_PE3_MP_C_TXN<13>'
 '@BASEBOARD_FAB2_LIB.BASEBOARD_FAB2(SCH_1):P3E_CPU1_PE3_MP_C_TXN'<13>:
 C_SIGNAL='@baseboard_fab2_lib.baseboard_fab2(sch_1):p3e_cpu1_pe3_mp_c_txn(13)';
NODE_NAME     C9N6 1
 '@BASEBOARD_FAB2_LIB.BASEBOARD_FAB2(SCH_1):PAGE182_I42@MSTR_DISCRETE.CAP(CHIPS)':
 'A': CDS_PINID='A';
NODE_NAME     J1C1 G7
 '@BASEBOARD_FAB2_LIB.BASEBOARD_FAB2(SCH_1):PAGE182_I79@W_HDL.DM-FCI-CONN76-8R-GP-U-01(CHIPS)':
 'PCIE_TX_DP5': CDS_PINID='PCIE_TX_DP5';
NET_NAME
'P3E_CPU1_PE3_MP_C_TXN<14>'
 '@BASEBOARD_FAB2_LIB.BASEBOARD_FAB2(SCH_1):P3E_CPU1_PE3_MP_C_TXN'<14>:
 C_SIGNAL='@baseboard_fab2_lib.baseboard_fab2(sch_1):p3e_cpu1_pe3_mp_c_txn(14)';
NODE_NAME     C9N8 1
 '@BASEBOARD_FAB2_LIB.BASEBOARD_FAB2(SCH_1):PAGE182_I53@MSTR_DISCRETE.CAP(CHIPS)':
 'A': CDS_PINID='A';
NODE_NAME     J1C1 E6
 '@BASEBOARD_FAB2_LIB.BASEBOARD_FAB2(SCH_1):PAGE182_I79@W_HDL.DM-FCI-CONN76-8R-GP-U-01(CHIPS)':
 'PCIE_TX_DP6': CDS_PINID='PCIE_TX_DP6';
NET_NAME
'P3E_CPU1_PE3_MP_C_TXN<15>'
 '@BASEBOARD_FAB2_LIB.BASEBOARD_FAB2(SCH_1):P3E_CPU1_PE3_MP_C_TXN'<15>:
 C_SIGNAL='@baseboard_fab2_lib.baseboard_fab2(sch_1):p3e_cpu1_pe3_mp_c_txn(15)';
NODE_NAME     C9N9 1
 '@BASEBOARD_FAB2_LIB.BASEBOARD_FAB2(SCH_1):PAGE182_I52@MSTR_DISCRETE.CAP(CHIPS)':
 'A': CDS_PINID='A';
NODE_NAME     J1C1 H6
 '@BASEBOARD_FAB2_LIB.BASEBOARD_FAB2(SCH_1):PAGE182_I79@W_HDL.DM-FCI-CONN76-8R-GP-U-01(CHIPS)':
 'PCIE_TX_DP7': CDS_PINID='PCIE_TX_DP7';
NET_NAME
'P3E_CPU1_PE3_MP_C_TXN<1>'
 '@BASEBOARD_FAB2_LIB.BASEBOARD_FAB2(SCH_1):P3E_CPU1_PE3_MP_C_TXN'<1>:
 C_SIGNAL='@baseboard_fab2_lib.baseboard_fab2(sch_1):p3e_cpu1_pe3_mp_c_txn(1)';
NODE_NAME     C1F16 1
 '@BASEBOARD_FAB2_LIB.BASEBOARD_FAB2(SCH_1):PAGE181_I79@MSTR_DISCRETE.CAP(CHIPS)':
 'A': CDS_PINID='A';
NODE_NAME     J1F1 E8
 '@BASEBOARD_FAB2_LIB.BASEBOARD_FAB2(SCH_1):PAGE181_I134@W_HDL.DM-FCI-CONN76-8R-GP-U-01(CHIPS)':
 'PCIE_TX_DP1': CDS_PINID='PCIE_TX_DP1';
NET_NAME
'P3E_CPU1_PE3_MP_C_TXN<2>'
 '@BASEBOARD_FAB2_LIB.BASEBOARD_FAB2(SCH_1):P3E_CPU1_PE3_MP_C_TXN'<2>:
 C_SIGNAL='@baseboard_fab2_lib.baseboard_fab2(sch_1):p3e_cpu1_pe3_mp_c_txn(2)';
NODE_NAME     C1F15 1
 '@BASEBOARD_FAB2_LIB.BASEBOARD_FAB2(SCH_1):PAGE181_I78@MSTR_DISCRETE.CAP(CHIPS)':
 'A': CDS_PINID='A';
NODE_NAME     J1F1 H8
 '@BASEBOARD_FAB2_LIB.BASEBOARD_FAB2(SCH_1):PAGE181_I134@W_HDL.DM-FCI-CONN76-8R-GP-U-01(CHIPS)':
 'PCIE_TX_DP2': CDS_PINID='PCIE_TX_DP2';
NET_NAME
'P3E_CPU1_PE3_MP_C_TXN<3>'
 '@BASEBOARD_FAB2_LIB.BASEBOARD_FAB2(SCH_1):P3E_CPU1_PE3_MP_C_TXN'<3>:
 C_SIGNAL='@baseboard_fab2_lib.baseboard_fab2(sch_1):p3e_cpu1_pe3_mp_c_txn(3)';
NODE_NAME     C1F13 1
 '@BASEBOARD_FAB2_LIB.BASEBOARD_FAB2(SCH_1):PAGE181_I89@MSTR_DISCRETE.CAP(CHIPS)':
 'A': CDS_PINID='A';
NODE_NAME     J1F1 A7
 '@BASEBOARD_FAB2_LIB.BASEBOARD_FAB2(SCH_1):PAGE181_I134@W_HDL.DM-FCI-CONN76-8R-GP-U-01(CHIPS)':
 'PCIE_TX_DP3': CDS_PINID='PCIE_TX_DP3';
NET_NAME
'P3E_CPU1_PE3_MP_C_TXN<4>'
 '@BASEBOARD_FAB2_LIB.BASEBOARD_FAB2(SCH_1):P3E_CPU1_PE3_MP_C_TXN'<4>:
 C_SIGNAL='@baseboard_fab2_lib.baseboard_fab2(sch_1):p3e_cpu1_pe3_mp_c_txn(4)';
NODE_NAME     C1F10 1
 '@BASEBOARD_FAB2_LIB.BASEBOARD_FAB2(SCH_1):PAGE181_I87@MSTR_DISCRETE.CAP(CHIPS)':
 'A': CDS_PINID='A';
NODE_NAME     J1F1 D7
 '@BASEBOARD_FAB2_LIB.BASEBOARD_FAB2(SCH_1):PAGE181_I134@W_HDL.DM-FCI-CONN76-8R-GP-U-01(CHIPS)':
 'PCIE_TX_DP4': CDS_PINID='PCIE_TX_DP4';
NET_NAME
'P3E_CPU1_PE3_MP_C_TXN<5>'
 '@BASEBOARD_FAB2_LIB.BASEBOARD_FAB2(SCH_1):P3E_CPU1_PE3_MP_C_TXN'<5>:
 C_SIGNAL='@baseboard_fab2_lib.baseboard_fab2(sch_1):p3e_cpu1_pe3_mp_c_txn(5)';
NODE_NAME     C1F8 1
 '@BASEBOARD_FAB2_LIB.BASEBOARD_FAB2(SCH_1):PAGE181_I73@MSTR_DISCRETE.CAP(CHIPS)':
 'A': CDS_PINID='A';
NODE_NAME     J1F1 H7
 '@BASEBOARD_FAB2_LIB.BASEBOARD_FAB2(SCH_1):PAGE181_I134@W_HDL.DM-FCI-CONN76-8R-GP-U-01(CHIPS)':
 'PCIE_TX_DN5': CDS_PINID='PCIE_TX_DN5';
NET_NAME
'P3E_CPU1_PE3_MP_C_TXN<6>'
 '@BASEBOARD_FAB2_LIB.BASEBOARD_FAB2(SCH_1):P3E_CPU1_PE3_MP_C_TXN'<6>:
 C_SIGNAL='@baseboard_fab2_lib.baseboard_fab2(sch_1):p3e_cpu1_pe3_mp_c_txn(6)';
NODE_NAME     C1F4 1
 '@BASEBOARD_FAB2_LIB.BASEBOARD_FAB2(SCH_1):PAGE181_I91@MSTR_DISCRETE.CAP(CHIPS)':
 'A': CDS_PINID='A';
NODE_NAME     J1F1 E6
 '@BASEBOARD_FAB2_LIB.BASEBOARD_FAB2(SCH_1):PAGE181_I134@W_HDL.DM-FCI-CONN76-8R-GP-U-01(CHIPS)':
 'PCIE_TX_DP6': CDS_PINID='PCIE_TX_DP6';
NET_NAME
'P3E_CPU1_PE3_MP_C_TXN<7>'
 '@BASEBOARD_FAB2_LIB.BASEBOARD_FAB2(SCH_1):P3E_CPU1_PE3_MP_C_TXN'<7>:
 C_SIGNAL='@baseboard_fab2_lib.baseboard_fab2(sch_1):p3e_cpu1_pe3_mp_c_txn(7)';
NODE_NAME     C1F3 1
 '@BASEBOARD_FAB2_LIB.BASEBOARD_FAB2(SCH_1):PAGE181_I76@MSTR_DISCRETE.CAP(CHIPS)':
 'A': CDS_PINID='A';
NODE_NAME     J1F1 I6
 '@BASEBOARD_FAB2_LIB.BASEBOARD_FAB2(SCH_1):PAGE181_I134@W_HDL.DM-FCI-CONN76-8R-GP-U-01(CHIPS)':
 'PCIE_TX_DN7': CDS_PINID='PCIE_TX_DN7';
NET_NAME
'P3E_CPU1_PE3_MP_C_TXN<8>'
 '@BASEBOARD_FAB2_LIB.BASEBOARD_FAB2(SCH_1):P3E_CPU1_PE3_MP_C_TXN'<8>:
 C_SIGNAL='@baseboard_fab2_lib.baseboard_fab2(sch_1):p3e_cpu1_pe3_mp_c_txn(8)';
NODE_NAME     C9N18 1
 '@BASEBOARD_FAB2_LIB.BASEBOARD_FAB2(SCH_1):PAGE182_I39@MSTR_DISCRETE.CAP(CHIPS)':
 'A': CDS_PINID='A';
NODE_NAME     J1C1 B8
 '@BASEBOARD_FAB2_LIB.BASEBOARD_FAB2(SCH_1):PAGE182_I79@W_HDL.DM-FCI-CONN76-8R-GP-U-01(CHIPS)':
 'PCIE_TX_DP0': CDS_PINID='PCIE_TX_DP0';
NET_NAME
'P3E_CPU1_PE3_MP_C_TXN<9>'
 '@BASEBOARD_FAB2_LIB.BASEBOARD_FAB2(SCH_1):P3E_CPU1_PE3_MP_C_TXN'<9>:
 C_SIGNAL='@baseboard_fab2_lib.baseboard_fab2(sch_1):p3e_cpu1_pe3_mp_c_txn(9)';
NODE_NAME     C9N15 1
 '@BASEBOARD_FAB2_LIB.BASEBOARD_FAB2(SCH_1):PAGE182_I41@MSTR_DISCRETE.CAP(CHIPS)':
 'A': CDS_PINID='A';
NODE_NAME     J1C1 E8
 '@BASEBOARD_FAB2_LIB.BASEBOARD_FAB2(SCH_1):PAGE182_I79@W_HDL.DM-FCI-CONN76-8R-GP-U-01(CHIPS)':
 'PCIE_TX_DP1': CDS_PINID='PCIE_TX_DP1';
NET_NAME
'P3E_CPU1_PE3_MP_C_TXP<0>'
 '@BASEBOARD_FAB2_LIB.BASEBOARD_FAB2(SCH_1):P3E_CPU1_PE3_MP_C_TXP'<0>:
 C_SIGNAL='@baseboard_fab2_lib.baseboard_fab2(sch_1):p3e_cpu1_pe3_mp_c_txp(0)';
NODE_NAME     C1F18 1
 '@BASEBOARD_FAB2_LIB.BASEBOARD_FAB2(SCH_1):PAGE181_I72@MSTR_DISCRETE.CAP(CHIPS)':
 'A': CDS_PINID='A';
NODE_NAME     J1F1 C8
 '@BASEBOARD_FAB2_LIB.BASEBOARD_FAB2(SCH_1):PAGE181_I134@W_HDL.DM-FCI-CONN76-8R-GP-U-01(CHIPS)':
 'PCIE_TX_DN0': CDS_PINID='PCIE_TX_DN0';
NET_NAME
'P3E_CPU1_PE3_MP_C_TXP<10>'
 '@BASEBOARD_FAB2_LIB.BASEBOARD_FAB2(SCH_1):P3E_CPU1_PE3_MP_C_TXP'<10>:
 C_SIGNAL='@baseboard_fab2_lib.baseboard_fab2(sch_1):p3e_cpu1_pe3_mp_c_txp(10)';
NODE_NAME     C9N1 1
 '@BASEBOARD_FAB2_LIB.BASEBOARD_FAB2(SCH_1):PAGE182_I40@MSTR_DISCRETE.CAP(CHIPS)':
 'A': CDS_PINID='A';
NODE_NAME     J1C1 H8
 '@BASEBOARD_FAB2_LIB.BASEBOARD_FAB2(SCH_1):PAGE182_I79@W_HDL.DM-FCI-CONN76-8R-GP-U-01(CHIPS)':
 'PCIE_TX_DP2': CDS_PINID='PCIE_TX_DP2';
NET_NAME
'P3E_CPU1_PE3_MP_C_TXP<11>'
 '@BASEBOARD_FAB2_LIB.BASEBOARD_FAB2(SCH_1):P3E_CPU1_PE3_MP_C_TXP'<11>:
 C_SIGNAL='@baseboard_fab2_lib.baseboard_fab2(sch_1):p3e_cpu1_pe3_mp_c_txp(11)';
NODE_NAME     C9N4 1
 '@BASEBOARD_FAB2_LIB.BASEBOARD_FAB2(SCH_1):PAGE182_I44@MSTR_DISCRETE.CAP(CHIPS)':
 'A': CDS_PINID='A';
NODE_NAME     J1C1 B7
 '@BASEBOARD_FAB2_LIB.BASEBOARD_FAB2(SCH_1):PAGE182_I79@W_HDL.DM-FCI-CONN76-8R-GP-U-01(CHIPS)':
 'PCIE_TX_DN3': CDS_PINID='PCIE_TX_DN3';
NET_NAME
'P3E_CPU1_PE3_MP_C_TXP<12>'
 '@BASEBOARD_FAB2_LIB.BASEBOARD_FAB2(SCH_1):P3E_CPU1_PE3_MP_C_TXP'<12>:
 C_SIGNAL='@baseboard_fab2_lib.baseboard_fab2(sch_1):p3e_cpu1_pe3_mp_c_txp(12)';
NODE_NAME     C9N14 1
 '@BASEBOARD_FAB2_LIB.BASEBOARD_FAB2(SCH_1):PAGE182_I43@MSTR_DISCRETE.CAP(CHIPS)':
 'A': CDS_PINID='A';
NODE_NAME     J1C1 E7
 '@BASEBOARD_FAB2_LIB.BASEBOARD_FAB2(SCH_1):PAGE182_I79@W_HDL.DM-FCI-CONN76-8R-GP-U-01(CHIPS)':
 'PCIE_TX_DN4': CDS_PINID='PCIE_TX_DN4';
NET_NAME
'P3E_CPU1_PE3_MP_C_TXP<13>'
 '@BASEBOARD_FAB2_LIB.BASEBOARD_FAB2(SCH_1):P3E_CPU1_PE3_MP_C_TXP'<13>:
 C_SIGNAL='@baseboard_fab2_lib.baseboard_fab2(sch_1):p3e_cpu1_pe3_mp_c_txp(13)';
NODE_NAME     C9N5 1
 '@BASEBOARD_FAB2_LIB.BASEBOARD_FAB2(SCH_1):PAGE182_I45@MSTR_DISCRETE.CAP(CHIPS)':
 'A': CDS_PINID='A';
NODE_NAME     J1C1 H7
 '@BASEBOARD_FAB2_LIB.BASEBOARD_FAB2(SCH_1):PAGE182_I79@W_HDL.DM-FCI-CONN76-8R-GP-U-01(CHIPS)':
 'PCIE_TX_DN5': CDS_PINID='PCIE_TX_DN5';
NET_NAME
'P3E_CPU1_PE3_MP_C_TXP<14>'
 '@BASEBOARD_FAB2_LIB.BASEBOARD_FAB2(SCH_1):P3E_CPU1_PE3_MP_C_TXP'<14>:
 C_SIGNAL='@baseboard_fab2_lib.baseboard_fab2(sch_1):p3e_cpu1_pe3_mp_c_txp(14)';
NODE_NAME     C9N10 1
 '@BASEBOARD_FAB2_LIB.BASEBOARD_FAB2(SCH_1):PAGE182_I49@MSTR_DISCRETE.CAP(CHIPS)':
 'A': CDS_PINID='A';
NODE_NAME     J1C1 F6
 '@BASEBOARD_FAB2_LIB.BASEBOARD_FAB2(SCH_1):PAGE182_I79@W_HDL.DM-FCI-CONN76-8R-GP-U-01(CHIPS)':
 'PCIE_TX_DN6': CDS_PINID='PCIE_TX_DN6';
NET_NAME
'P3E_CPU1_PE3_MP_C_TXP<15>'
 '@BASEBOARD_FAB2_LIB.BASEBOARD_FAB2(SCH_1):P3E_CPU1_PE3_MP_C_TXP'<15>:
 C_SIGNAL='@baseboard_fab2_lib.baseboard_fab2(sch_1):p3e_cpu1_pe3_mp_c_txp(15)';
NODE_NAME     C9N7 1
 '@BASEBOARD_FAB2_LIB.BASEBOARD_FAB2(SCH_1):PAGE182_I48@MSTR_DISCRETE.CAP(CHIPS)':
 'A': CDS_PINID='A';
NODE_NAME     J1C1 I6
 '@BASEBOARD_FAB2_LIB.BASEBOARD_FAB2(SCH_1):PAGE182_I79@W_HDL.DM-FCI-CONN76-8R-GP-U-01(CHIPS)':
 'PCIE_TX_DN7': CDS_PINID='PCIE_TX_DN7';
NET_NAME
'P3E_CPU1_PE3_MP_C_TXP<1>'
 '@BASEBOARD_FAB2_LIB.BASEBOARD_FAB2(SCH_1):P3E_CPU1_PE3_MP_C_TXP'<1>:
 C_SIGNAL='@baseboard_fab2_lib.baseboard_fab2(sch_1):p3e_cpu1_pe3_mp_c_txp(1)';
NODE_NAME     C1F17 1
 '@BASEBOARD_FAB2_LIB.BASEBOARD_FAB2(SCH_1):PAGE181_I71@MSTR_DISCRETE.CAP(CHIPS)':
 'A': CDS_PINID='A';
NODE_NAME     J1F1 F8
 '@BASEBOARD_FAB2_LIB.BASEBOARD_FAB2(SCH_1):PAGE181_I134@W_HDL.DM-FCI-CONN76-8R-GP-U-01(CHIPS)':
 'PCIE_TX_DN1': CDS_PINID='PCIE_TX_DN1';
NET_NAME
'P3E_CPU1_PE3_MP_C_TXP<2>'
 '@BASEBOARD_FAB2_LIB.BASEBOARD_FAB2(SCH_1):P3E_CPU1_PE3_MP_C_TXP'<2>:
 C_SIGNAL='@baseboard_fab2_lib.baseboard_fab2(sch_1):p3e_cpu1_pe3_mp_c_txp(2)';
NODE_NAME     C1F14 1
 '@BASEBOARD_FAB2_LIB.BASEBOARD_FAB2(SCH_1):PAGE181_I70@MSTR_DISCRETE.CAP(CHIPS)':
 'A': CDS_PINID='A';
NODE_NAME     J1F1 I8
 '@BASEBOARD_FAB2_LIB.BASEBOARD_FAB2(SCH_1):PAGE181_I134@W_HDL.DM-FCI-CONN76-8R-GP-U-01(CHIPS)':
 'PCIE_TX_DN2': CDS_PINID='PCIE_TX_DN2';
NET_NAME
'P3E_CPU1_PE3_MP_C_TXP<3>'
 '@BASEBOARD_FAB2_LIB.BASEBOARD_FAB2(SCH_1):P3E_CPU1_PE3_MP_C_TXP'<3>:
 C_SIGNAL='@baseboard_fab2_lib.baseboard_fab2(sch_1):p3e_cpu1_pe3_mp_c_txp(3)';
NODE_NAME     C1F12 1
 '@BASEBOARD_FAB2_LIB.BASEBOARD_FAB2(SCH_1):PAGE181_I75@MSTR_DISCRETE.CAP(CHIPS)':
 'A': CDS_PINID='A';
NODE_NAME     J1F1 B7
 '@BASEBOARD_FAB2_LIB.BASEBOARD_FAB2(SCH_1):PAGE181_I134@W_HDL.DM-FCI-CONN76-8R-GP-U-01(CHIPS)':
 'PCIE_TX_DN3': CDS_PINID='PCIE_TX_DN3';
NET_NAME
'P3E_CPU1_PE3_MP_C_TXP<4>'
 '@BASEBOARD_FAB2_LIB.BASEBOARD_FAB2(SCH_1):P3E_CPU1_PE3_MP_C_TXP'<4>:
 C_SIGNAL='@baseboard_fab2_lib.baseboard_fab2(sch_1):p3e_cpu1_pe3_mp_c_txp(4)';
NODE_NAME     C1F11 1
 '@BASEBOARD_FAB2_LIB.BASEBOARD_FAB2(SCH_1):PAGE181_I74@MSTR_DISCRETE.CAP(CHIPS)':
 'A': CDS_PINID='A';
NODE_NAME     J1F1 E7
 '@BASEBOARD_FAB2_LIB.BASEBOARD_FAB2(SCH_1):PAGE181_I134@W_HDL.DM-FCI-CONN76-8R-GP-U-01(CHIPS)':
 'PCIE_TX_DN4': CDS_PINID='PCIE_TX_DN4';
NET_NAME
'P3E_CPU1_PE3_MP_C_TXP<5>'
 '@BASEBOARD_FAB2_LIB.BASEBOARD_FAB2(SCH_1):P3E_CPU1_PE3_MP_C_TXP'<5>:
 C_SIGNAL='@baseboard_fab2_lib.baseboard_fab2(sch_1):p3e_cpu1_pe3_mp_c_txp(5)';
NODE_NAME     C1F6 1
 '@BASEBOARD_FAB2_LIB.BASEBOARD_FAB2(SCH_1):PAGE181_I88@MSTR_DISCRETE.CAP(CHIPS)':
 'A': CDS_PINID='A';
NODE_NAME     J1F1 G7
 '@BASEBOARD_FAB2_LIB.BASEBOARD_FAB2(SCH_1):PAGE181_I134@W_HDL.DM-FCI-CONN76-8R-GP-U-01(CHIPS)':
 'PCIE_TX_DP5': CDS_PINID='PCIE_TX_DP5';
NET_NAME
'P3E_CPU1_PE3_MP_C_TXP<6>'
 '@BASEBOARD_FAB2_LIB.BASEBOARD_FAB2(SCH_1):P3E_CPU1_PE3_MP_C_TXP'<6>:
 C_SIGNAL='@baseboard_fab2_lib.baseboard_fab2(sch_1):p3e_cpu1_pe3_mp_c_txp(6)';
NODE_NAME     C1F5 1
 '@BASEBOARD_FAB2_LIB.BASEBOARD_FAB2(SCH_1):PAGE181_I77@MSTR_DISCRETE.CAP(CHIPS)':
 'A': CDS_PINID='A';
NODE_NAME     J1F1 F6
 '@BASEBOARD_FAB2_LIB.BASEBOARD_FAB2(SCH_1):PAGE181_I134@W_HDL.DM-FCI-CONN76-8R-GP-U-01(CHIPS)':
 'PCIE_TX_DN6': CDS_PINID='PCIE_TX_DN6';
NET_NAME
'P3E_CPU1_PE3_MP_C_TXP<7>'
 '@BASEBOARD_FAB2_LIB.BASEBOARD_FAB2(SCH_1):P3E_CPU1_PE3_MP_C_TXP'<7>:
 C_SIGNAL='@baseboard_fab2_lib.baseboard_fab2(sch_1):p3e_cpu1_pe3_mp_c_txp(7)';
NODE_NAME     C1F2 1
 '@BASEBOARD_FAB2_LIB.BASEBOARD_FAB2(SCH_1):PAGE181_I90@MSTR_DISCRETE.CAP(CHIPS)':
 'A': CDS_PINID='A';
NODE_NAME     J1F1 H6
 '@BASEBOARD_FAB2_LIB.BASEBOARD_FAB2(SCH_1):PAGE181_I134@W_HDL.DM-FCI-CONN76-8R-GP-U-01(CHIPS)':
 'PCIE_TX_DP7': CDS_PINID='PCIE_TX_DP7';
NET_NAME
'P3E_CPU1_PE3_MP_C_TXP<8>'
 '@BASEBOARD_FAB2_LIB.BASEBOARD_FAB2(SCH_1):P3E_CPU1_PE3_MP_C_TXP'<8>:
 C_SIGNAL='@baseboard_fab2_lib.baseboard_fab2(sch_1):p3e_cpu1_pe3_mp_c_txp(8)';
NODE_NAME     C9N17 1
 '@BASEBOARD_FAB2_LIB.BASEBOARD_FAB2(SCH_1):PAGE182_I38@MSTR_DISCRETE.CAP(CHIPS)':
 'A': CDS_PINID='A';
NODE_NAME     J1C1 C8
 '@BASEBOARD_FAB2_LIB.BASEBOARD_FAB2(SCH_1):PAGE182_I79@W_HDL.DM-FCI-CONN76-8R-GP-U-01(CHIPS)':
 'PCIE_TX_DN0': CDS_PINID='PCIE_TX_DN0';
NET_NAME
'P3E_CPU1_PE3_MP_C_TXP<9>'
 '@BASEBOARD_FAB2_LIB.BASEBOARD_FAB2(SCH_1):P3E_CPU1_PE3_MP_C_TXP'<9>:
 C_SIGNAL='@baseboard_fab2_lib.baseboard_fab2(sch_1):p3e_cpu1_pe3_mp_c_txp(9)';
NODE_NAME     C9N12 1
 '@BASEBOARD_FAB2_LIB.BASEBOARD_FAB2(SCH_1):PAGE182_I37@MSTR_DISCRETE.CAP(CHIPS)':
 'A': CDS_PINID='A';
NODE_NAME     J1C1 F8
 '@BASEBOARD_FAB2_LIB.BASEBOARD_FAB2(SCH_1):PAGE182_I79@W_HDL.DM-FCI-CONN76-8R-GP-U-01(CHIPS)':
 'PCIE_TX_DN1': CDS_PINID='PCIE_TX_DN1';
NET_NAME
'P3E_CPU1_PE3_MP_RXN<0>'
 '@BASEBOARD_FAB2_LIB.BASEBOARD_FAB2(SCH_1):P3E_CPU1_PE3_MP_RXN'<0>:
 C_SIGNAL='@baseboard_fab2_lib.baseboard_fab2(sch_1):p3e_cpu1_pe3_mp_rxn(0)';
NODE_NAME     U2D1 EA18
 '@BASEBOARD_FAB2_LIB.BASEBOARD_FAB2(SCH_1):PAGE66_I84@CHPSET_LIB.SKX_EXT_B(CHIPS)':
 'PE3_RX_DN'<0>: CDS_PINID='PE3_RX_DN(0)';
NODE_NAME     J1F1 A1
 '@BASEBOARD_FAB2_LIB.BASEBOARD_FAB2(SCH_1):PAGE181_I134@W_HDL.DM-FCI-CONN76-8R-GP-U-01(CHIPS)':
 'PCIE_RX_DP0': CDS_PINID='PCIE_RX_DP0';
NET_NAME
'P3E_CPU1_PE3_MP_RXN<10>'
 '@BASEBOARD_FAB2_LIB.BASEBOARD_FAB2(SCH_1):P3E_CPU1_PE3_MP_RXN'<10>:
 C_SIGNAL='@baseboard_fab2_lib.baseboard_fab2(sch_1):p3e_cpu1_pe3_mp_rxn(10)';
NODE_NAME     U2D1 DG12
 '@BASEBOARD_FAB2_LIB.BASEBOARD_FAB2(SCH_1):PAGE66_I84@CHPSET_LIB.SKX_EXT_B(CHIPS)':
 'PE3_RX_DN'<10>: CDS_PINID='PE3_RX_DN(10)';
NODE_NAME     J1C1 H1
 '@BASEBOARD_FAB2_LIB.BASEBOARD_FAB2(SCH_1):PAGE182_I79@W_HDL.DM-FCI-CONN76-8R-GP-U-01(CHIPS)':
 'PCIE_RX_DN2': CDS_PINID='PCIE_RX_DN2';
NET_NAME
'P3E_CPU1_PE3_MP_RXN<11>'
 '@BASEBOARD_FAB2_LIB.BASEBOARD_FAB2(SCH_1):P3E_CPU1_PE3_MP_RXN'<11>:
 C_SIGNAL='@baseboard_fab2_lib.baseboard_fab2(sch_1):p3e_cpu1_pe3_mp_rxn(11)';
NODE_NAME     U2D1 DG10
 '@BASEBOARD_FAB2_LIB.BASEBOARD_FAB2(SCH_1):PAGE66_I84@CHPSET_LIB.SKX_EXT_B(CHIPS)':
 'PE3_RX_DN'<11>: CDS_PINID='PE3_RX_DN(11)';
NODE_NAME     J1C1 B2
 '@BASEBOARD_FAB2_LIB.BASEBOARD_FAB2(SCH_1):PAGE182_I79@W_HDL.DM-FCI-CONN76-8R-GP-U-01(CHIPS)':
 'PCIE_RX_DP3': CDS_PINID='PCIE_RX_DP3';
NET_NAME
'P3E_CPU1_PE3_MP_RXN<12>'
 '@BASEBOARD_FAB2_LIB.BASEBOARD_FAB2(SCH_1):P3E_CPU1_PE3_MP_RXN'<12>:
 C_SIGNAL='@baseboard_fab2_lib.baseboard_fab2(sch_1):p3e_cpu1_pe3_mp_rxn(12)';
NODE_NAME     U2D1 DC12
 '@BASEBOARD_FAB2_LIB.BASEBOARD_FAB2(SCH_1):PAGE66_I84@CHPSET_LIB.SKX_EXT_B(CHIPS)':
 'PE3_RX_DP'<12>: CDS_PINID='PE3_RX_DP(12)';
NODE_NAME     J1C1 E2
 '@BASEBOARD_FAB2_LIB.BASEBOARD_FAB2(SCH_1):PAGE182_I79@W_HDL.DM-FCI-CONN76-8R-GP-U-01(CHIPS)':
 'PCIE_RX_DP4': CDS_PINID='PCIE_RX_DP4';
NET_NAME
'P3E_CPU1_PE3_MP_RXN<13>'
 '@BASEBOARD_FAB2_LIB.BASEBOARD_FAB2(SCH_1):P3E_CPU1_PE3_MP_RXN'<13>:
 C_SIGNAL='@baseboard_fab2_lib.baseboard_fab2(sch_1):p3e_cpu1_pe3_mp_rxn(13)';
NODE_NAME     U2D1 DB11
 '@BASEBOARD_FAB2_LIB.BASEBOARD_FAB2(SCH_1):PAGE66_I84@CHPSET_LIB.SKX_EXT_B(CHIPS)':
 'PE3_RX_DN'<13>: CDS_PINID='PE3_RX_DN(13)';
NODE_NAME     J1C1 I2
 '@BASEBOARD_FAB2_LIB.BASEBOARD_FAB2(SCH_1):PAGE182_I79@W_HDL.DM-FCI-CONN76-8R-GP-U-01(CHIPS)':
 'PCIE_RX_DN5': CDS_PINID='PCIE_RX_DN5';
NET_NAME
'P3E_CPU1_PE3_MP_RXN<14>'
 '@BASEBOARD_FAB2_LIB.BASEBOARD_FAB2(SCH_1):P3E_CPU1_PE3_MP_RXN'<14>:
 C_SIGNAL='@baseboard_fab2_lib.baseboard_fab2(sch_1):p3e_cpu1_pe3_mp_rxn(14)';
NODE_NAME     U2D1 CY11
 '@BASEBOARD_FAB2_LIB.BASEBOARD_FAB2(SCH_1):PAGE66_I84@CHPSET_LIB.SKX_EXT_B(CHIPS)':
 'PE3_RX_DN'<14>: CDS_PINID='PE3_RX_DN(14)';
NODE_NAME     J1C1 B3
 '@BASEBOARD_FAB2_LIB.BASEBOARD_FAB2(SCH_1):PAGE182_I79@W_HDL.DM-FCI-CONN76-8R-GP-U-01(CHIPS)':
 'PCIE_RX_DN6': CDS_PINID='PCIE_RX_DN6';
NET_NAME
'P3E_CPU1_PE3_MP_RXN<15>'
 '@BASEBOARD_FAB2_LIB.BASEBOARD_FAB2(SCH_1):P3E_CPU1_PE3_MP_RXN'<15>:
 C_SIGNAL='@baseboard_fab2_lib.baseboard_fab2(sch_1):p3e_cpu1_pe3_mp_rxn(15)';
NODE_NAME     U2D1 CV9
 '@BASEBOARD_FAB2_LIB.BASEBOARD_FAB2(SCH_1):PAGE66_I84@CHPSET_LIB.SKX_EXT_B(CHIPS)':
 'PE3_RX_DN'<15>: CDS_PINID='PE3_RX_DN(15)';
NODE_NAME     J1C1 D3
 '@BASEBOARD_FAB2_LIB.BASEBOARD_FAB2(SCH_1):PAGE182_I79@W_HDL.DM-FCI-CONN76-8R-GP-U-01(CHIPS)':
 'PCIE_RX_DP7': CDS_PINID='PCIE_RX_DP7';
NET_NAME
'P3E_CPU1_PE3_MP_RXN<1>'
 '@BASEBOARD_FAB2_LIB.BASEBOARD_FAB2(SCH_1):P3E_CPU1_PE3_MP_RXN'<1>:
 C_SIGNAL='@baseboard_fab2_lib.baseboard_fab2(sch_1):p3e_cpu1_pe3_mp_rxn(1)';
NODE_NAME     U2D1 DW18
 '@BASEBOARD_FAB2_LIB.BASEBOARD_FAB2(SCH_1):PAGE66_I84@CHPSET_LIB.SKX_EXT_B(CHIPS)':
 'PE3_RX_DN'<1>: CDS_PINID='PE3_RX_DN(1)';
NODE_NAME     J1F1 D1
 '@BASEBOARD_FAB2_LIB.BASEBOARD_FAB2(SCH_1):PAGE181_I134@W_HDL.DM-FCI-CONN76-8R-GP-U-01(CHIPS)':
 'PCIE_RX_DP1': CDS_PINID='PCIE_RX_DP1';
NET_NAME
'P3E_CPU1_PE3_MP_RXN<2>'
 '@BASEBOARD_FAB2_LIB.BASEBOARD_FAB2(SCH_1):P3E_CPU1_PE3_MP_RXN'<2>:
 C_SIGNAL='@baseboard_fab2_lib.baseboard_fab2(sch_1):p3e_cpu1_pe3_mp_rxn(2)';
NODE_NAME     U2D1 DW16
 '@BASEBOARD_FAB2_LIB.BASEBOARD_FAB2(SCH_1):PAGE66_I84@CHPSET_LIB.SKX_EXT_B(CHIPS)':
 'PE3_RX_DN'<2>: CDS_PINID='PE3_RX_DN(2)';
NODE_NAME     J1F1 H1
 '@BASEBOARD_FAB2_LIB.BASEBOARD_FAB2(SCH_1):PAGE181_I134@W_HDL.DM-FCI-CONN76-8R-GP-U-01(CHIPS)':
 'PCIE_RX_DN2': CDS_PINID='PCIE_RX_DN2';
NET_NAME
'P3E_CPU1_PE3_MP_RXN<3>'
 '@BASEBOARD_FAB2_LIB.BASEBOARD_FAB2(SCH_1):P3E_CPU1_PE3_MP_RXN'<3>:
 C_SIGNAL='@baseboard_fab2_lib.baseboard_fab2(sch_1):p3e_cpu1_pe3_mp_rxn(3)';
NODE_NAME     U2D1 DT19
 '@BASEBOARD_FAB2_LIB.BASEBOARD_FAB2(SCH_1):PAGE66_I84@CHPSET_LIB.SKX_EXT_B(CHIPS)':
 'PE3_RX_DN'<3>: CDS_PINID='PE3_RX_DN(3)';
NODE_NAME     J1F1 B2
 '@BASEBOARD_FAB2_LIB.BASEBOARD_FAB2(SCH_1):PAGE181_I134@W_HDL.DM-FCI-CONN76-8R-GP-U-01(CHIPS)':
 'PCIE_RX_DP3': CDS_PINID='PCIE_RX_DP3';
NET_NAME
'P3E_CPU1_PE3_MP_RXN<4>'
 '@BASEBOARD_FAB2_LIB.BASEBOARD_FAB2(SCH_1):P3E_CPU1_PE3_MP_RXN'<4>:
 C_SIGNAL='@baseboard_fab2_lib.baseboard_fab2(sch_1):p3e_cpu1_pe3_mp_rxn(4)';
NODE_NAME     U2D1 DR16
 '@BASEBOARD_FAB2_LIB.BASEBOARD_FAB2(SCH_1):PAGE66_I84@CHPSET_LIB.SKX_EXT_B(CHIPS)':
 'PE3_RX_DN'<4>: CDS_PINID='PE3_RX_DN(4)';
NODE_NAME     J1F1 E2
 '@BASEBOARD_FAB2_LIB.BASEBOARD_FAB2(SCH_1):PAGE181_I134@W_HDL.DM-FCI-CONN76-8R-GP-U-01(CHIPS)':
 'PCIE_RX_DP4': CDS_PINID='PCIE_RX_DP4';
NET_NAME
'P3E_CPU1_PE3_MP_RXN<5>'
 '@BASEBOARD_FAB2_LIB.BASEBOARD_FAB2(SCH_1):P3E_CPU1_PE3_MP_RXN'<5>:
 C_SIGNAL='@baseboard_fab2_lib.baseboard_fab2(sch_1):p3e_cpu1_pe3_mp_rxn(5)';
NODE_NAME     U2D1 DR14
 '@BASEBOARD_FAB2_LIB.BASEBOARD_FAB2(SCH_1):PAGE66_I84@CHPSET_LIB.SKX_EXT_B(CHIPS)':
 'PE3_RX_DN'<5>: CDS_PINID='PE3_RX_DN(5)';
NODE_NAME     J1F1 I2
 '@BASEBOARD_FAB2_LIB.BASEBOARD_FAB2(SCH_1):PAGE181_I134@W_HDL.DM-FCI-CONN76-8R-GP-U-01(CHIPS)':
 'PCIE_RX_DN5': CDS_PINID='PCIE_RX_DN5';
NET_NAME
'P3E_CPU1_PE3_MP_RXN<6>'
 '@BASEBOARD_FAB2_LIB.BASEBOARD_FAB2(SCH_1):P3E_CPU1_PE3_MP_RXN'<6>:
 C_SIGNAL='@baseboard_fab2_lib.baseboard_fab2(sch_1):p3e_cpu1_pe3_mp_rxn(6)';
NODE_NAME     U2D1 DN14
 '@BASEBOARD_FAB2_LIB.BASEBOARD_FAB2(SCH_1):PAGE66_I84@CHPSET_LIB.SKX_EXT_B(CHIPS)':
 'PE3_RX_DN'<6>: CDS_PINID='PE3_RX_DN(6)';
NODE_NAME     J1F1 B3
 '@BASEBOARD_FAB2_LIB.BASEBOARD_FAB2(SCH_1):PAGE181_I134@W_HDL.DM-FCI-CONN76-8R-GP-U-01(CHIPS)':
 'PCIE_RX_DN6': CDS_PINID='PCIE_RX_DN6';
NET_NAME
'P3E_CPU1_PE3_MP_RXN<7>'
 '@BASEBOARD_FAB2_LIB.BASEBOARD_FAB2(SCH_1):P3E_CPU1_PE3_MP_RXN'<7>:
 C_SIGNAL='@baseboard_fab2_lib.baseboard_fab2(sch_1):p3e_cpu1_pe3_mp_rxn(7)';
NODE_NAME     U2D1 DL14
 '@BASEBOARD_FAB2_LIB.BASEBOARD_FAB2(SCH_1):PAGE66_I84@CHPSET_LIB.SKX_EXT_B(CHIPS)':
 'PE3_RX_DN'<7>: CDS_PINID='PE3_RX_DN(7)';
NODE_NAME     J1F1 D3
 '@BASEBOARD_FAB2_LIB.BASEBOARD_FAB2(SCH_1):PAGE181_I134@W_HDL.DM-FCI-CONN76-8R-GP-U-01(CHIPS)':
 'PCIE_RX_DP7': CDS_PINID='PCIE_RX_DP7';
NET_NAME
'P3E_CPU1_PE3_MP_RXN<8>'
 '@BASEBOARD_FAB2_LIB.BASEBOARD_FAB2(SCH_1):P3E_CPU1_PE3_MP_RXN'<8>:
 C_SIGNAL='@baseboard_fab2_lib.baseboard_fab2(sch_1):p3e_cpu1_pe3_mp_rxn(8)';
NODE_NAME     U2D1 DL12
 '@BASEBOARD_FAB2_LIB.BASEBOARD_FAB2(SCH_1):PAGE66_I84@CHPSET_LIB.SKX_EXT_B(CHIPS)':
 'PE3_RX_DN'<8>: CDS_PINID='PE3_RX_DN(8)';
NODE_NAME     J1C1 A1
 '@BASEBOARD_FAB2_LIB.BASEBOARD_FAB2(SCH_1):PAGE182_I79@W_HDL.DM-FCI-CONN76-8R-GP-U-01(CHIPS)':
 'PCIE_RX_DP0': CDS_PINID='PCIE_RX_DP0';
NET_NAME
'P3E_CPU1_PE3_MP_RXN<9>'
 '@BASEBOARD_FAB2_LIB.BASEBOARD_FAB2(SCH_1):P3E_CPU1_PE3_MP_RXN'<9>:
 C_SIGNAL='@baseboard_fab2_lib.baseboard_fab2(sch_1):p3e_cpu1_pe3_mp_rxn(9)';
NODE_NAME     U2D1 DJ12
 '@BASEBOARD_FAB2_LIB.BASEBOARD_FAB2(SCH_1):PAGE66_I84@CHPSET_LIB.SKX_EXT_B(CHIPS)':
 'PE3_RX_DN'<9>: CDS_PINID='PE3_RX_DN(9)';
NODE_NAME     J1C1 D1
 '@BASEBOARD_FAB2_LIB.BASEBOARD_FAB2(SCH_1):PAGE182_I79@W_HDL.DM-FCI-CONN76-8R-GP-U-01(CHIPS)':
 'PCIE_RX_DP1': CDS_PINID='PCIE_RX_DP1';
NET_NAME
'P3E_CPU1_PE3_MP_RXP<0>'
 '@BASEBOARD_FAB2_LIB.BASEBOARD_FAB2(SCH_1):P3E_CPU1_PE3_MP_RXP'<0>:
 C_SIGNAL='@baseboard_fab2_lib.baseboard_fab2(sch_1):p3e_cpu1_pe3_mp_rxp(0)';
NODE_NAME     U2D1 DY17
 '@BASEBOARD_FAB2_LIB.BASEBOARD_FAB2(SCH_1):PAGE66_I84@CHPSET_LIB.SKX_EXT_B(CHIPS)':
 'PE3_RX_DP'<0>: CDS_PINID='PE3_RX_DP(0)';
NODE_NAME     J1F1 B1
 '@BASEBOARD_FAB2_LIB.BASEBOARD_FAB2(SCH_1):PAGE181_I134@W_HDL.DM-FCI-CONN76-8R-GP-U-01(CHIPS)':
 'PCIE_RX_DN0': CDS_PINID='PCIE_RX_DN0';
NET_NAME
'P3E_CPU1_PE3_MP_RXP<10>'
 '@BASEBOARD_FAB2_LIB.BASEBOARD_FAB2(SCH_1):P3E_CPU1_PE3_MP_RXP'<10>:
 C_SIGNAL='@baseboard_fab2_lib.baseboard_fab2(sch_1):p3e_cpu1_pe3_mp_rxp(10)';
NODE_NAME     U2D1 DE12
 '@BASEBOARD_FAB2_LIB.BASEBOARD_FAB2(SCH_1):PAGE66_I84@CHPSET_LIB.SKX_EXT_B(CHIPS)':
 'PE3_RX_DP'<10>: CDS_PINID='PE3_RX_DP(10)';
NODE_NAME     J1C1 G1
 '@BASEBOARD_FAB2_LIB.BASEBOARD_FAB2(SCH_1):PAGE182_I79@W_HDL.DM-FCI-CONN76-8R-GP-U-01(CHIPS)':
 'PCIE_RX_DP2': CDS_PINID='PCIE_RX_DP2';
NET_NAME
'P3E_CPU1_PE3_MP_RXP<11>'
 '@BASEBOARD_FAB2_LIB.BASEBOARD_FAB2(SCH_1):P3E_CPU1_PE3_MP_RXP'<11>:
 C_SIGNAL='@baseboard_fab2_lib.baseboard_fab2(sch_1):p3e_cpu1_pe3_mp_rxp(11)';
NODE_NAME     U2D1 DF11
 '@BASEBOARD_FAB2_LIB.BASEBOARD_FAB2(SCH_1):PAGE66_I84@CHPSET_LIB.SKX_EXT_B(CHIPS)':
 'PE3_RX_DP'<11>: CDS_PINID='PE3_RX_DP(11)';
NODE_NAME     J1C1 C2
 '@BASEBOARD_FAB2_LIB.BASEBOARD_FAB2(SCH_1):PAGE182_I79@W_HDL.DM-FCI-CONN76-8R-GP-U-01(CHIPS)':
 'PCIE_RX_DN3': CDS_PINID='PCIE_RX_DN3';
NET_NAME
'P3E_CPU1_PE3_MP_RXP<12>'
 '@BASEBOARD_FAB2_LIB.BASEBOARD_FAB2(SCH_1):P3E_CPU1_PE3_MP_RXP'<12>:
 C_SIGNAL='@baseboard_fab2_lib.baseboard_fab2(sch_1):p3e_cpu1_pe3_mp_rxp(12)';
NODE_NAME     U2D1 DD13
 '@BASEBOARD_FAB2_LIB.BASEBOARD_FAB2(SCH_1):PAGE66_I84@CHPSET_LIB.SKX_EXT_B(CHIPS)':
 'PE3_RX_DN'<12>: CDS_PINID='PE3_RX_DN(12)';
NODE_NAME     J1C1 F2
 '@BASEBOARD_FAB2_LIB.BASEBOARD_FAB2(SCH_1):PAGE182_I79@W_HDL.DM-FCI-CONN76-8R-GP-U-01(CHIPS)':
 'PCIE_RX_DN4': CDS_PINID='PCIE_RX_DN4';
NET_NAME
'P3E_CPU1_PE3_MP_RXP<13>'
 '@BASEBOARD_FAB2_LIB.BASEBOARD_FAB2(SCH_1):P3E_CPU1_PE3_MP_RXP'<13>:
 C_SIGNAL='@baseboard_fab2_lib.baseboard_fab2(sch_1):p3e_cpu1_pe3_mp_rxp(13)';
NODE_NAME     U2D1 DA12
 '@BASEBOARD_FAB2_LIB.BASEBOARD_FAB2(SCH_1):PAGE66_I84@CHPSET_LIB.SKX_EXT_B(CHIPS)':
 'PE3_RX_DP'<13>: CDS_PINID='PE3_RX_DP(13)';
NODE_NAME     J1C1 H2
 '@BASEBOARD_FAB2_LIB.BASEBOARD_FAB2(SCH_1):PAGE182_I79@W_HDL.DM-FCI-CONN76-8R-GP-U-01(CHIPS)':
 'PCIE_RX_DP5': CDS_PINID='PCIE_RX_DP5';
NET_NAME
'P3E_CPU1_PE3_MP_RXP<14>'
 '@BASEBOARD_FAB2_LIB.BASEBOARD_FAB2(SCH_1):P3E_CPU1_PE3_MP_RXP'<14>:
 C_SIGNAL='@baseboard_fab2_lib.baseboard_fab2(sch_1):p3e_cpu1_pe3_mp_rxp(14)';
NODE_NAME     U2D1 CW10
 '@BASEBOARD_FAB2_LIB.BASEBOARD_FAB2(SCH_1):PAGE66_I84@CHPSET_LIB.SKX_EXT_B(CHIPS)':
 'PE3_RX_DP'<14>: CDS_PINID='PE3_RX_DP(14)';
NODE_NAME     J1C1 A3
 '@BASEBOARD_FAB2_LIB.BASEBOARD_FAB2(SCH_1):PAGE182_I79@W_HDL.DM-FCI-CONN76-8R-GP-U-01(CHIPS)':
 'PCIE_RX_DP6': CDS_PINID='PCIE_RX_DP6';
NET_NAME
'P3E_CPU1_PE3_MP_RXP<15>'
 '@BASEBOARD_FAB2_LIB.BASEBOARD_FAB2(SCH_1):P3E_CPU1_PE3_MP_RXP'<15>:
 C_SIGNAL='@baseboard_fab2_lib.baseboard_fab2(sch_1):p3e_cpu1_pe3_mp_rxp(15)';
NODE_NAME     U2D1 CU10
 '@BASEBOARD_FAB2_LIB.BASEBOARD_FAB2(SCH_1):PAGE66_I84@CHPSET_LIB.SKX_EXT_B(CHIPS)':
 'PE3_RX_DP'<15>: CDS_PINID='PE3_RX_DP(15)';
NODE_NAME     J1C1 E3
 '@BASEBOARD_FAB2_LIB.BASEBOARD_FAB2(SCH_1):PAGE182_I79@W_HDL.DM-FCI-CONN76-8R-GP-U-01(CHIPS)':
 'PCIE_RX_DN7': CDS_PINID='PCIE_RX_DN7';
NET_NAME
'P3E_CPU1_PE3_MP_RXP<1>'
 '@BASEBOARD_FAB2_LIB.BASEBOARD_FAB2(SCH_1):P3E_CPU1_PE3_MP_RXP'<1>:
 C_SIGNAL='@baseboard_fab2_lib.baseboard_fab2(sch_1):p3e_cpu1_pe3_mp_rxp(1)';
NODE_NAME     U2D1 DU18
 '@BASEBOARD_FAB2_LIB.BASEBOARD_FAB2(SCH_1):PAGE66_I84@CHPSET_LIB.SKX_EXT_B(CHIPS)':
 'PE3_RX_DP'<1>: CDS_PINID='PE3_RX_DP(1)';
NODE_NAME     J1F1 E1
 '@BASEBOARD_FAB2_LIB.BASEBOARD_FAB2(SCH_1):PAGE181_I134@W_HDL.DM-FCI-CONN76-8R-GP-U-01(CHIPS)':
 'PCIE_RX_DN1': CDS_PINID='PCIE_RX_DN1';
NET_NAME
'P3E_CPU1_PE3_MP_RXP<2>'
 '@BASEBOARD_FAB2_LIB.BASEBOARD_FAB2(SCH_1):P3E_CPU1_PE3_MP_RXP'<2>:
 C_SIGNAL='@baseboard_fab2_lib.baseboard_fab2(sch_1):p3e_cpu1_pe3_mp_rxp(2)';
NODE_NAME     U2D1 DV17
 '@BASEBOARD_FAB2_LIB.BASEBOARD_FAB2(SCH_1):PAGE66_I84@CHPSET_LIB.SKX_EXT_B(CHIPS)':
 'PE3_RX_DP'<2>: CDS_PINID='PE3_RX_DP(2)';
NODE_NAME     J1F1 G1
 '@BASEBOARD_FAB2_LIB.BASEBOARD_FAB2(SCH_1):PAGE181_I134@W_HDL.DM-FCI-CONN76-8R-GP-U-01(CHIPS)':
 'PCIE_RX_DP2': CDS_PINID='PCIE_RX_DP2';
NET_NAME
'P3E_CPU1_PE3_MP_RXP<3>'
 '@BASEBOARD_FAB2_LIB.BASEBOARD_FAB2(SCH_1):P3E_CPU1_PE3_MP_RXP'<3>:
 C_SIGNAL='@baseboard_fab2_lib.baseboard_fab2(sch_1):p3e_cpu1_pe3_mp_rxp(3)';
NODE_NAME     U2D1 DR18
 '@BASEBOARD_FAB2_LIB.BASEBOARD_FAB2(SCH_1):PAGE66_I84@CHPSET_LIB.SKX_EXT_B(CHIPS)':
 'PE3_RX_DP'<3>: CDS_PINID='PE3_RX_DP(3)';
NODE_NAME     J1F1 C2
 '@BASEBOARD_FAB2_LIB.BASEBOARD_FAB2(SCH_1):PAGE181_I134@W_HDL.DM-FCI-CONN76-8R-GP-U-01(CHIPS)':
 'PCIE_RX_DN3': CDS_PINID='PCIE_RX_DN3';
NET_NAME
'P3E_CPU1_PE3_MP_RXP<4>'
 '@BASEBOARD_FAB2_LIB.BASEBOARD_FAB2(SCH_1):P3E_CPU1_PE3_MP_RXP'<4>:
 C_SIGNAL='@baseboard_fab2_lib.baseboard_fab2(sch_1):p3e_cpu1_pe3_mp_rxp(4)';
NODE_NAME     U2D1 DN16
 '@BASEBOARD_FAB2_LIB.BASEBOARD_FAB2(SCH_1):PAGE66_I84@CHPSET_LIB.SKX_EXT_B(CHIPS)':
 'PE3_RX_DP'<4>: CDS_PINID='PE3_RX_DP(4)';
NODE_NAME     J1F1 F2
 '@BASEBOARD_FAB2_LIB.BASEBOARD_FAB2(SCH_1):PAGE181_I134@W_HDL.DM-FCI-CONN76-8R-GP-U-01(CHIPS)':
 'PCIE_RX_DN4': CDS_PINID='PCIE_RX_DN4';
NET_NAME
'P3E_CPU1_PE3_MP_RXP<5>'
 '@BASEBOARD_FAB2_LIB.BASEBOARD_FAB2(SCH_1):P3E_CPU1_PE3_MP_RXP'<5>:
 C_SIGNAL='@baseboard_fab2_lib.baseboard_fab2(sch_1):p3e_cpu1_pe3_mp_rxp(5)';
NODE_NAME     U2D1 DP15
 '@BASEBOARD_FAB2_LIB.BASEBOARD_FAB2(SCH_1):PAGE66_I84@CHPSET_LIB.SKX_EXT_B(CHIPS)':
 'PE3_RX_DP'<5>: CDS_PINID='PE3_RX_DP(5)';
NODE_NAME     J1F1 H2
 '@BASEBOARD_FAB2_LIB.BASEBOARD_FAB2(SCH_1):PAGE181_I134@W_HDL.DM-FCI-CONN76-8R-GP-U-01(CHIPS)':
 'PCIE_RX_DP5': CDS_PINID='PCIE_RX_DP5';
NET_NAME
'P3E_CPU1_PE3_MP_RXP<6>'
 '@BASEBOARD_FAB2_LIB.BASEBOARD_FAB2(SCH_1):P3E_CPU1_PE3_MP_RXP'<6>:
 C_SIGNAL='@baseboard_fab2_lib.baseboard_fab2(sch_1):p3e_cpu1_pe3_mp_rxp(6)';
NODE_NAME     U2D1 DM13
 '@BASEBOARD_FAB2_LIB.BASEBOARD_FAB2(SCH_1):PAGE66_I84@CHPSET_LIB.SKX_EXT_B(CHIPS)':
 'PE3_RX_DP'<6>: CDS_PINID='PE3_RX_DP(6)';
NODE_NAME     J1F1 A3
 '@BASEBOARD_FAB2_LIB.BASEBOARD_FAB2(SCH_1):PAGE181_I134@W_HDL.DM-FCI-CONN76-8R-GP-U-01(CHIPS)':
 'PCIE_RX_DP6': CDS_PINID='PCIE_RX_DP6';
NET_NAME
'P3E_CPU1_PE3_MP_RXP<7>'
 '@BASEBOARD_FAB2_LIB.BASEBOARD_FAB2(SCH_1):P3E_CPU1_PE3_MP_RXP'<7>:
 C_SIGNAL='@baseboard_fab2_lib.baseboard_fab2(sch_1):p3e_cpu1_pe3_mp_rxp(7)';
NODE_NAME     U2D1 DJ14
 '@BASEBOARD_FAB2_LIB.BASEBOARD_FAB2(SCH_1):PAGE66_I84@CHPSET_LIB.SKX_EXT_B(CHIPS)':
 'PE3_RX_DP'<7>: CDS_PINID='PE3_RX_DP(7)';
NODE_NAME     J1F1 E3
 '@BASEBOARD_FAB2_LIB.BASEBOARD_FAB2(SCH_1):PAGE181_I134@W_HDL.DM-FCI-CONN76-8R-GP-U-01(CHIPS)':
 'PCIE_RX_DN7': CDS_PINID='PCIE_RX_DN7';
NET_NAME
'P3E_CPU1_PE3_MP_RXP<8>'
 '@BASEBOARD_FAB2_LIB.BASEBOARD_FAB2(SCH_1):P3E_CPU1_PE3_MP_RXP'<8>:
 C_SIGNAL='@baseboard_fab2_lib.baseboard_fab2(sch_1):p3e_cpu1_pe3_mp_rxp(8)';
NODE_NAME     U2D1 DK13
 '@BASEBOARD_FAB2_LIB.BASEBOARD_FAB2(SCH_1):PAGE66_I84@CHPSET_LIB.SKX_EXT_B(CHIPS)':
 'PE3_RX_DP'<8>: CDS_PINID='PE3_RX_DP(8)';
NODE_NAME     J1C1 B1
 '@BASEBOARD_FAB2_LIB.BASEBOARD_FAB2(SCH_1):PAGE182_I79@W_HDL.DM-FCI-CONN76-8R-GP-U-01(CHIPS)':
 'PCIE_RX_DN0': CDS_PINID='PCIE_RX_DN0';
NET_NAME
'P3E_CPU1_PE3_MP_RXP<9>'
 '@BASEBOARD_FAB2_LIB.BASEBOARD_FAB2(SCH_1):P3E_CPU1_PE3_MP_RXP'<9>:
 C_SIGNAL='@baseboard_fab2_lib.baseboard_fab2(sch_1):p3e_cpu1_pe3_mp_rxp(9)';
NODE_NAME     U2D1 DH11
 '@BASEBOARD_FAB2_LIB.BASEBOARD_FAB2(SCH_1):PAGE66_I84@CHPSET_LIB.SKX_EXT_B(CHIPS)':
 'PE3_RX_DP'<9>: CDS_PINID='PE3_RX_DP(9)';
NODE_NAME     J1C1 E1
 '@BASEBOARD_FAB2_LIB.BASEBOARD_FAB2(SCH_1):PAGE182_I79@W_HDL.DM-FCI-CONN76-8R-GP-U-01(CHIPS)':
 'PCIE_RX_DN1': CDS_PINID='PCIE_RX_DN1';
NET_NAME
'P3E_CPU1_PE3_MP_TXN<0>'
 '@BASEBOARD_FAB2_LIB.BASEBOARD_FAB2(SCH_1):P3E_CPU1_PE3_MP_TXN'<0>:
 C_SIGNAL='@baseboard_fab2_lib.baseboard_fab2(sch_1):p3e_cpu1_pe3_mp_txn(0)';
NODE_NAME     U2D1 EE14
 '@BASEBOARD_FAB2_LIB.BASEBOARD_FAB2(SCH_1):PAGE66_I84@CHPSET_LIB.SKX_EXT_B(CHIPS)':
 'PE3_TX_DN'<0>: CDS_PINID='PE3_TX_DN(0)';
NODE_NAME     C1F20 2
 '@BASEBOARD_FAB2_LIB.BASEBOARD_FAB2(SCH_1):PAGE181_I86@MSTR_DISCRETE.CAP(CHIPS)':
 'B': CDS_PINID='B';
NET_NAME
'P3E_CPU1_PE3_MP_TXN<10>'
 '@BASEBOARD_FAB2_LIB.BASEBOARD_FAB2(SCH_1):P3E_CPU1_PE3_MP_TXN'<10>:
 C_SIGNAL='@baseboard_fab2_lib.baseboard_fab2(sch_1):p3e_cpu1_pe3_mp_txn(10)';
NODE_NAME     U2D1 DL6
 '@BASEBOARD_FAB2_LIB.BASEBOARD_FAB2(SCH_1):PAGE66_I84@CHPSET_LIB.SKX_EXT_B(CHIPS)':
 'PE3_TX_DN'<10>: CDS_PINID='PE3_TX_DN(10)';
NODE_NAME     C9N2 2
 '@BASEBOARD_FAB2_LIB.BASEBOARD_FAB2(SCH_1):PAGE182_I36@MSTR_DISCRETE.CAP(CHIPS)':
 'B': CDS_PINID='B';
NET_NAME
'P3E_CPU1_PE3_MP_TXN<11>'
 '@BASEBOARD_FAB2_LIB.BASEBOARD_FAB2(SCH_1):P3E_CPU1_PE3_MP_TXN'<11>:
 C_SIGNAL='@baseboard_fab2_lib.baseboard_fab2(sch_1):p3e_cpu1_pe3_mp_txn(11)';
NODE_NAME     U2D1 DJ4
 '@BASEBOARD_FAB2_LIB.BASEBOARD_FAB2(SCH_1):PAGE66_I84@CHPSET_LIB.SKX_EXT_B(CHIPS)':
 'PE3_TX_DN'<11>: CDS_PINID='PE3_TX_DN(11)';
NODE_NAME     C9N3 2
 '@BASEBOARD_FAB2_LIB.BASEBOARD_FAB2(SCH_1):PAGE182_I47@MSTR_DISCRETE.CAP(CHIPS)':
 'B': CDS_PINID='B';
NET_NAME
'P3E_CPU1_PE3_MP_TXN<12>'
 '@BASEBOARD_FAB2_LIB.BASEBOARD_FAB2(SCH_1):P3E_CPU1_PE3_MP_TXN'<12>:
 C_SIGNAL='@baseboard_fab2_lib.baseboard_fab2(sch_1):p3e_cpu1_pe3_mp_txn(12)';
NODE_NAME     U2D1 DJ6
 '@BASEBOARD_FAB2_LIB.BASEBOARD_FAB2(SCH_1):PAGE66_I84@CHPSET_LIB.SKX_EXT_B(CHIPS)':
 'PE3_TX_DN'<12>: CDS_PINID='PE3_TX_DN(12)';
NODE_NAME     C9N16 2
 '@BASEBOARD_FAB2_LIB.BASEBOARD_FAB2(SCH_1):PAGE182_I46@MSTR_DISCRETE.CAP(CHIPS)':
 'B': CDS_PINID='B';
NET_NAME
'P3E_CPU1_PE3_MP_TXN<13>'
 '@BASEBOARD_FAB2_LIB.BASEBOARD_FAB2(SCH_1):P3E_CPU1_PE3_MP_TXN'<13>:
 C_SIGNAL='@baseboard_fab2_lib.baseboard_fab2(sch_1):p3e_cpu1_pe3_mp_txn(13)';
NODE_NAME     U2D1 DD5
 '@BASEBOARD_FAB2_LIB.BASEBOARD_FAB2(SCH_1):PAGE66_I84@CHPSET_LIB.SKX_EXT_B(CHIPS)':
 'PE3_TX_DN'<13>: CDS_PINID='PE3_TX_DN(13)';
NODE_NAME     C9N6 2
 '@BASEBOARD_FAB2_LIB.BASEBOARD_FAB2(SCH_1):PAGE182_I42@MSTR_DISCRETE.CAP(CHIPS)':
 'B': CDS_PINID='B';
NET_NAME
'P3E_CPU1_PE3_MP_TXN<14>'
 '@BASEBOARD_FAB2_LIB.BASEBOARD_FAB2(SCH_1):P3E_CPU1_PE3_MP_TXN'<14>:
 C_SIGNAL='@baseboard_fab2_lib.baseboard_fab2(sch_1):p3e_cpu1_pe3_mp_txn(14)';
NODE_NAME     U2D1 DB5
 '@BASEBOARD_FAB2_LIB.BASEBOARD_FAB2(SCH_1):PAGE66_I84@CHPSET_LIB.SKX_EXT_B(CHIPS)':
 'PE3_TX_DN'<14>: CDS_PINID='PE3_TX_DN(14)';
NODE_NAME     C9N8 2
 '@BASEBOARD_FAB2_LIB.BASEBOARD_FAB2(SCH_1):PAGE182_I53@MSTR_DISCRETE.CAP(CHIPS)':
 'B': CDS_PINID='B';
NET_NAME
'P3E_CPU1_PE3_MP_TXN<15>'
 '@BASEBOARD_FAB2_LIB.BASEBOARD_FAB2(SCH_1):P3E_CPU1_PE3_MP_TXN'<15>:
 C_SIGNAL='@baseboard_fab2_lib.baseboard_fab2(sch_1):p3e_cpu1_pe3_mp_txn(15)';
NODE_NAME     U2D1 CY5
 '@BASEBOARD_FAB2_LIB.BASEBOARD_FAB2(SCH_1):PAGE66_I84@CHPSET_LIB.SKX_EXT_B(CHIPS)':
 'PE3_TX_DN'<15>: CDS_PINID='PE3_TX_DN(15)';
NODE_NAME     C9N9 2
 '@BASEBOARD_FAB2_LIB.BASEBOARD_FAB2(SCH_1):PAGE182_I52@MSTR_DISCRETE.CAP(CHIPS)':
 'B': CDS_PINID='B';
NET_NAME
'P3E_CPU1_PE3_MP_TXN<1>'
 '@BASEBOARD_FAB2_LIB.BASEBOARD_FAB2(SCH_1):P3E_CPU1_PE3_MP_TXN'<1>:
 C_SIGNAL='@baseboard_fab2_lib.baseboard_fab2(sch_1):p3e_cpu1_pe3_mp_txn(1)';
NODE_NAME     U2D1 EE12
 '@BASEBOARD_FAB2_LIB.BASEBOARD_FAB2(SCH_1):PAGE66_I84@CHPSET_LIB.SKX_EXT_B(CHIPS)':
 'PE3_TX_DN'<1>: CDS_PINID='PE3_TX_DN(1)';
NODE_NAME     C1F16 2
 '@BASEBOARD_FAB2_LIB.BASEBOARD_FAB2(SCH_1):PAGE181_I79@MSTR_DISCRETE.CAP(CHIPS)':
 'B': CDS_PINID='B';
NET_NAME
'P3E_CPU1_PE3_MP_TXN<2>'
 '@BASEBOARD_FAB2_LIB.BASEBOARD_FAB2(SCH_1):P3E_CPU1_PE3_MP_TXN'<2>:
 C_SIGNAL='@baseboard_fab2_lib.baseboard_fab2(sch_1):p3e_cpu1_pe3_mp_txn(2)';
NODE_NAME     U2D1 EC12
 '@BASEBOARD_FAB2_LIB.BASEBOARD_FAB2(SCH_1):PAGE66_I84@CHPSET_LIB.SKX_EXT_B(CHIPS)':
 'PE3_TX_DN'<2>: CDS_PINID='PE3_TX_DN(2)';
NODE_NAME     C1F15 2
 '@BASEBOARD_FAB2_LIB.BASEBOARD_FAB2(SCH_1):PAGE181_I78@MSTR_DISCRETE.CAP(CHIPS)':
 'B': CDS_PINID='B';
NET_NAME
'P3E_CPU1_PE3_MP_TXN<3>'
 '@BASEBOARD_FAB2_LIB.BASEBOARD_FAB2(SCH_1):P3E_CPU1_PE3_MP_TXN'<3>:
 C_SIGNAL='@baseboard_fab2_lib.baseboard_fab2(sch_1):p3e_cpu1_pe3_mp_txn(3)';
NODE_NAME     U2D1 DY11
 '@BASEBOARD_FAB2_LIB.BASEBOARD_FAB2(SCH_1):PAGE66_I84@CHPSET_LIB.SKX_EXT_B(CHIPS)':
 'PE3_TX_DN'<3>: CDS_PINID='PE3_TX_DN(3)';
NODE_NAME     C1F13 2
 '@BASEBOARD_FAB2_LIB.BASEBOARD_FAB2(SCH_1):PAGE181_I89@MSTR_DISCRETE.CAP(CHIPS)':
 'B': CDS_PINID='B';
NET_NAME
'P3E_CPU1_PE3_MP_TXN<4>'
 '@BASEBOARD_FAB2_LIB.BASEBOARD_FAB2(SCH_1):P3E_CPU1_PE3_MP_TXN'<4>:
 C_SIGNAL='@baseboard_fab2_lib.baseboard_fab2(sch_1):p3e_cpu1_pe3_mp_txn(4)';
NODE_NAME     U2D1 EB9
 '@BASEBOARD_FAB2_LIB.BASEBOARD_FAB2(SCH_1):PAGE66_I84@CHPSET_LIB.SKX_EXT_B(CHIPS)':
 'PE3_TX_DN'<4>: CDS_PINID='PE3_TX_DN(4)';
NODE_NAME     C1F10 2
 '@BASEBOARD_FAB2_LIB.BASEBOARD_FAB2(SCH_1):PAGE181_I87@MSTR_DISCRETE.CAP(CHIPS)':
 'B': CDS_PINID='B';
NET_NAME
'P3E_CPU1_PE3_MP_TXN<5>'
 '@BASEBOARD_FAB2_LIB.BASEBOARD_FAB2(SCH_1):P3E_CPU1_PE3_MP_TXN'<5>:
 C_SIGNAL='@baseboard_fab2_lib.baseboard_fab2(sch_1):p3e_cpu1_pe3_mp_txn(5)';
NODE_NAME     U2D1 DW10
 '@BASEBOARD_FAB2_LIB.BASEBOARD_FAB2(SCH_1):PAGE66_I84@CHPSET_LIB.SKX_EXT_B(CHIPS)':
 'PE3_TX_DN'<5>: CDS_PINID='PE3_TX_DN(5)';
NODE_NAME     C1F8 2
 '@BASEBOARD_FAB2_LIB.BASEBOARD_FAB2(SCH_1):PAGE181_I73@MSTR_DISCRETE.CAP(CHIPS)':
 'B': CDS_PINID='B';
NET_NAME
'P3E_CPU1_PE3_MP_TXN<6>'
 '@BASEBOARD_FAB2_LIB.BASEBOARD_FAB2(SCH_1):P3E_CPU1_PE3_MP_TXN'<6>:
 C_SIGNAL='@baseboard_fab2_lib.baseboard_fab2(sch_1):p3e_cpu1_pe3_mp_txn(6)';
NODE_NAME     U2D1 DU8
 '@BASEBOARD_FAB2_LIB.BASEBOARD_FAB2(SCH_1):PAGE66_I84@CHPSET_LIB.SKX_EXT_B(CHIPS)':
 'PE3_TX_DN'<6>: CDS_PINID='PE3_TX_DN(6)';
NODE_NAME     C1F4 2
 '@BASEBOARD_FAB2_LIB.BASEBOARD_FAB2(SCH_1):PAGE181_I91@MSTR_DISCRETE.CAP(CHIPS)':
 'B': CDS_PINID='B';
NET_NAME
'P3E_CPU1_PE3_MP_TXN<7>'
 '@BASEBOARD_FAB2_LIB.BASEBOARD_FAB2(SCH_1):P3E_CPU1_PE3_MP_TXN'<7>:
 C_SIGNAL='@baseboard_fab2_lib.baseboard_fab2(sch_1):p3e_cpu1_pe3_mp_txn(7)';
NODE_NAME     U2D1 DR8
 '@BASEBOARD_FAB2_LIB.BASEBOARD_FAB2(SCH_1):PAGE66_I84@CHPSET_LIB.SKX_EXT_B(CHIPS)':
 'PE3_TX_DN'<7>: CDS_PINID='PE3_TX_DN(7)';
NODE_NAME     C1F3 2
 '@BASEBOARD_FAB2_LIB.BASEBOARD_FAB2(SCH_1):PAGE181_I76@MSTR_DISCRETE.CAP(CHIPS)':
 'B': CDS_PINID='B';
NET_NAME
'P3E_CPU1_PE3_MP_TXN<8>'
 '@BASEBOARD_FAB2_LIB.BASEBOARD_FAB2(SCH_1):P3E_CPU1_PE3_MP_TXN'<8>:
 C_SIGNAL='@baseboard_fab2_lib.baseboard_fab2(sch_1):p3e_cpu1_pe3_mp_txn(8)';
NODE_NAME     U2D1 DM7
 '@BASEBOARD_FAB2_LIB.BASEBOARD_FAB2(SCH_1):PAGE66_I84@CHPSET_LIB.SKX_EXT_B(CHIPS)':
 'PE3_TX_DN'<8>: CDS_PINID='PE3_TX_DN(8)';
NODE_NAME     C9N18 2
 '@BASEBOARD_FAB2_LIB.BASEBOARD_FAB2(SCH_1):PAGE182_I39@MSTR_DISCRETE.CAP(CHIPS)':
 'B': CDS_PINID='B';
NET_NAME
'P3E_CPU1_PE3_MP_TXN<9>'
 '@BASEBOARD_FAB2_LIB.BASEBOARD_FAB2(SCH_1):P3E_CPU1_PE3_MP_TXN'<9>:
 C_SIGNAL='@baseboard_fab2_lib.baseboard_fab2(sch_1):p3e_cpu1_pe3_mp_txn(9)';
NODE_NAME     U2D1 DP5
 '@BASEBOARD_FAB2_LIB.BASEBOARD_FAB2(SCH_1):PAGE66_I84@CHPSET_LIB.SKX_EXT_B(CHIPS)':
 'PE3_TX_DN'<9>: CDS_PINID='PE3_TX_DN(9)';
NODE_NAME     C9N15 2
 '@BASEBOARD_FAB2_LIB.BASEBOARD_FAB2(SCH_1):PAGE182_I41@MSTR_DISCRETE.CAP(CHIPS)':
 'B': CDS_PINID='B';
NET_NAME
'P3E_CPU1_PE3_MP_TXP<0>'
 '@BASEBOARD_FAB2_LIB.BASEBOARD_FAB2(SCH_1):P3E_CPU1_PE3_MP_TXP'<0>:
 C_SIGNAL='@baseboard_fab2_lib.baseboard_fab2(sch_1):p3e_cpu1_pe3_mp_txp(0)';
NODE_NAME     U2D1 EC14
 '@BASEBOARD_FAB2_LIB.BASEBOARD_FAB2(SCH_1):PAGE66_I84@CHPSET_LIB.SKX_EXT_B(CHIPS)':
 'PE3_TX_DP'<0>: CDS_PINID='PE3_TX_DP(0)';
NODE_NAME     C1F18 2
 '@BASEBOARD_FAB2_LIB.BASEBOARD_FAB2(SCH_1):PAGE181_I72@MSTR_DISCRETE.CAP(CHIPS)':
 'B': CDS_PINID='B';
NET_NAME
'P3E_CPU1_PE3_MP_TXP<10>'
 '@BASEBOARD_FAB2_LIB.BASEBOARD_FAB2(SCH_1):P3E_CPU1_PE3_MP_TXP'<10>:
 C_SIGNAL='@baseboard_fab2_lib.baseboard_fab2(sch_1):p3e_cpu1_pe3_mp_txp(10)';
NODE_NAME     U2D1 DK5
 '@BASEBOARD_FAB2_LIB.BASEBOARD_FAB2(SCH_1):PAGE66_I84@CHPSET_LIB.SKX_EXT_B(CHIPS)':
 'PE3_TX_DP'<10>: CDS_PINID='PE3_TX_DP(10)';
NODE_NAME     C9N1 2
 '@BASEBOARD_FAB2_LIB.BASEBOARD_FAB2(SCH_1):PAGE182_I40@MSTR_DISCRETE.CAP(CHIPS)':
 'B': CDS_PINID='B';
NET_NAME
'P3E_CPU1_PE3_MP_TXP<11>'
 '@BASEBOARD_FAB2_LIB.BASEBOARD_FAB2(SCH_1):P3E_CPU1_PE3_MP_TXP'<11>:
 C_SIGNAL='@baseboard_fab2_lib.baseboard_fab2(sch_1):p3e_cpu1_pe3_mp_txp(11)';
NODE_NAME     U2D1 DH5
 '@BASEBOARD_FAB2_LIB.BASEBOARD_FAB2(SCH_1):PAGE66_I84@CHPSET_LIB.SKX_EXT_B(CHIPS)':
 'PE3_TX_DP'<11>: CDS_PINID='PE3_TX_DP(11)';
NODE_NAME     C9N4 2
 '@BASEBOARD_FAB2_LIB.BASEBOARD_FAB2(SCH_1):PAGE182_I44@MSTR_DISCRETE.CAP(CHIPS)':
 'B': CDS_PINID='B';
NET_NAME
'P3E_CPU1_PE3_MP_TXP<12>'
 '@BASEBOARD_FAB2_LIB.BASEBOARD_FAB2(SCH_1):P3E_CPU1_PE3_MP_TXP'<12>:
 C_SIGNAL='@baseboard_fab2_lib.baseboard_fab2(sch_1):p3e_cpu1_pe3_mp_txp(12)';
NODE_NAME     U2D1 DG6
 '@BASEBOARD_FAB2_LIB.BASEBOARD_FAB2(SCH_1):PAGE66_I84@CHPSET_LIB.SKX_EXT_B(CHIPS)':
 'PE3_TX_DP'<12>: CDS_PINID='PE3_TX_DP(12)';
NODE_NAME     C9N14 2
 '@BASEBOARD_FAB2_LIB.BASEBOARD_FAB2(SCH_1):PAGE182_I43@MSTR_DISCRETE.CAP(CHIPS)':
 'B': CDS_PINID='B';
NET_NAME
'P3E_CPU1_PE3_MP_TXP<13>'
 '@BASEBOARD_FAB2_LIB.BASEBOARD_FAB2(SCH_1):P3E_CPU1_PE3_MP_TXP'<13>:
 C_SIGNAL='@baseboard_fab2_lib.baseboard_fab2(sch_1):p3e_cpu1_pe3_mp_txp(13)';
NODE_NAME     U2D1 DC6
 '@BASEBOARD_FAB2_LIB.BASEBOARD_FAB2(SCH_1):PAGE66_I84@CHPSET_LIB.SKX_EXT_B(CHIPS)':
 'PE3_TX_DP'<13>: CDS_PINID='PE3_TX_DP(13)';
NODE_NAME     C9N5 2
 '@BASEBOARD_FAB2_LIB.BASEBOARD_FAB2(SCH_1):PAGE182_I45@MSTR_DISCRETE.CAP(CHIPS)':
 'B': CDS_PINID='B';
NET_NAME
'P3E_CPU1_PE3_MP_TXP<14>'
 '@BASEBOARD_FAB2_LIB.BASEBOARD_FAB2(SCH_1):P3E_CPU1_PE3_MP_TXP'<14>:
 C_SIGNAL='@baseboard_fab2_lib.baseboard_fab2(sch_1):p3e_cpu1_pe3_mp_txp(14)';
NODE_NAME     U2D1 DA4
 '@BASEBOARD_FAB2_LIB.BASEBOARD_FAB2(SCH_1):PAGE66_I84@CHPSET_LIB.SKX_EXT_B(CHIPS)':
 'PE3_TX_DP'<14>: CDS_PINID='PE3_TX_DP(14)';
NODE_NAME     C9N10 2
 '@BASEBOARD_FAB2_LIB.BASEBOARD_FAB2(SCH_1):PAGE182_I49@MSTR_DISCRETE.CAP(CHIPS)':
 'B': CDS_PINID='B';
NET_NAME
'P3E_CPU1_PE3_MP_TXP<15>'
 '@BASEBOARD_FAB2_LIB.BASEBOARD_FAB2(SCH_1):P3E_CPU1_PE3_MP_TXP'<15>:
 C_SIGNAL='@baseboard_fab2_lib.baseboard_fab2(sch_1):p3e_cpu1_pe3_mp_txp(15)';
NODE_NAME     U2D1 CV5
 '@BASEBOARD_FAB2_LIB.BASEBOARD_FAB2(SCH_1):PAGE66_I84@CHPSET_LIB.SKX_EXT_B(CHIPS)':
 'PE3_TX_DP'<15>: CDS_PINID='PE3_TX_DP(15)';
NODE_NAME     C9N7 2
 '@BASEBOARD_FAB2_LIB.BASEBOARD_FAB2(SCH_1):PAGE182_I48@MSTR_DISCRETE.CAP(CHIPS)':
 'B': CDS_PINID='B';
NET_NAME
'P3E_CPU1_PE3_MP_TXP<1>'
 '@BASEBOARD_FAB2_LIB.BASEBOARD_FAB2(SCH_1):P3E_CPU1_PE3_MP_TXP'<1>:
 C_SIGNAL='@baseboard_fab2_lib.baseboard_fab2(sch_1):p3e_cpu1_pe3_mp_txp(1)';
NODE_NAME     U2D1 ED13
 '@BASEBOARD_FAB2_LIB.BASEBOARD_FAB2(SCH_1):PAGE66_I84@CHPSET_LIB.SKX_EXT_B(CHIPS)':
 'PE3_TX_DP'<1>: CDS_PINID='PE3_TX_DP(1)';
NODE_NAME     C1F17 2
 '@BASEBOARD_FAB2_LIB.BASEBOARD_FAB2(SCH_1):PAGE181_I71@MSTR_DISCRETE.CAP(CHIPS)':
 'B': CDS_PINID='B';
NET_NAME
'P3E_CPU1_PE3_MP_TXP<2>'
 '@BASEBOARD_FAB2_LIB.BASEBOARD_FAB2(SCH_1):P3E_CPU1_PE3_MP_TXP'<2>:
 C_SIGNAL='@baseboard_fab2_lib.baseboard_fab2(sch_1):p3e_cpu1_pe3_mp_txp(2)';
NODE_NAME     U2D1 EB11
 '@BASEBOARD_FAB2_LIB.BASEBOARD_FAB2(SCH_1):PAGE66_I84@CHPSET_LIB.SKX_EXT_B(CHIPS)':
 'PE3_TX_DP'<2>: CDS_PINID='PE3_TX_DP(2)';
NODE_NAME     C1F14 2
 '@BASEBOARD_FAB2_LIB.BASEBOARD_FAB2(SCH_1):PAGE181_I70@MSTR_DISCRETE.CAP(CHIPS)':
 'B': CDS_PINID='B';
NET_NAME
'P3E_CPU1_PE3_MP_TXP<3>'
 '@BASEBOARD_FAB2_LIB.BASEBOARD_FAB2(SCH_1):P3E_CPU1_PE3_MP_TXP'<3>:
 C_SIGNAL='@baseboard_fab2_lib.baseboard_fab2(sch_1):p3e_cpu1_pe3_mp_txp(3)';
NODE_NAME     U2D1 EA10
 '@BASEBOARD_FAB2_LIB.BASEBOARD_FAB2(SCH_1):PAGE66_I84@CHPSET_LIB.SKX_EXT_B(CHIPS)':
 'PE3_TX_DP'<3>: CDS_PINID='PE3_TX_DP(3)';
NODE_NAME     C1F12 2
 '@BASEBOARD_FAB2_LIB.BASEBOARD_FAB2(SCH_1):PAGE181_I75@MSTR_DISCRETE.CAP(CHIPS)':
 'B': CDS_PINID='B';
NET_NAME
'P3E_CPU1_PE3_MP_TXP<4>'
 '@BASEBOARD_FAB2_LIB.BASEBOARD_FAB2(SCH_1):P3E_CPU1_PE3_MP_TXP'<4>:
 C_SIGNAL='@baseboard_fab2_lib.baseboard_fab2(sch_1):p3e_cpu1_pe3_mp_txp(4)';
NODE_NAME     U2D1 DY9
 '@BASEBOARD_FAB2_LIB.BASEBOARD_FAB2(SCH_1):PAGE66_I84@CHPSET_LIB.SKX_EXT_B(CHIPS)':
 'PE3_TX_DP'<4>: CDS_PINID='PE3_TX_DP(4)';
NODE_NAME     C1F11 2
 '@BASEBOARD_FAB2_LIB.BASEBOARD_FAB2(SCH_1):PAGE181_I74@MSTR_DISCRETE.CAP(CHIPS)':
 'B': CDS_PINID='B';
NET_NAME
'P3E_CPU1_PE3_MP_TXP<5>'
 '@BASEBOARD_FAB2_LIB.BASEBOARD_FAB2(SCH_1):P3E_CPU1_PE3_MP_TXP'<5>:
 C_SIGNAL='@baseboard_fab2_lib.baseboard_fab2(sch_1):p3e_cpu1_pe3_mp_txp(5)';
NODE_NAME     U2D1 DV9
 '@BASEBOARD_FAB2_LIB.BASEBOARD_FAB2(SCH_1):PAGE66_I84@CHPSET_LIB.SKX_EXT_B(CHIPS)':
 'PE3_TX_DP'<5>: CDS_PINID='PE3_TX_DP(5)';
NODE_NAME     C1F6 2
 '@BASEBOARD_FAB2_LIB.BASEBOARD_FAB2(SCH_1):PAGE181_I88@MSTR_DISCRETE.CAP(CHIPS)':
 'B': CDS_PINID='B';
NET_NAME
'P3E_CPU1_PE3_MP_TXP<6>'
 '@BASEBOARD_FAB2_LIB.BASEBOARD_FAB2(SCH_1):P3E_CPU1_PE3_MP_TXP'<6>:
 C_SIGNAL='@baseboard_fab2_lib.baseboard_fab2(sch_1):p3e_cpu1_pe3_mp_txp(6)';
NODE_NAME     U2D1 DT9
 '@BASEBOARD_FAB2_LIB.BASEBOARD_FAB2(SCH_1):PAGE66_I84@CHPSET_LIB.SKX_EXT_B(CHIPS)':
 'PE3_TX_DP'<6>: CDS_PINID='PE3_TX_DP(6)';
NODE_NAME     C1F5 2
 '@BASEBOARD_FAB2_LIB.BASEBOARD_FAB2(SCH_1):PAGE181_I77@MSTR_DISCRETE.CAP(CHIPS)':
 'B': CDS_PINID='B';
NET_NAME
'P3E_CPU1_PE3_MP_TXP<7>'
 '@BASEBOARD_FAB2_LIB.BASEBOARD_FAB2(SCH_1):P3E_CPU1_PE3_MP_TXP'<7>:
 C_SIGNAL='@baseboard_fab2_lib.baseboard_fab2(sch_1):p3e_cpu1_pe3_mp_txp(7)';
NODE_NAME     U2D1 DP7
 '@BASEBOARD_FAB2_LIB.BASEBOARD_FAB2(SCH_1):PAGE66_I84@CHPSET_LIB.SKX_EXT_B(CHIPS)':
 'PE3_TX_DP'<7>: CDS_PINID='PE3_TX_DP(7)';
NODE_NAME     C1F2 2
 '@BASEBOARD_FAB2_LIB.BASEBOARD_FAB2(SCH_1):PAGE181_I90@MSTR_DISCRETE.CAP(CHIPS)':
 'B': CDS_PINID='B';
NET_NAME
'P3E_CPU1_PE3_MP_TXP<8>'
 '@BASEBOARD_FAB2_LIB.BASEBOARD_FAB2(SCH_1):P3E_CPU1_PE3_MP_TXP'<8>:
 C_SIGNAL='@baseboard_fab2_lib.baseboard_fab2(sch_1):p3e_cpu1_pe3_mp_txp(8)';
NODE_NAME     U2D1 DN6
 '@BASEBOARD_FAB2_LIB.BASEBOARD_FAB2(SCH_1):PAGE66_I84@CHPSET_LIB.SKX_EXT_B(CHIPS)':
 'PE3_TX_DP'<8>: CDS_PINID='PE3_TX_DP(8)';
NODE_NAME     C9N17 2
 '@BASEBOARD_FAB2_LIB.BASEBOARD_FAB2(SCH_1):PAGE182_I38@MSTR_DISCRETE.CAP(CHIPS)':
 'B': CDS_PINID='B';
NET_NAME
'P3E_CPU1_PE3_MP_TXP<9>'
 '@BASEBOARD_FAB2_LIB.BASEBOARD_FAB2(SCH_1):P3E_CPU1_PE3_MP_TXP'<9>:
 C_SIGNAL='@baseboard_fab2_lib.baseboard_fab2(sch_1):p3e_cpu1_pe3_mp_txp(9)';
NODE_NAME     U2D1 DM5
 '@BASEBOARD_FAB2_LIB.BASEBOARD_FAB2(SCH_1):PAGE66_I84@CHPSET_LIB.SKX_EXT_B(CHIPS)':
 'PE3_TX_DP'<9>: CDS_PINID='PE3_TX_DP(9)';
NODE_NAME     C9N12 2
 '@BASEBOARD_FAB2_LIB.BASEBOARD_FAB2(SCH_1):PAGE182_I37@MSTR_DISCRETE.CAP(CHIPS)':
 'B': CDS_PINID='B';
NET_NAME
'P3E_OCP_CPU0_PE3_C_TXN<0>'
 '@BASEBOARD_FAB2_LIB.BASEBOARD_FAB2(SCH_1):P3E_OCP_CPU0_PE3_C_TXN'<0>:
 C_SIGNAL='@baseboard_fab2_lib.baseboard_fab2(sch_1):p3e_ocp_cpu0_pe3_c_txn(0)';
NODE_NAME     C1R1 2
 '@BASEBOARD_FAB2_LIB.BASEBOARD_FAB2(SCH_1):PAGE106_I29@MSTR_DISCRETE.CAP(CHIPS)':
 'B': CDS_PINID='B';
NODE_NAME     J8E3 68
 '@BASEBOARD_FAB2_LIB.BASEBOARD_FAB2(SCH_1):PAGE187_I119@MSTR_SCONN.SCONN80_E67482007(CHIPS)':
 'IO68': CDS_PINID='IO68';
NET_NAME
'P3E_OCP_CPU0_PE3_C_TXN<10>'
 '@BASEBOARD_FAB2_LIB.BASEBOARD_FAB2(SCH_1):P3E_OCP_CPU0_PE3_C_TXN'<10>:
 C_SIGNAL='@baseboard_fab2_lib.baseboard_fab2(sch_1):p3e_ocp_cpu0_pe3_c_txn(10)';
NODE_NAME     C1M17 2
 '@BASEBOARD_FAB2_LIB.BASEBOARD_FAB2(SCH_1):PAGE106_I92@MSTR_DISCRETE.CAP(CHIPS)':
 'B': CDS_PINID='B';
NODE_NAME     J9B3 98
 '@BASEBOARD_FAB2_LIB.BASEBOARD_FAB2(SCH_1):PAGE186_I336@MSTR_SCONN.SCONN120_A28699018(CHIPS)':
 'IO98': CDS_PINID='IO98';
NET_NAME
'P3E_OCP_CPU0_PE3_C_TXN<11>'
 '@BASEBOARD_FAB2_LIB.BASEBOARD_FAB2(SCH_1):P3E_OCP_CPU0_PE3_C_TXN'<11>:
 C_SIGNAL='@baseboard_fab2_lib.baseboard_fab2(sch_1):p3e_ocp_cpu0_pe3_c_txn(11)';
NODE_NAME     C1M15 2
 '@BASEBOARD_FAB2_LIB.BASEBOARD_FAB2(SCH_1):PAGE106_I95@MSTR_DISCRETE.CAP(CHIPS)':
 'B': CDS_PINID='B';
NODE_NAME     J9B3 90
 '@BASEBOARD_FAB2_LIB.BASEBOARD_FAB2(SCH_1):PAGE186_I336@MSTR_SCONN.SCONN120_A28699018(CHIPS)':
 'IO90': CDS_PINID='IO90';
NET_NAME
'P3E_OCP_CPU0_PE3_C_TXN<12>'
 '@BASEBOARD_FAB2_LIB.BASEBOARD_FAB2(SCH_1):P3E_OCP_CPU0_PE3_C_TXN'<12>:
 C_SIGNAL='@baseboard_fab2_lib.baseboard_fab2(sch_1):p3e_ocp_cpu0_pe3_c_txn(12)';
NODE_NAME     C1M13 2
 '@BASEBOARD_FAB2_LIB.BASEBOARD_FAB2(SCH_1):PAGE106_I111@MSTR_DISCRETE.CAP(CHIPS)':
 'B': CDS_PINID='B';
NODE_NAME     J9B3 82
 '@BASEBOARD_FAB2_LIB.BASEBOARD_FAB2(SCH_1):PAGE186_I336@MSTR_SCONN.SCONN120_A28699018(CHIPS)':
 'IO82': CDS_PINID='IO82';
NET_NAME
'P3E_OCP_CPU0_PE3_C_TXN<13>'
 '@BASEBOARD_FAB2_LIB.BASEBOARD_FAB2(SCH_1):P3E_OCP_CPU0_PE3_C_TXN'<13>:
 C_SIGNAL='@baseboard_fab2_lib.baseboard_fab2(sch_1):p3e_ocp_cpu0_pe3_c_txn(13)';
NODE_NAME     C1M11 2
 '@BASEBOARD_FAB2_LIB.BASEBOARD_FAB2(SCH_1):PAGE106_I117@MSTR_DISCRETE.CAP(CHIPS)':
 'B': CDS_PINID='B';
NODE_NAME     J9B3 74
 '@BASEBOARD_FAB2_LIB.BASEBOARD_FAB2(SCH_1):PAGE186_I336@MSTR_SCONN.SCONN120_A28699018(CHIPS)':
 'IO74': CDS_PINID='IO74';
NET_NAME
'P3E_OCP_CPU0_PE3_C_TXN<14>'
 '@BASEBOARD_FAB2_LIB.BASEBOARD_FAB2(SCH_1):P3E_OCP_CPU0_PE3_C_TXN'<14>:
 C_SIGNAL='@baseboard_fab2_lib.baseboard_fab2(sch_1):p3e_ocp_cpu0_pe3_c_txn(14)';
NODE_NAME     C1M9 2
 '@BASEBOARD_FAB2_LIB.BASEBOARD_FAB2(SCH_1):PAGE106_I114@MSTR_DISCRETE.CAP(CHIPS)':
 'B': CDS_PINID='B';
NODE_NAME     J9B3 66
 '@BASEBOARD_FAB2_LIB.BASEBOARD_FAB2(SCH_1):PAGE186_I336@MSTR_SCONN.SCONN120_A28699018(CHIPS)':
 'IO66': CDS_PINID='IO66';
NET_NAME
'P3E_OCP_CPU0_PE3_C_TXN<15>'
 '@BASEBOARD_FAB2_LIB.BASEBOARD_FAB2(SCH_1):P3E_OCP_CPU0_PE3_C_TXN'<15>:
 C_SIGNAL='@baseboard_fab2_lib.baseboard_fab2(sch_1):p3e_ocp_cpu0_pe3_c_txn(15)';
NODE_NAME     C1M7 2
 '@BASEBOARD_FAB2_LIB.BASEBOARD_FAB2(SCH_1):PAGE106_I122@MSTR_DISCRETE.CAP(CHIPS)':
 'B': CDS_PINID='B';
NODE_NAME     J9B3 58
 '@BASEBOARD_FAB2_LIB.BASEBOARD_FAB2(SCH_1):PAGE186_I336@MSTR_SCONN.SCONN120_A28699018(CHIPS)':
 'IO58': CDS_PINID='IO58';
NET_NAME
'P3E_OCP_CPU0_PE3_C_TXN<1>'
 '@BASEBOARD_FAB2_LIB.BASEBOARD_FAB2(SCH_1):P3E_OCP_CPU0_PE3_C_TXN'<1>:
 C_SIGNAL='@baseboard_fab2_lib.baseboard_fab2(sch_1):p3e_ocp_cpu0_pe3_c_txn(1)';
NODE_NAME     C1R3 2
 '@BASEBOARD_FAB2_LIB.BASEBOARD_FAB2(SCH_1):PAGE106_I37@MSTR_DISCRETE.CAP(CHIPS)':
 'B': CDS_PINID='B';
NODE_NAME     J8E3 60
 '@BASEBOARD_FAB2_LIB.BASEBOARD_FAB2(SCH_1):PAGE187_I119@MSTR_SCONN.SCONN80_E67482007(CHIPS)':
 'IO60': CDS_PINID='IO60';
NET_NAME
'P3E_OCP_CPU0_PE3_C_TXN<2>'
 '@BASEBOARD_FAB2_LIB.BASEBOARD_FAB2(SCH_1):P3E_OCP_CPU0_PE3_C_TXN'<2>:
 C_SIGNAL='@baseboard_fab2_lib.baseboard_fab2(sch_1):p3e_ocp_cpu0_pe3_c_txn(2)';
NODE_NAME     C1R5 2
 '@BASEBOARD_FAB2_LIB.BASEBOARD_FAB2(SCH_1):PAGE106_I59@MSTR_DISCRETE.CAP(CHIPS)':
 'B': CDS_PINID='B';
NODE_NAME     J8E3 52
 '@BASEBOARD_FAB2_LIB.BASEBOARD_FAB2(SCH_1):PAGE187_I119@MSTR_SCONN.SCONN80_E67482007(CHIPS)':
 'IO52': CDS_PINID='IO52';
NET_NAME
'P3E_OCP_CPU0_PE3_C_TXN<3>'
 '@BASEBOARD_FAB2_LIB.BASEBOARD_FAB2(SCH_1):P3E_OCP_CPU0_PE3_C_TXN'<3>:
 C_SIGNAL='@baseboard_fab2_lib.baseboard_fab2(sch_1):p3e_ocp_cpu0_pe3_c_txn(3)';
NODE_NAME     C1R7 2
 '@BASEBOARD_FAB2_LIB.BASEBOARD_FAB2(SCH_1):PAGE106_I70@MSTR_DISCRETE.CAP(CHIPS)':
 'B': CDS_PINID='B';
NODE_NAME     J8E3 44
 '@BASEBOARD_FAB2_LIB.BASEBOARD_FAB2(SCH_1):PAGE187_I119@MSTR_SCONN.SCONN80_E67482007(CHIPS)':
 'IO44': CDS_PINID='IO44';
NET_NAME
'P3E_OCP_CPU0_PE3_C_TXN<4>'
 '@BASEBOARD_FAB2_LIB.BASEBOARD_FAB2(SCH_1):P3E_OCP_CPU0_PE3_C_TXN'<4>:
 C_SIGNAL='@baseboard_fab2_lib.baseboard_fab2(sch_1):p3e_ocp_cpu0_pe3_c_txn(4)';
NODE_NAME     C1R9 2
 '@BASEBOARD_FAB2_LIB.BASEBOARD_FAB2(SCH_1):PAGE106_I134@MSTR_DISCRETE.CAP(CHIPS)':
 'B': CDS_PINID='B';
NODE_NAME     J8E3 36
 '@BASEBOARD_FAB2_LIB.BASEBOARD_FAB2(SCH_1):PAGE187_I119@MSTR_SCONN.SCONN80_E67482007(CHIPS)':
 'IO36': CDS_PINID='IO36';
NET_NAME
'P3E_OCP_CPU0_PE3_C_TXN<5>'
 '@BASEBOARD_FAB2_LIB.BASEBOARD_FAB2(SCH_1):P3E_OCP_CPU0_PE3_C_TXN'<5>:
 C_SIGNAL='@baseboard_fab2_lib.baseboard_fab2(sch_1):p3e_ocp_cpu0_pe3_c_txn(5)';
NODE_NAME     C2R13 2
 '@BASEBOARD_FAB2_LIB.BASEBOARD_FAB2(SCH_1):PAGE106_I137@MSTR_DISCRETE.CAP(CHIPS)':
 'B': CDS_PINID='B';
NODE_NAME     J8E3 28
 '@BASEBOARD_FAB2_LIB.BASEBOARD_FAB2(SCH_1):PAGE187_I119@MSTR_SCONN.SCONN80_E67482007(CHIPS)':
 'IO28': CDS_PINID='IO28';
NET_NAME
'P3E_OCP_CPU0_PE3_C_TXN<6>'
 '@BASEBOARD_FAB2_LIB.BASEBOARD_FAB2(SCH_1):P3E_OCP_CPU0_PE3_C_TXN'<6>:
 C_SIGNAL='@baseboard_fab2_lib.baseboard_fab2(sch_1):p3e_ocp_cpu0_pe3_c_txn(6)';
NODE_NAME     C2R7 2
 '@BASEBOARD_FAB2_LIB.BASEBOARD_FAB2(SCH_1):PAGE106_I123@MSTR_DISCRETE.CAP(CHIPS)':
 'B': CDS_PINID='B';
NODE_NAME     J8E3 20
 '@BASEBOARD_FAB2_LIB.BASEBOARD_FAB2(SCH_1):PAGE187_I119@MSTR_SCONN.SCONN80_E67482007(CHIPS)':
 'IO20': CDS_PINID='IO20';
NET_NAME
'P3E_OCP_CPU0_PE3_C_TXN<7>'
 '@BASEBOARD_FAB2_LIB.BASEBOARD_FAB2(SCH_1):P3E_OCP_CPU0_PE3_C_TXN'<7>:
 C_SIGNAL='@baseboard_fab2_lib.baseboard_fab2(sch_1):p3e_ocp_cpu0_pe3_c_txn(7)';
NODE_NAME     C2R9 2
 '@BASEBOARD_FAB2_LIB.BASEBOARD_FAB2(SCH_1):PAGE106_I147@MSTR_DISCRETE.CAP(CHIPS)':
 'B': CDS_PINID='B';
NODE_NAME     J8E3 12
 '@BASEBOARD_FAB2_LIB.BASEBOARD_FAB2(SCH_1):PAGE187_I119@MSTR_SCONN.SCONN80_E67482007(CHIPS)':
 'IO12': CDS_PINID='IO12';
NET_NAME
'P3E_OCP_CPU0_PE3_C_TXN<8>'
 '@BASEBOARD_FAB2_LIB.BASEBOARD_FAB2(SCH_1):P3E_OCP_CPU0_PE3_C_TXN'<8>:
 C_SIGNAL='@baseboard_fab2_lib.baseboard_fab2(sch_1):p3e_ocp_cpu0_pe3_c_txn(8)';
NODE_NAME     C2M15 2
 '@BASEBOARD_FAB2_LIB.BASEBOARD_FAB2(SCH_1):PAGE106_I86@MSTR_DISCRETE.CAP(CHIPS)':
 'B': CDS_PINID='B';
NODE_NAME     J9B3 114
 '@BASEBOARD_FAB2_LIB.BASEBOARD_FAB2(SCH_1):PAGE186_I336@MSTR_SCONN.SCONN120_A28699018(CHIPS)':
 'IO114': CDS_PINID='IO114';
NET_NAME
'P3E_OCP_CPU0_PE3_C_TXN<9>'
 '@BASEBOARD_FAB2_LIB.BASEBOARD_FAB2(SCH_1):P3E_OCP_CPU0_PE3_C_TXN'<9>:
 C_SIGNAL='@baseboard_fab2_lib.baseboard_fab2(sch_1):p3e_ocp_cpu0_pe3_c_txn(9)';
NODE_NAME     C1M19 2
 '@BASEBOARD_FAB2_LIB.BASEBOARD_FAB2(SCH_1):PAGE106_I90@MSTR_DISCRETE.CAP(CHIPS)':
 'B': CDS_PINID='B';
NODE_NAME     J9B3 106
 '@BASEBOARD_FAB2_LIB.BASEBOARD_FAB2(SCH_1):PAGE186_I336@MSTR_SCONN.SCONN120_A28699018(CHIPS)':
 'IO106': CDS_PINID='IO106';
NET_NAME
'P3E_OCP_CPU0_PE3_C_TXP<0>'
 '@BASEBOARD_FAB2_LIB.BASEBOARD_FAB2(SCH_1):P3E_OCP_CPU0_PE3_C_TXP'<0>:
 C_SIGNAL='@baseboard_fab2_lib.baseboard_fab2(sch_1):p3e_ocp_cpu0_pe3_c_txp(0)';
NODE_NAME     C1R2 2
 '@BASEBOARD_FAB2_LIB.BASEBOARD_FAB2(SCH_1):PAGE106_I10@MSTR_DISCRETE.CAP(CHIPS)':
 'B': CDS_PINID='B';
NODE_NAME     J8E3 66
 '@BASEBOARD_FAB2_LIB.BASEBOARD_FAB2(SCH_1):PAGE187_I119@MSTR_SCONN.SCONN80_E67482007(CHIPS)':
 'IO66': CDS_PINID='IO66';
NET_NAME
'P3E_OCP_CPU0_PE3_C_TXP<10>'
 '@BASEBOARD_FAB2_LIB.BASEBOARD_FAB2(SCH_1):P3E_OCP_CPU0_PE3_C_TXP'<10>:
 C_SIGNAL='@baseboard_fab2_lib.baseboard_fab2(sch_1):p3e_ocp_cpu0_pe3_c_txp(10)';
NODE_NAME     C1M16 2
 '@BASEBOARD_FAB2_LIB.BASEBOARD_FAB2(SCH_1):PAGE106_I82@MSTR_DISCRETE.CAP(CHIPS)':
 'B': CDS_PINID='B';
NODE_NAME     J9B3 96
 '@BASEBOARD_FAB2_LIB.BASEBOARD_FAB2(SCH_1):PAGE186_I336@MSTR_SCONN.SCONN120_A28699018(CHIPS)':
 'IO96': CDS_PINID='IO96';
NET_NAME
'P3E_OCP_CPU0_PE3_C_TXP<11>'
 '@BASEBOARD_FAB2_LIB.BASEBOARD_FAB2(SCH_1):P3E_OCP_CPU0_PE3_C_TXP'<11>:
 C_SIGNAL='@baseboard_fab2_lib.baseboard_fab2(sch_1):p3e_ocp_cpu0_pe3_c_txp(11)';
NODE_NAME     C1M14 2
 '@BASEBOARD_FAB2_LIB.BASEBOARD_FAB2(SCH_1):PAGE106_I85@MSTR_DISCRETE.CAP(CHIPS)':
 'B': CDS_PINID='B';
NODE_NAME     J9B3 88
 '@BASEBOARD_FAB2_LIB.BASEBOARD_FAB2(SCH_1):PAGE186_I336@MSTR_SCONN.SCONN120_A28699018(CHIPS)':
 'IO88': CDS_PINID='IO88';
NET_NAME
'P3E_OCP_CPU0_PE3_C_TXP<12>'
 '@BASEBOARD_FAB2_LIB.BASEBOARD_FAB2(SCH_1):P3E_OCP_CPU0_PE3_C_TXP'<12>:
 C_SIGNAL='@baseboard_fab2_lib.baseboard_fab2(sch_1):p3e_ocp_cpu0_pe3_c_txp(12)';
NODE_NAME     C1M12 2
 '@BASEBOARD_FAB2_LIB.BASEBOARD_FAB2(SCH_1):PAGE106_I100@MSTR_DISCRETE.CAP(CHIPS)':
 'B': CDS_PINID='B';
NODE_NAME     J9B3 80
 '@BASEBOARD_FAB2_LIB.BASEBOARD_FAB2(SCH_1):PAGE186_I336@MSTR_SCONN.SCONN120_A28699018(CHIPS)':
 'IO80': CDS_PINID='IO80';
NET_NAME
'P3E_OCP_CPU0_PE3_C_TXP<13>'
 '@BASEBOARD_FAB2_LIB.BASEBOARD_FAB2(SCH_1):P3E_OCP_CPU0_PE3_C_TXP'<13>:
 C_SIGNAL='@baseboard_fab2_lib.baseboard_fab2(sch_1):p3e_ocp_cpu0_pe3_c_txp(13)';
NODE_NAME     C1M10 2
 '@BASEBOARD_FAB2_LIB.BASEBOARD_FAB2(SCH_1):PAGE106_I102@MSTR_DISCRETE.CAP(CHIPS)':
 'B': CDS_PINID='B';
NODE_NAME     J9B3 72
 '@BASEBOARD_FAB2_LIB.BASEBOARD_FAB2(SCH_1):PAGE186_I336@MSTR_SCONN.SCONN120_A28699018(CHIPS)':
 'IO72': CDS_PINID='IO72';
NET_NAME
'P3E_OCP_CPU0_PE3_C_TXP<14>'
 '@BASEBOARD_FAB2_LIB.BASEBOARD_FAB2(SCH_1):P3E_OCP_CPU0_PE3_C_TXP'<14>:
 C_SIGNAL='@baseboard_fab2_lib.baseboard_fab2(sch_1):p3e_ocp_cpu0_pe3_c_txp(14)';
NODE_NAME     C1M8 2
 '@BASEBOARD_FAB2_LIB.BASEBOARD_FAB2(SCH_1):PAGE106_I105@MSTR_DISCRETE.CAP(CHIPS)':
 'B': CDS_PINID='B';
NODE_NAME     J9B3 64
 '@BASEBOARD_FAB2_LIB.BASEBOARD_FAB2(SCH_1):PAGE186_I336@MSTR_SCONN.SCONN120_A28699018(CHIPS)':
 'IO64': CDS_PINID='IO64';
NET_NAME
'P3E_OCP_CPU0_PE3_C_TXP<15>'
 '@BASEBOARD_FAB2_LIB.BASEBOARD_FAB2(SCH_1):P3E_OCP_CPU0_PE3_C_TXP'<15>:
 C_SIGNAL='@baseboard_fab2_lib.baseboard_fab2(sch_1):p3e_ocp_cpu0_pe3_c_txp(15)';
NODE_NAME     C1M6 2
 '@BASEBOARD_FAB2_LIB.BASEBOARD_FAB2(SCH_1):PAGE106_I109@MSTR_DISCRETE.CAP(CHIPS)':
 'B': CDS_PINID='B';
NODE_NAME     J9B3 56
 '@BASEBOARD_FAB2_LIB.BASEBOARD_FAB2(SCH_1):PAGE186_I336@MSTR_SCONN.SCONN120_A28699018(CHIPS)':
 'IO56': CDS_PINID='IO56';
NET_NAME
'P3E_OCP_CPU0_PE3_C_TXP<1>'
 '@BASEBOARD_FAB2_LIB.BASEBOARD_FAB2(SCH_1):P3E_OCP_CPU0_PE3_C_TXP'<1>:
 C_SIGNAL='@baseboard_fab2_lib.baseboard_fab2(sch_1):p3e_ocp_cpu0_pe3_c_txp(1)';
NODE_NAME     C1R4 2
 '@BASEBOARD_FAB2_LIB.BASEBOARD_FAB2(SCH_1):PAGE106_I26@MSTR_DISCRETE.CAP(CHIPS)':
 'B': CDS_PINID='B';
NODE_NAME     J8E3 58
 '@BASEBOARD_FAB2_LIB.BASEBOARD_FAB2(SCH_1):PAGE187_I119@MSTR_SCONN.SCONN80_E67482007(CHIPS)':
 'IO58': CDS_PINID='IO58';
NET_NAME
'P3E_OCP_CPU0_PE3_C_TXP<2>'
 '@BASEBOARD_FAB2_LIB.BASEBOARD_FAB2(SCH_1):P3E_OCP_CPU0_PE3_C_TXP'<2>:
 C_SIGNAL='@baseboard_fab2_lib.baseboard_fab2(sch_1):p3e_ocp_cpu0_pe3_c_txp(2)';
NODE_NAME     C1R6 2
 '@BASEBOARD_FAB2_LIB.BASEBOARD_FAB2(SCH_1):PAGE106_I40@MSTR_DISCRETE.CAP(CHIPS)':
 'B': CDS_PINID='B';
NODE_NAME     J8E3 50
 '@BASEBOARD_FAB2_LIB.BASEBOARD_FAB2(SCH_1):PAGE187_I119@MSTR_SCONN.SCONN80_E67482007(CHIPS)':
 'IO50': CDS_PINID='IO50';
NET_NAME
'P3E_OCP_CPU0_PE3_C_TXP<3>'
 '@BASEBOARD_FAB2_LIB.BASEBOARD_FAB2(SCH_1):P3E_OCP_CPU0_PE3_C_TXP'<3>:
 C_SIGNAL='@baseboard_fab2_lib.baseboard_fab2(sch_1):p3e_ocp_cpu0_pe3_c_txp(3)';
NODE_NAME     C1R8 2
 '@BASEBOARD_FAB2_LIB.BASEBOARD_FAB2(SCH_1):PAGE106_I55@MSTR_DISCRETE.CAP(CHIPS)':
 'B': CDS_PINID='B';
NODE_NAME     J8E3 42
 '@BASEBOARD_FAB2_LIB.BASEBOARD_FAB2(SCH_1):PAGE187_I119@MSTR_SCONN.SCONN80_E67482007(CHIPS)':
 'IO42': CDS_PINID='IO42';
NET_NAME
'P3E_OCP_CPU0_PE3_C_TXP<4>'
 '@BASEBOARD_FAB2_LIB.BASEBOARD_FAB2(SCH_1):P3E_OCP_CPU0_PE3_C_TXP'<4>:
 C_SIGNAL='@baseboard_fab2_lib.baseboard_fab2(sch_1):p3e_ocp_cpu0_pe3_c_txp(4)';
NODE_NAME     C1R10 2
 '@BASEBOARD_FAB2_LIB.BASEBOARD_FAB2(SCH_1):PAGE106_I128@MSTR_DISCRETE.CAP(CHIPS)':
 'B': CDS_PINID='B';
NODE_NAME     J8E3 34
 '@BASEBOARD_FAB2_LIB.BASEBOARD_FAB2(SCH_1):PAGE187_I119@MSTR_SCONN.SCONN80_E67482007(CHIPS)':
 'IO34': CDS_PINID='IO34';
NET_NAME
'P3E_OCP_CPU0_PE3_C_TXP<5>'
 '@BASEBOARD_FAB2_LIB.BASEBOARD_FAB2(SCH_1):P3E_OCP_CPU0_PE3_C_TXP'<5>:
 C_SIGNAL='@baseboard_fab2_lib.baseboard_fab2(sch_1):p3e_ocp_cpu0_pe3_c_txp(5)';
NODE_NAME     C2R14 2
 '@BASEBOARD_FAB2_LIB.BASEBOARD_FAB2(SCH_1):PAGE106_I130@MSTR_DISCRETE.CAP(CHIPS)':
 'B': CDS_PINID='B';
NODE_NAME     J8E3 26
 '@BASEBOARD_FAB2_LIB.BASEBOARD_FAB2(SCH_1):PAGE187_I119@MSTR_SCONN.SCONN80_E67482007(CHIPS)':
 'IO26': CDS_PINID='IO26';
NET_NAME
'P3E_OCP_CPU0_PE3_C_TXP<6>'
 '@BASEBOARD_FAB2_LIB.BASEBOARD_FAB2(SCH_1):P3E_OCP_CPU0_PE3_C_TXP'<6>:
 C_SIGNAL='@baseboard_fab2_lib.baseboard_fab2(sch_1):p3e_ocp_cpu0_pe3_c_txp(6)';
NODE_NAME     C2R8 2
 '@BASEBOARD_FAB2_LIB.BASEBOARD_FAB2(SCH_1):PAGE106_I141@MSTR_DISCRETE.CAP(CHIPS)':
 'B': CDS_PINID='B';
NODE_NAME     J8E3 18
 '@BASEBOARD_FAB2_LIB.BASEBOARD_FAB2(SCH_1):PAGE187_I119@MSTR_SCONN.SCONN80_E67482007(CHIPS)':
 'IO18': CDS_PINID='IO18';
NET_NAME
'P3E_OCP_CPU0_PE3_C_TXP<7>'
 '@BASEBOARD_FAB2_LIB.BASEBOARD_FAB2(SCH_1):P3E_OCP_CPU0_PE3_C_TXP'<7>:
 C_SIGNAL='@baseboard_fab2_lib.baseboard_fab2(sch_1):p3e_ocp_cpu0_pe3_c_txp(7)';
NODE_NAME     C2R10 2
 '@BASEBOARD_FAB2_LIB.BASEBOARD_FAB2(SCH_1):PAGE106_I142@MSTR_DISCRETE.CAP(CHIPS)':
 'B': CDS_PINID='B';
NODE_NAME     J8E3 10
 '@BASEBOARD_FAB2_LIB.BASEBOARD_FAB2(SCH_1):PAGE187_I119@MSTR_SCONN.SCONN80_E67482007(CHIPS)':
 'IO10': CDS_PINID='IO10';
NET_NAME
'P3E_OCP_CPU0_PE3_C_TXP<8>'
 '@BASEBOARD_FAB2_LIB.BASEBOARD_FAB2(SCH_1):P3E_OCP_CPU0_PE3_C_TXP'<8>:
 C_SIGNAL='@baseboard_fab2_lib.baseboard_fab2(sch_1):p3e_ocp_cpu0_pe3_c_txp(8)';
NODE_NAME     C2M14 2
 '@BASEBOARD_FAB2_LIB.BASEBOARD_FAB2(SCH_1):PAGE106_I76@MSTR_DISCRETE.CAP(CHIPS)':
 'B': CDS_PINID='B';
NODE_NAME     J9B3 112
 '@BASEBOARD_FAB2_LIB.BASEBOARD_FAB2(SCH_1):PAGE186_I336@MSTR_SCONN.SCONN120_A28699018(CHIPS)':
 'IO112': CDS_PINID='IO112';
NET_NAME
'P3E_OCP_CPU0_PE3_C_TXP<9>'
 '@BASEBOARD_FAB2_LIB.BASEBOARD_FAB2(SCH_1):P3E_OCP_CPU0_PE3_C_TXP'<9>:
 C_SIGNAL='@baseboard_fab2_lib.baseboard_fab2(sch_1):p3e_ocp_cpu0_pe3_c_txp(9)';
NODE_NAME     C1M18 2
 '@BASEBOARD_FAB2_LIB.BASEBOARD_FAB2(SCH_1):PAGE106_I78@MSTR_DISCRETE.CAP(CHIPS)':
 'B': CDS_PINID='B';
NODE_NAME     J9B3 104
 '@BASEBOARD_FAB2_LIB.BASEBOARD_FAB2(SCH_1):PAGE186_I336@MSTR_SCONN.SCONN120_A28699018(CHIPS)':
 'IO104': CDS_PINID='IO104';
NET_NAME
'P3E_PCH_M2_RX_DN<1>'
 '@BASEBOARD_FAB2_LIB.BASEBOARD_FAB2(SCH_1):P3E_PCH_M2_RX_DN'<1>:
 C_SIGNAL='@baseboard_fab2_lib.baseboard_fab2(sch_1):p3e_pch_m2_rx_dn(1)';
NODE_NAME     U7C1 AY72
 '@BASEBOARD_FAB2_LIB.BASEBOARD_FAB2(SCH_1):PAGE116_I220@MSTR_U_PROC.LBG_CORE_QAT_EXT_D(CHIPS)':
 'USB3_8_PCIE1_RXN': CDS_PINID='USB3_8_PCIE1_RXN';
NODE_NAME     J8F1 29
 '@BASEBOARD_FAB2_LIB.BASEBOARD_FAB2(SCH_1):PAGE185_I143@W_HDL.SKT-MINI67P-41-GP(CHIPS)':
 '29': CDS_PINID='\29\';
NET_NAME
'P3E_PCH_M2_RX_DN<2>'
 '@BASEBOARD_FAB2_LIB.BASEBOARD_FAB2(SCH_1):P3E_PCH_M2_RX_DN'<2>:
 C_SIGNAL='@baseboard_fab2_lib.baseboard_fab2(sch_1):p3e_pch_m2_rx_dn(2)';
NODE_NAME     U7C1 AW71
 '@BASEBOARD_FAB2_LIB.BASEBOARD_FAB2(SCH_1):PAGE116_I220@MSTR_U_PROC.LBG_CORE_QAT_EXT_D(CHIPS)':
 'USB3_9_PCIE2_RXN': CDS_PINID='USB3_9_PCIE2_RXN';
NODE_NAME     J8F1 17
 '@BASEBOARD_FAB2_LIB.BASEBOARD_FAB2(SCH_1):PAGE185_I143@W_HDL.SKT-MINI67P-41-GP(CHIPS)':
 '17': CDS_PINID='\17\';
NET_NAME
'P3E_PCH_M2_RX_DN<3>'
 '@BASEBOARD_FAB2_LIB.BASEBOARD_FAB2(SCH_1):P3E_PCH_M2_RX_DN'<3>:
 C_SIGNAL='@baseboard_fab2_lib.baseboard_fab2(sch_1):p3e_pch_m2_rx_dn(3)';
NODE_NAME     U7C1 AV72
 '@BASEBOARD_FAB2_LIB.BASEBOARD_FAB2(SCH_1):PAGE116_I220@MSTR_U_PROC.LBG_CORE_QAT_EXT_D(CHIPS)':
 'USB3_10_PCIE3_GBE_RXN': CDS_PINID='USB3_10_PCIE3_GBE_RXN';
NODE_NAME     J8F1 5
 '@BASEBOARD_FAB2_LIB.BASEBOARD_FAB2(SCH_1):PAGE185_I143@W_HDL.SKT-MINI67P-41-GP(CHIPS)':
 '5': CDS_PINID='\5\';
NET_NAME
'P3E_PCH_M2_RX_DP<1>'
 '@BASEBOARD_FAB2_LIB.BASEBOARD_FAB2(SCH_1):P3E_PCH_M2_RX_DP'<1>:
 C_SIGNAL='@baseboard_fab2_lib.baseboard_fab2(sch_1):p3e_pch_m2_rx_dp(1)';
NODE_NAME     U7C1 AY70
 '@BASEBOARD_FAB2_LIB.BASEBOARD_FAB2(SCH_1):PAGE116_I220@MSTR_U_PROC.LBG_CORE_QAT_EXT_D(CHIPS)':
 'USB3_8_PCIE1_RXP': CDS_PINID='USB3_8_PCIE1_RXP';
NODE_NAME     J8F1 31
 '@BASEBOARD_FAB2_LIB.BASEBOARD_FAB2(SCH_1):PAGE185_I143@W_HDL.SKT-MINI67P-41-GP(CHIPS)':
 '31': CDS_PINID='\31\';
NET_NAME
'P3E_PCH_M2_RX_DP<2>'
 '@BASEBOARD_FAB2_LIB.BASEBOARD_FAB2(SCH_1):P3E_PCH_M2_RX_DP'<2>:
 C_SIGNAL='@baseboard_fab2_lib.baseboard_fab2(sch_1):p3e_pch_m2_rx_dp(2)';
NODE_NAME     U7C1 AW69
 '@BASEBOARD_FAB2_LIB.BASEBOARD_FAB2(SCH_1):PAGE116_I220@MSTR_U_PROC.LBG_CORE_QAT_EXT_D(CHIPS)':
 'USB3_9_PCIE2_RXP': CDS_PINID='USB3_9_PCIE2_RXP';
NODE_NAME     J8F1 19
 '@BASEBOARD_FAB2_LIB.BASEBOARD_FAB2(SCH_1):PAGE185_I143@W_HDL.SKT-MINI67P-41-GP(CHIPS)':
 '19': CDS_PINID='\19\';
NET_NAME
'P3E_PCH_M2_RX_DP<3>'
 '@BASEBOARD_FAB2_LIB.BASEBOARD_FAB2(SCH_1):P3E_PCH_M2_RX_DP'<3>:
 C_SIGNAL='@baseboard_fab2_lib.baseboard_fab2(sch_1):p3e_pch_m2_rx_dp(3)';
NODE_NAME     U7C1 AV70
 '@BASEBOARD_FAB2_LIB.BASEBOARD_FAB2(SCH_1):PAGE116_I220@MSTR_U_PROC.LBG_CORE_QAT_EXT_D(CHIPS)':
 'USB3_10_PCIE3_GBE_RXP': CDS_PINID='USB3_10_PCIE3_GBE_RXP';
NODE_NAME     J8F1 7
 '@BASEBOARD_FAB2_LIB.BASEBOARD_FAB2(SCH_1):PAGE185_I143@W_HDL.SKT-MINI67P-41-GP(CHIPS)':
 '7': CDS_PINID='\7\';
NET_NAME
'P3E_PCH_M2_SATA6G_RX_R_DN'
 '@BASEBOARD_FAB2_LIB.BASEBOARD_FAB2(SCH_1):P3E_PCH_M2_SATA6G_RX_R_DN':
 C_SIGNAL='@baseboard_fab2_lib.baseboard_fab2(sch_1):p3e_pch_m2_sata6g_rx_r_dn';
NODE_NAME     R8F21 2
 '@BASEBOARD_FAB2_LIB.BASEBOARD_FAB2(SCH_1):PAGE185_I106@MSTR_DISCRETE.RES(CHIPS)':
 'B': CDS_PINID='B';
NODE_NAME     C8F15 2
 '@BASEBOARD_FAB2_LIB.BASEBOARD_FAB2(SCH_1):PAGE185_I142@DEV_DISCRETE.CAP_A(CHIPS)':
 'B': CDS_PINID='B';
NODE_NAME     J8F1 43
 '@BASEBOARD_FAB2_LIB.BASEBOARD_FAB2(SCH_1):PAGE185_I143@W_HDL.SKT-MINI67P-41-GP(CHIPS)':
 '43': CDS_PINID='\43\';
NET_NAME
'P3E_PCH_M2_SATA6G_RX_R_DP'
 '@BASEBOARD_FAB2_LIB.BASEBOARD_FAB2(SCH_1):P3E_PCH_M2_SATA6G_RX_R_DP':
 C_SIGNAL='@baseboard_fab2_lib.baseboard_fab2(sch_1):p3e_pch_m2_sata6g_rx_r_dp';
NODE_NAME     R8F18 2
 '@BASEBOARD_FAB2_LIB.BASEBOARD_FAB2(SCH_1):PAGE185_I105@MSTR_DISCRETE.RES(CHIPS)':
 'B': CDS_PINID='B';
NODE_NAME     C8F13 2
 '@BASEBOARD_FAB2_LIB.BASEBOARD_FAB2(SCH_1):PAGE185_I141@DEV_DISCRETE.CAP_A(CHIPS)':
 'B': CDS_PINID='B';
NODE_NAME     J8F1 41
 '@BASEBOARD_FAB2_LIB.BASEBOARD_FAB2(SCH_1):PAGE185_I143@W_HDL.SKT-MINI67P-41-GP(CHIPS)':
 '41': CDS_PINID='\41\';
NET_NAME
'P3E_PCH_M2_SATA6G_TX_R_DN'
 '@BASEBOARD_FAB2_LIB.BASEBOARD_FAB2(SCH_1):P3E_PCH_M2_SATA6G_TX_R_DN':
 C_SIGNAL='@baseboard_fab2_lib.baseboard_fab2(sch_1):p3e_pch_m2_sata6g_tx_r_dn';
NODE_NAME     C8F11 2
 '@BASEBOARD_FAB2_LIB.BASEBOARD_FAB2(SCH_1):PAGE185_I139@DEV_DISCRETE.CAP_A(CHIPS)':
 'B': CDS_PINID='B';
NODE_NAME     C8F12 2
 '@BASEBOARD_FAB2_LIB.BASEBOARD_FAB2(SCH_1):PAGE185_I140@MSTR_DISCRETE.CAP(CHIPS)':
 'B': CDS_PINID='B';
NODE_NAME     J8F1 47
 '@BASEBOARD_FAB2_LIB.BASEBOARD_FAB2(SCH_1):PAGE185_I143@W_HDL.SKT-MINI67P-41-GP(CHIPS)':
 '47': CDS_PINID='\47\';
NET_NAME
'P3E_PCH_M2_SATA6G_TX_R_DP'
 '@BASEBOARD_FAB2_LIB.BASEBOARD_FAB2(SCH_1):P3E_PCH_M2_SATA6G_TX_R_DP':
 C_SIGNAL='@baseboard_fab2_lib.baseboard_fab2(sch_1):p3e_pch_m2_sata6g_tx_r_dp';
NODE_NAME     C8F7 2
 '@BASEBOARD_FAB2_LIB.BASEBOARD_FAB2(SCH_1):PAGE185_I96@MSTR_DISCRETE.CAP(CHIPS)':
 'B': CDS_PINID='B';
NODE_NAME     C8F6 2
 '@BASEBOARD_FAB2_LIB.BASEBOARD_FAB2(SCH_1):PAGE185_I138@DEV_DISCRETE.CAP_A(CHIPS)':
 'B': CDS_PINID='B';
NODE_NAME     J8F1 49
 '@BASEBOARD_FAB2_LIB.BASEBOARD_FAB2(SCH_1):PAGE185_I143@W_HDL.SKT-MINI67P-41-GP(CHIPS)':
 '49': CDS_PINID='\49\';
NET_NAME
'P3E_PCH_M2_TX_C_DN<1>'
 '@BASEBOARD_FAB2_LIB.BASEBOARD_FAB2(SCH_1):P3E_PCH_M2_TX_C_DN'<1>:
 C_SIGNAL='@baseboard_fab2_lib.baseboard_fab2(sch_1):p3e_pch_m2_tx_c_dn(1)';
NODE_NAME     J8F1 35
 '@BASEBOARD_FAB2_LIB.BASEBOARD_FAB2(SCH_1):PAGE185_I143@W_HDL.SKT-MINI67P-41-GP(CHIPS)':
 '35': CDS_PINID='\35\';
NODE_NAME     C2T11 1
 '@BASEBOARD_FAB2_LIB.BASEBOARD_FAB2(SCH_1):PAGE185_I167@MSTR_DISCRETE.CAP(CHIPS)':
 'A': CDS_PINID='A';
NET_NAME
'P3E_PCH_M2_TX_C_DN<2>'
 '@BASEBOARD_FAB2_LIB.BASEBOARD_FAB2(SCH_1):P3E_PCH_M2_TX_C_DN'<2>:
 C_SIGNAL='@baseboard_fab2_lib.baseboard_fab2(sch_1):p3e_pch_m2_tx_c_dn(2)';
NODE_NAME     J8F1 23
 '@BASEBOARD_FAB2_LIB.BASEBOARD_FAB2(SCH_1):PAGE185_I143@W_HDL.SKT-MINI67P-41-GP(CHIPS)':
 '23': CDS_PINID='\23\';
NODE_NAME     C2T14 1
 '@BASEBOARD_FAB2_LIB.BASEBOARD_FAB2(SCH_1):PAGE185_I171@MSTR_DISCRETE.CAP(CHIPS)':
 'A': CDS_PINID='A';
NET_NAME
'P3E_PCH_M2_TX_C_DN<3>'
 '@BASEBOARD_FAB2_LIB.BASEBOARD_FAB2(SCH_1):P3E_PCH_M2_TX_C_DN'<3>:
 C_SIGNAL='@baseboard_fab2_lib.baseboard_fab2(sch_1):p3e_pch_m2_tx_c_dn(3)';
NODE_NAME     J8F1 11
 '@BASEBOARD_FAB2_LIB.BASEBOARD_FAB2(SCH_1):PAGE185_I143@W_HDL.SKT-MINI67P-41-GP(CHIPS)':
 '11': CDS_PINID='\11\';
NODE_NAME     C2T23 1
 '@BASEBOARD_FAB2_LIB.BASEBOARD_FAB2(SCH_1):PAGE185_I180@MSTR_DISCRETE.CAP(CHIPS)':
 'A': CDS_PINID='A';
NET_NAME
'P3E_PCH_M2_TX_C_DP<1>'
 '@BASEBOARD_FAB2_LIB.BASEBOARD_FAB2(SCH_1):P3E_PCH_M2_TX_C_DP'<1>:
 C_SIGNAL='@baseboard_fab2_lib.baseboard_fab2(sch_1):p3e_pch_m2_tx_c_dp(1)';
NODE_NAME     J8F1 37
 '@BASEBOARD_FAB2_LIB.BASEBOARD_FAB2(SCH_1):PAGE185_I143@W_HDL.SKT-MINI67P-41-GP(CHIPS)':
 '37': CDS_PINID='\37\';
NODE_NAME     C2T10 1
 '@BASEBOARD_FAB2_LIB.BASEBOARD_FAB2(SCH_1):PAGE185_I168@MSTR_DISCRETE.CAP(CHIPS)':
 'A': CDS_PINID='A';
NET_NAME
'P3E_PCH_M2_TX_C_DP<2>'
 '@BASEBOARD_FAB2_LIB.BASEBOARD_FAB2(SCH_1):P3E_PCH_M2_TX_C_DP'<2>:
 C_SIGNAL='@baseboard_fab2_lib.baseboard_fab2(sch_1):p3e_pch_m2_tx_c_dp(2)';
NODE_NAME     J8F1 25
 '@BASEBOARD_FAB2_LIB.BASEBOARD_FAB2(SCH_1):PAGE185_I143@W_HDL.SKT-MINI67P-41-GP(CHIPS)':
 '25': CDS_PINID='\25\';
NODE_NAME     C2T13 1
 '@BASEBOARD_FAB2_LIB.BASEBOARD_FAB2(SCH_1):PAGE185_I172@MSTR_DISCRETE.CAP(CHIPS)':
 'A': CDS_PINID='A';
NET_NAME
'P3E_PCH_M2_TX_C_DP<3>'
 '@BASEBOARD_FAB2_LIB.BASEBOARD_FAB2(SCH_1):P3E_PCH_M2_TX_C_DP'<3>:
 C_SIGNAL='@baseboard_fab2_lib.baseboard_fab2(sch_1):p3e_pch_m2_tx_c_dp(3)';
NODE_NAME     J8F1 13
 '@BASEBOARD_FAB2_LIB.BASEBOARD_FAB2(SCH_1):PAGE185_I143@W_HDL.SKT-MINI67P-41-GP(CHIPS)':
 '13': CDS_PINID='\13\';
NODE_NAME     C2T20 1
 '@BASEBOARD_FAB2_LIB.BASEBOARD_FAB2(SCH_1):PAGE185_I179@MSTR_DISCRETE.CAP(CHIPS)':
 'A': CDS_PINID='A';
NET_NAME
'P3E_PCH_M2_TX_DN<1>'
 '@BASEBOARD_FAB2_LIB.BASEBOARD_FAB2(SCH_1):P3E_PCH_M2_TX_DN'<1>:
 C_SIGNAL='@baseboard_fab2_lib.baseboard_fab2(sch_1):p3e_pch_m2_tx_dn(1)';
NODE_NAME     U7C1 BM65
 '@BASEBOARD_FAB2_LIB.BASEBOARD_FAB2(SCH_1):PAGE116_I220@MSTR_U_PROC.LBG_CORE_QAT_EXT_D(CHIPS)':
 'USB3_8_PCIE1_TXN': CDS_PINID='USB3_8_PCIE1_TXN';
NODE_NAME     C2T11 2
 '@BASEBOARD_FAB2_LIB.BASEBOARD_FAB2(SCH_1):PAGE185_I167@MSTR_DISCRETE.CAP(CHIPS)':
 'B': CDS_PINID='B';
NET_NAME
'P3E_PCH_M2_TX_DN<2>'
 '@BASEBOARD_FAB2_LIB.BASEBOARD_FAB2(SCH_1):P3E_PCH_M2_TX_DN'<2>:
 C_SIGNAL='@baseboard_fab2_lib.baseboard_fab2(sch_1):p3e_pch_m2_tx_dn(2)';
NODE_NAME     U7C1 BK65
 '@BASEBOARD_FAB2_LIB.BASEBOARD_FAB2(SCH_1):PAGE116_I220@MSTR_U_PROC.LBG_CORE_QAT_EXT_D(CHIPS)':
 'USB3_9_PCIE2_TXN': CDS_PINID='USB3_9_PCIE2_TXN';
NODE_NAME     C2T14 2
 '@BASEBOARD_FAB2_LIB.BASEBOARD_FAB2(SCH_1):PAGE185_I171@MSTR_DISCRETE.CAP(CHIPS)':
 'B': CDS_PINID='B';
NET_NAME
'P3E_PCH_M2_TX_DN<3>'
 '@BASEBOARD_FAB2_LIB.BASEBOARD_FAB2(SCH_1):P3E_PCH_M2_TX_DN'<3>:
 C_SIGNAL='@baseboard_fab2_lib.baseboard_fab2(sch_1):p3e_pch_m2_tx_dn(3)';
NODE_NAME     U7C1 BH61
 '@BASEBOARD_FAB2_LIB.BASEBOARD_FAB2(SCH_1):PAGE116_I220@MSTR_U_PROC.LBG_CORE_QAT_EXT_D(CHIPS)':
 'USB3_10_PCIE3_GBE_TXN': CDS_PINID='USB3_10_PCIE3_GBE_TXN';
NODE_NAME     C2T23 2
 '@BASEBOARD_FAB2_LIB.BASEBOARD_FAB2(SCH_1):PAGE185_I180@MSTR_DISCRETE.CAP(CHIPS)':
 'B': CDS_PINID='B';
NET_NAME
'P3E_PCH_M2_TX_DP<1>'
 '@BASEBOARD_FAB2_LIB.BASEBOARD_FAB2(SCH_1):P3E_PCH_M2_TX_DP'<1>:
 C_SIGNAL='@baseboard_fab2_lib.baseboard_fab2(sch_1):p3e_pch_m2_tx_dp(1)';
NODE_NAME     U7C1 BR65
 '@BASEBOARD_FAB2_LIB.BASEBOARD_FAB2(SCH_1):PAGE116_I220@MSTR_U_PROC.LBG_CORE_QAT_EXT_D(CHIPS)':
 'USB3_8_PCIE1_TXP': CDS_PINID='USB3_8_PCIE1_TXP';
NODE_NAME     C2T10 2
 '@BASEBOARD_FAB2_LIB.BASEBOARD_FAB2(SCH_1):PAGE185_I168@MSTR_DISCRETE.CAP(CHIPS)':
 'B': CDS_PINID='B';
NET_NAME
'P3E_PCH_M2_TX_DP<2>'
 '@BASEBOARD_FAB2_LIB.BASEBOARD_FAB2(SCH_1):P3E_PCH_M2_TX_DP'<2>:
 C_SIGNAL='@baseboard_fab2_lib.baseboard_fab2(sch_1):p3e_pch_m2_tx_dp(2)';
NODE_NAME     U7C1 BL66
 '@BASEBOARD_FAB2_LIB.BASEBOARD_FAB2(SCH_1):PAGE116_I220@MSTR_U_PROC.LBG_CORE_QAT_EXT_D(CHIPS)':
 'USB3_9_PCIE2_TXP': CDS_PINID='USB3_9_PCIE2_TXP';
NODE_NAME     C2T13 2
 '@BASEBOARD_FAB2_LIB.BASEBOARD_FAB2(SCH_1):PAGE185_I172@MSTR_DISCRETE.CAP(CHIPS)':
 'B': CDS_PINID='B';
NET_NAME
'P3E_PCH_M2_TX_DP<3>'
 '@BASEBOARD_FAB2_LIB.BASEBOARD_FAB2(SCH_1):P3E_PCH_M2_TX_DP'<3>:
 C_SIGNAL='@baseboard_fab2_lib.baseboard_fab2(sch_1):p3e_pch_m2_tx_dp(3)';
NODE_NAME     U7C1 BK61
 '@BASEBOARD_FAB2_LIB.BASEBOARD_FAB2(SCH_1):PAGE116_I220@MSTR_U_PROC.LBG_CORE_QAT_EXT_D(CHIPS)':
 'USB3_10_PCIE3_GBE_TXP': CDS_PINID='USB3_10_PCIE3_GBE_TXP';
NODE_NAME     C2T20 2
 '@BASEBOARD_FAB2_LIB.BASEBOARD_FAB2(SCH_1):PAGE185_I179@MSTR_DISCRETE.CAP(CHIPS)':
 'B': CDS_PINID='B';
NET_NAME
'P3E_PCH_RX_0_DN'
 '@BASEBOARD_FAB2_LIB.BASEBOARD_FAB2(SCH_1):P3E_PCH_RX_0_DN':
 C_SIGNAL='@baseboard_fab2_lib.baseboard_fab2(sch_1):p3e_pch_rx_0_dn';
NODE_NAME     U7C1 BA71
 '@BASEBOARD_FAB2_LIB.BASEBOARD_FAB2(SCH_1):PAGE116_I220@MSTR_U_PROC.LBG_CORE_QAT_EXT_D(CHIPS)':
 'USB3_7_PCIE0_RXN': CDS_PINID='USB3_7_PCIE0_RXN';
NODE_NAME     R8F21 1
 '@BASEBOARD_FAB2_LIB.BASEBOARD_FAB2(SCH_1):PAGE185_I106@MSTR_DISCRETE.RES(CHIPS)':
 'A': CDS_PINID='A';
NET_NAME
'P3E_PCH_RX_0_DP'
 '@BASEBOARD_FAB2_LIB.BASEBOARD_FAB2(SCH_1):P3E_PCH_RX_0_DP':
 C_SIGNAL='@baseboard_fab2_lib.baseboard_fab2(sch_1):p3e_pch_rx_0_dp';
NODE_NAME     U7C1 BA69
 '@BASEBOARD_FAB2_LIB.BASEBOARD_FAB2(SCH_1):PAGE116_I220@MSTR_U_PROC.LBG_CORE_QAT_EXT_D(CHIPS)':
 'USB3_7_PCIE0_RXP': CDS_PINID='USB3_7_PCIE0_RXP';
NODE_NAME     R8F18 1
 '@BASEBOARD_FAB2_LIB.BASEBOARD_FAB2(SCH_1):PAGE185_I105@MSTR_DISCRETE.RES(CHIPS)':
 'A': CDS_PINID='A';
NET_NAME
'P3E_PCH_TX_0_DN'
 '@BASEBOARD_FAB2_LIB.BASEBOARD_FAB2(SCH_1):P3E_PCH_TX_0_DN':
 C_SIGNAL='@baseboard_fab2_lib.baseboard_fab2(sch_1):p3e_pch_tx_0_dn';
NODE_NAME     U7C1 BR61
 '@BASEBOARD_FAB2_LIB.BASEBOARD_FAB2(SCH_1):PAGE116_I220@MSTR_U_PROC.LBG_CORE_QAT_EXT_D(CHIPS)':
 'USB3_7_PCIE0_TXN': CDS_PINID='USB3_7_PCIE0_TXN';
NODE_NAME     C8F12 1
 '@BASEBOARD_FAB2_LIB.BASEBOARD_FAB2(SCH_1):PAGE185_I140@MSTR_DISCRETE.CAP(CHIPS)':
 'A': CDS_PINID='A';
NET_NAME
'P3E_PCH_TX_0_DP'
 '@BASEBOARD_FAB2_LIB.BASEBOARD_FAB2(SCH_1):P3E_PCH_TX_0_DP':
 C_SIGNAL='@baseboard_fab2_lib.baseboard_fab2(sch_1):p3e_pch_tx_0_dp';
NODE_NAME     U7C1 BN63
 '@BASEBOARD_FAB2_LIB.BASEBOARD_FAB2(SCH_1):PAGE116_I220@MSTR_U_PROC.LBG_CORE_QAT_EXT_D(CHIPS)':
 'USB3_7_PCIE0_TXP': CDS_PINID='USB3_7_PCIE0_TXP';
NODE_NAME     C8F7 1
 '@BASEBOARD_FAB2_LIB.BASEBOARD_FAB2(SCH_1):PAGE185_I96@MSTR_DISCRETE.CAP(CHIPS)':
 'A': CDS_PINID='A';
NET_NAME
'P3V3'
 '@BASEBOARD_FAB2_LIB.BASEBOARD_FAB2(SCH_1):P3V3':
 C_SIGNAL='@baseboard_fab2_lib.baseboard_fab2(sch_1):p3v3';
NODE_NAME     J8B1 18
 '@BASEBOARD_FAB2_LIB.BASEBOARD_FAB2(SCH_1):PAGE91_I1@MSTR_SCONN.SCONN24_H46321001(CHIPS)':
 'IO18': CDS_PINID='IO18';
NODE_NAME     J8B1 20
 '@BASEBOARD_FAB2_LIB.BASEBOARD_FAB2(SCH_1):PAGE91_I1@MSTR_SCONN.SCONN24_H46321001(CHIPS)':
 'IO20': CDS_PINID='IO20';
NODE_NAME     U3P2 14
 '@BASEBOARD_FAB2_LIB.BASEBOARD_FAB2(SCH_1):PAGE92_I1@MSTR_DIGITAL.GTL2014(CHIPS)':
 'VCC': CDS_PINID='VCC';
NODE_NAME     U7D2 14
 '@BASEBOARD_FAB2_LIB.BASEBOARD_FAB2(SCH_1):PAGE92_I32@MSTR_DIGITAL.GTL2014(CHIPS)':
 'VCC': CDS_PINID='VCC';
NODE_NAME     C7D4 1
 '@BASEBOARD_FAB2_LIB.BASEBOARD_FAB2(SCH_1):PAGE92_I79@MSTR_DISCRETE.CAP(CHIPS)':
 'A': CDS_PINID='A';
NODE_NAME     C3P50 1
 '@BASEBOARD_FAB2_LIB.BASEBOARD_FAB2(SCH_1):PAGE92_I84@MSTR_DISCRETE.CAP(CHIPS)':
 'A': CDS_PINID='A';
NODE_NAME     U2T4 14
 '@BASEBOARD_FAB2_LIB.BASEBOARD_FAB2(SCH_1):PAGE93_I30@MSTR_DIGITAL.GTL2014(CHIPS)':
 'VCC': CDS_PINID='VCC';
NODE_NAME     C2T33 1
 '@BASEBOARD_FAB2_LIB.BASEBOARD_FAB2(SCH_1):PAGE93_I72@DEV_DISCRETE.CAP_A(CHIPS)':
 'A': CDS_PINID='A';
NODE_NAME     R7G7 1
 '@BASEBOARD_FAB2_LIB.BASEBOARD_FAB2(SCH_1):PAGE94_I51@MSTR_DISCRETE.RES(CHIPS)':
 'A': CDS_PINID='A';
NODE_NAME     R3R4 1
 '@BASEBOARD_FAB2_LIB.BASEBOARD_FAB2(SCH_1):PAGE94_I66@MSTR_DISCRETE.RES(CHIPS)':
 'A': CDS_PINID='A';
NODE_NAME     R3R10 1
 '@BASEBOARD_FAB2_LIB.BASEBOARD_FAB2(SCH_1):PAGE94_I79@MSTR_DISCRETE.RES(CHIPS)':
 'A': CDS_PINID='A';
NODE_NAME     R6M4 1
 '@BASEBOARD_FAB2_LIB.BASEBOARD_FAB2(SCH_1):PAGE94_I82@MSTR_DISCRETE.RES(CHIPS)':
 'A': CDS_PINID='A';
NODE_NAME     R7E10 1
 '@BASEBOARD_FAB2_LIB.BASEBOARD_FAB2(SCH_1):PAGE95_I62@MSTR_DISCRETE.RES(CHIPS)':
 'A': CDS_PINID='A';
NODE_NAME     R7E11 1
 '@BASEBOARD_FAB2_LIB.BASEBOARD_FAB2(SCH_1):PAGE95_I72@MSTR_DISCRETE.RES(CHIPS)':
 'A': CDS_PINID='A';
NODE_NAME     R7E7 1
 '@BASEBOARD_FAB2_LIB.BASEBOARD_FAB2(SCH_1):PAGE95_I106@MSTR_DISCRETE.RES(CHIPS)':
 'A': CDS_PINID='A';
NODE_NAME     FB6P1 1
 '@BASEBOARD_FAB2_LIB.BASEBOARD_FAB2(SCH_1):PAGE102_I8@MSTR_DISCRETE.FERRITE(CHIPS)':
 'A': CDS_PINID='A';
NODE_NAME     R4D69 1
 '@BASEBOARD_FAB2_LIB.BASEBOARD_FAB2(SCH_1):PAGE102_I93@MSTR_DISCRETE.RES(CHIPS)':
 'A': CDS_PINID='A';
NODE_NAME     R4D70 1
 '@BASEBOARD_FAB2_LIB.BASEBOARD_FAB2(SCH_1):PAGE102_I94@MSTR_DISCRETE.RES(CHIPS)':
 'A': CDS_PINID='A';
NODE_NAME     C6F1 1
 '@BASEBOARD_FAB2_LIB.BASEBOARD_FAB2(SCH_1):PAGE104_I25@DEV_DISCRETE.CAP_A(CHIPS)':
 'A': CDS_PINID='A';
NODE_NAME     C3F2 1
 '@BASEBOARD_FAB2_LIB.BASEBOARD_FAB2(SCH_1):PAGE104_I34@DEV_DISCRETE.CAP_A(CHIPS)':
 'A': CDS_PINID='A';
NODE_NAME     Y6F1 6
 '@BASEBOARD_FAB2_LIB.BASEBOARD_FAB2(SCH_1):PAGE104_I71@MSTR_DISCRETE.OSC_C(CHIPS)':
 'VCC': CDS_PINID='VCC';
NODE_NAME     Y3F1 6
 '@BASEBOARD_FAB2_LIB.BASEBOARD_FAB2(SCH_1):PAGE104_I72@MSTR_DISCRETE.OSC_C(CHIPS)':
 'VCC': CDS_PINID='VCC';
NODE_NAME     C2U21 1
 '@BASEBOARD_FAB2_LIB.BASEBOARD_FAB2(SCH_1):PAGE108_I5@DEV_DISCRETE.CAP_A(CHIPS)':
 'A': CDS_PINID='A';
NODE_NAME     C2U25 1
 '@BASEBOARD_FAB2_LIB.BASEBOARD_FAB2(SCH_1):PAGE108_I7@DEV_DISCRETE.CAP_A(CHIPS)':
 'A': CDS_PINID='A';
NODE_NAME     J8G1 21
 '@BASEBOARD_FAB2_LIB.BASEBOARD_FAB2(SCH_1):PAGE108_I258@MSTR_SCONN.SCONN200_H68296001(CHIPS)':
 'IO21': CDS_PINID='IO21';
NODE_NAME     J8G1 22
 '@BASEBOARD_FAB2_LIB.BASEBOARD_FAB2(SCH_1):PAGE108_I258@MSTR_SCONN.SCONN200_H68296001(CHIPS)':
 'IO22': CDS_PINID='IO22';
NODE_NAME     J8G1 23
 '@BASEBOARD_FAB2_LIB.BASEBOARD_FAB2(SCH_1):PAGE108_I258@MSTR_SCONN.SCONN200_H68296001(CHIPS)':
 'IO23': CDS_PINID='IO23';
NODE_NAME     J8G1 24
 '@BASEBOARD_FAB2_LIB.BASEBOARD_FAB2(SCH_1):PAGE108_I258@MSTR_SCONN.SCONN200_H68296001(CHIPS)':
 'IO24': CDS_PINID='IO24';
NODE_NAME     R7E21 1
 '@BASEBOARD_FAB2_LIB.BASEBOARD_FAB2(SCH_1):PAGE108_I343@MSTR_DISCRETE.RES(CHIPS)':
 'A': CDS_PINID='A';
NODE_NAME     Q9A1 3
 '@BASEBOARD_FAB2_LIB.BASEBOARD_FAB2(SCH_1):PAGE111_I94@MSTR_DISCRETE.NPN_DUAL(CHIPS)':
 'C'<0>: CDS_PINID='C(0)';
NODE_NAME     R9A1 1
 '@BASEBOARD_FAB2_LIB.BASEBOARD_FAB2(SCH_1):PAGE111_I95@MSTR_DISCRETE.RES(CHIPS)':
 'A': CDS_PINID='A';
NODE_NAME     U9G1 14
 '@BASEBOARD_FAB2_LIB.BASEBOARD_FAB2(SCH_1):PAGE152_I1@MSTR_DIGITAL.GTL2014(CHIPS)':
 'VCC': CDS_PINID='VCC';
NODE_NAME     C1U19 1
 '@BASEBOARD_FAB2_LIB.BASEBOARD_FAB2(SCH_1):PAGE152_I18@MSTR_DISCRETE.CAP(CHIPS)':
 'A': CDS_PINID='A';
NODE_NAME     R2N27 1
 '@BASEBOARD_FAB2_LIB.BASEBOARD_FAB2(SCH_1):PAGE157_I97@MSTR_DISCRETE.RES(CHIPS)':
 'A': CDS_PINID='A';
NODE_NAME     R1U26 1
 '@BASEBOARD_FAB2_LIB.BASEBOARD_FAB2(SCH_1):PAGE169_I148@MSTR_DISCRETE.RES(CHIPS)':
 'A': CDS_PINID='A';
NODE_NAME     R2L23 1
 '@BASEBOARD_FAB2_LIB.BASEBOARD_FAB2(SCH_1):PAGE173_I261@MSTR_DISCRETE.RES(CHIPS)':
 'A': CDS_PINID='A';
NODE_NAME     R2L21 1
 '@BASEBOARD_FAB2_LIB.BASEBOARD_FAB2(SCH_1):PAGE173_I263@MSTR_DISCRETE.RES(CHIPS)':
 'A': CDS_PINID='A';
NODE_NAME     R1M12 1
 '@BASEBOARD_FAB2_LIB.BASEBOARD_FAB2(SCH_1):PAGE177_I8@MSTR_DISCRETE.RES(CHIPS)':
 'A': CDS_PINID='A';
NODE_NAME     R1M11 1
 '@BASEBOARD_FAB2_LIB.BASEBOARD_FAB2(SCH_1):PAGE177_I9@MSTR_DISCRETE.RES(CHIPS)':
 'A': CDS_PINID='A';
NODE_NAME     C1M3 1
 '@BASEBOARD_FAB2_LIB.BASEBOARD_FAB2(SCH_1):PAGE177_I20@DEV_DISCRETE.CAP_A(CHIPS)':
 'A': CDS_PINID='A';
NODE_NAME     R1L21 1
 '@BASEBOARD_FAB2_LIB.BASEBOARD_FAB2(SCH_1):PAGE177_I43@MSTR_DISCRETE.RES(CHIPS)':
 'A': CDS_PINID='A';
NODE_NAME     R2P15 1
 '@BASEBOARD_FAB2_LIB.BASEBOARD_FAB2(SCH_1):PAGE185_I111@MSTR_DISCRETE.RES(CHIPS)':
 'A': CDS_PINID='A';
NODE_NAME     C2T29 1
 '@BASEBOARD_FAB2_LIB.BASEBOARD_FAB2(SCH_1):PAGE185_I120@DEV_DISCRETE.CAP_A(CHIPS)':
 'A': CDS_PINID='A';
NODE_NAME     C2T26 1
 '@BASEBOARD_FAB2_LIB.BASEBOARD_FAB2(SCH_1):PAGE185_I123@DEV_DISCRETE.CAP_A(CHIPS)':
 'A': CDS_PINID='A';
NODE_NAME     C2T21 1
 '@BASEBOARD_FAB2_LIB.BASEBOARD_FAB2(SCH_1):PAGE185_I124@DEV_DISCRETE.CAP_A(CHIPS)':
 'A': CDS_PINID='A';
NODE_NAME     C2T16 1
 '@BASEBOARD_FAB2_LIB.BASEBOARD_FAB2(SCH_1):PAGE185_I126@DEV_DISCRETE.CAP_A(CHIPS)':
 'A': CDS_PINID='A';
NODE_NAME     C2T15 1
 '@BASEBOARD_FAB2_LIB.BASEBOARD_FAB2(SCH_1):PAGE185_I127@DEV_DISCRETE.CAP_A(CHIPS)':
 'A': CDS_PINID='A';
NODE_NAME     C2T24 1
 '@BASEBOARD_FAB2_LIB.BASEBOARD_FAB2(SCH_1):PAGE185_I129@DEV_DISCRETE.CAP_A(CHIPS)':
 'A': CDS_PINID='A';
NODE_NAME     C2T2 1
 '@BASEBOARD_FAB2_LIB.BASEBOARD_FAB2(SCH_1):PAGE185_I131@DEV_DISCRETE.CAP_A(CHIPS)':
 'A': CDS_PINID='A';
NODE_NAME     C2T4 1
 '@BASEBOARD_FAB2_LIB.BASEBOARD_FAB2(SCH_1):PAGE185_I132@DEV_DISCRETE.CAP_A(CHIPS)':
 'A': CDS_PINID='A';
NODE_NAME     C2T5 1
 '@BASEBOARD_FAB2_LIB.BASEBOARD_FAB2(SCH_1):PAGE185_I135@DEV_DISCRETE.CAP_A(CHIPS)':
 'A': CDS_PINID='A';
NODE_NAME     R8F36 1
 '@BASEBOARD_FAB2_LIB.BASEBOARD_FAB2(SCH_1):PAGE185_I136@MSTR_DISCRETE.RES(CHIPS)':
 'A': CDS_PINID='A';
NODE_NAME     C1M24 1
 '@BASEBOARD_FAB2_LIB.BASEBOARD_FAB2(SCH_1):PAGE186_I10@DEV_DISCRETE.CAP_A(CHIPS)':
 'A': CDS_PINID='A';
NODE_NAME     C1M21 1
 '@BASEBOARD_FAB2_LIB.BASEBOARD_FAB2(SCH_1):PAGE186_I334@DEV_DISCRETE.CAP_A(CHIPS)':
 'A': CDS_PINID='A';
NODE_NAME     J9B3 18
 '@BASEBOARD_FAB2_LIB.BASEBOARD_FAB2(SCH_1):PAGE186_I336@MSTR_SCONN.SCONN120_A28699018(CHIPS)':
 'IO18': CDS_PINID='IO18';
NODE_NAME     J9B3 19
 '@BASEBOARD_FAB2_LIB.BASEBOARD_FAB2(SCH_1):PAGE186_I336@MSTR_SCONN.SCONN120_A28699018(CHIPS)':
 'IO19': CDS_PINID='IO19';
NODE_NAME     J9B3 20
 '@BASEBOARD_FAB2_LIB.BASEBOARD_FAB2(SCH_1):PAGE186_I336@MSTR_SCONN.SCONN120_A28699018(CHIPS)':
 'IO20': CDS_PINID='IO20';
NODE_NAME     J9B3 21
 '@BASEBOARD_FAB2_LIB.BASEBOARD_FAB2(SCH_1):PAGE186_I336@MSTR_SCONN.SCONN120_A28699018(CHIPS)':
 'IO21': CDS_PINID='IO21';
NODE_NAME     J9B3 22
 '@BASEBOARD_FAB2_LIB.BASEBOARD_FAB2(SCH_1):PAGE186_I336@MSTR_SCONN.SCONN120_A28699018(CHIPS)':
 'IO22': CDS_PINID='IO22';
NODE_NAME     J9B3 23
 '@BASEBOARD_FAB2_LIB.BASEBOARD_FAB2(SCH_1):PAGE186_I336@MSTR_SCONN.SCONN120_A28699018(CHIPS)':
 'IO23': CDS_PINID='IO23';
NODE_NAME     J9B3 24
 '@BASEBOARD_FAB2_LIB.BASEBOARD_FAB2(SCH_1):PAGE186_I336@MSTR_SCONN.SCONN120_A28699018(CHIPS)':
 'IO24': CDS_PINID='IO24';
NODE_NAME     J9B3 25
 '@BASEBOARD_FAB2_LIB.BASEBOARD_FAB2(SCH_1):PAGE186_I336@MSTR_SCONN.SCONN120_A28699018(CHIPS)':
 'IO25': CDS_PINID='IO25';
NODE_NAME     J4B2 D1
 '@BASEBOARD_FAB2_LIB.BASEBOARD_FAB2(SCH_1):PAGE193_I46@MSTR_SCONN.SCONN120_H61426002(CHIPS)':
 'IOD1': CDS_PINID='IOD1';
NODE_NAME     J6B1 D1
 '@BASEBOARD_FAB2_LIB.BASEBOARD_FAB2(SCH_1):PAGE194_I56@MSTR_SCONN.SCONN120_H61426002(CHIPS)':
 'IOD1': CDS_PINID='IOD1';
NODE_NAME     U1L3 3
 '@BASEBOARD_FAB2_LIB.BASEBOARD_FAB2(SCH_1):PAGE196_I80@MSTR_ANALOG.ADM809(CHIPS)':
 'VCC': CDS_PINID='VCC';
NODE_NAME     C1L16 1
 '@BASEBOARD_FAB2_LIB.BASEBOARD_FAB2(SCH_1):PAGE196_I81@DEV_DISCRETE.CAP_A(CHIPS)':
 'A': CDS_PINID='A';
NODE_NAME     EU2T1 6
 '@BASEBOARD_FAB2_LIB.BASEBOARD_FAB2(SCH_1):PAGE198_I1@MSTR_VREG.SLG55021(CHIPS)':
 'S': CDS_PINID='S';
NODE_NAME     C2U19 1
 '@BASEBOARD_FAB2_LIB.BASEBOARD_FAB2(SCH_1):PAGE198_I46@DEV_DISCRETE.CAP_A(CHIPS)':
 'A': CDS_PINID='A';
NODE_NAME     C2U2 1
 '@BASEBOARD_FAB2_LIB.BASEBOARD_FAB2(SCH_1):PAGE198_I47@MSTR_DISCRETE.CAP(CHIPS)':
 'A': CDS_PINID='A';
NODE_NAME     Q8G1 1
 '@BASEBOARD_FAB2_LIB.BASEBOARD_FAB2(SCH_1):PAGE198_I85@MSTR_DISCRETE.MOSFET_N(CHIPS)':
 'SRC': CDS_PINID='SRC';
NODE_NAME     C14W1 1
 '@BASEBOARD_FAB2_LIB.BASEBOARD_FAB2(SCH_1):PAGE248_I13@DEV_DISCRETE.CAP_A(CHIPS)':
 'A': CDS_PINID='A';
NODE_NAME     C14W2 1
 '@BASEBOARD_FAB2_LIB.BASEBOARD_FAB2(SCH_1):PAGE248_I17@DEV_DISCRETE.CAP_A(CHIPS)':
 'A': CDS_PINID='A';
NODE_NAME     R25W129 1
 '@BASEBOARD_FAB2_LIB.BASEBOARD_FAB2(SCH_1):PAGE146_I152@MSTR_DISCRETE.RES(CHIPS)':
 'A': CDS_PINID='A';
NODE_NAME     R25W130 1
 '@BASEBOARD_FAB2_LIB.BASEBOARD_FAB2(SCH_1):PAGE146_I153@MSTR_DISCRETE.RES(CHIPS)':
 'A': CDS_PINID='A';
NODE_NAME     R25W131 1
 '@BASEBOARD_FAB2_LIB.BASEBOARD_FAB2(SCH_1):PAGE255_I30@MSTR_DISCRETE.RES(CHIPS)':
 'A': CDS_PINID='A';
NODE_NAME     R25W134 1
 '@BASEBOARD_FAB2_LIB.BASEBOARD_FAB2(SCH_1):PAGE255_I43@MSTR_DISCRETE.RES(CHIPS)':
 'A': CDS_PINID='A';
NODE_NAME     J8F1 2
 '@BASEBOARD_FAB2_LIB.BASEBOARD_FAB2(SCH_1):PAGE185_I143@W_HDL.SKT-MINI67P-41-GP(CHIPS)':
 '2': CDS_PINID='\2\';
NODE_NAME     J8F1 4
 '@BASEBOARD_FAB2_LIB.BASEBOARD_FAB2(SCH_1):PAGE185_I143@W_HDL.SKT-MINI67P-41-GP(CHIPS)':
 '4': CDS_PINID='\4\';
NODE_NAME     J8F1 12
 '@BASEBOARD_FAB2_LIB.BASEBOARD_FAB2(SCH_1):PAGE185_I143@W_HDL.SKT-MINI67P-41-GP(CHIPS)':
 '12': CDS_PINID='\12\';
NODE_NAME     J8F1 14
 '@BASEBOARD_FAB2_LIB.BASEBOARD_FAB2(SCH_1):PAGE185_I143@W_HDL.SKT-MINI67P-41-GP(CHIPS)':
 '14': CDS_PINID='\14\';
NODE_NAME     J8F1 16
 '@BASEBOARD_FAB2_LIB.BASEBOARD_FAB2(SCH_1):PAGE185_I143@W_HDL.SKT-MINI67P-41-GP(CHIPS)':
 '16': CDS_PINID='\16\';
NODE_NAME     J8F1 18
 '@BASEBOARD_FAB2_LIB.BASEBOARD_FAB2(SCH_1):PAGE185_I143@W_HDL.SKT-MINI67P-41-GP(CHIPS)':
 '18': CDS_PINID='\18\';
NODE_NAME     J8F1 70
 '@BASEBOARD_FAB2_LIB.BASEBOARD_FAB2(SCH_1):PAGE185_I143@W_HDL.SKT-MINI67P-41-GP(CHIPS)':
 '70': CDS_PINID='\70\';
NODE_NAME     J8F1 72
 '@BASEBOARD_FAB2_LIB.BASEBOARD_FAB2(SCH_1):PAGE185_I143@W_HDL.SKT-MINI67P-41-GP(CHIPS)':
 '72': CDS_PINID='\72\';
NODE_NAME     J8F1 74
 '@BASEBOARD_FAB2_LIB.BASEBOARD_FAB2(SCH_1):PAGE185_I143@W_HDL.SKT-MINI67P-41-GP(CHIPS)':
 '74': CDS_PINID='\74\';
NODE_NAME     R6U15 1
 '@BASEBOARD_FAB2_LIB.BASEBOARD_FAB2(SCH_1):PAGE221_I5@MSTR_DISCRETE.RES(CHIPS)':
 'A': CDS_PINID='A';
NODE_NAME     R6U4 1
 '@BASEBOARD_FAB2_LIB.BASEBOARD_FAB2(SCH_1):PAGE221_I14@MSTR_DISCRETE.RES(CHIPS)':
 'A': CDS_PINID='A';
NODE_NAME     R4G18 1
 '@BASEBOARD_FAB2_LIB.BASEBOARD_FAB2(SCH_1):PAGE221_I25@MSTR_DISCRETE.RES(CHIPS)':
 'A': CDS_PINID='A';
NODE_NAME     R6L4 1
 '@BASEBOARD_FAB2_LIB.BASEBOARD_FAB2(SCH_1):PAGE222_I5@MSTR_DISCRETE.RES(CHIPS)':
 'A': CDS_PINID='A';
NODE_NAME     R6L11 1
 '@BASEBOARD_FAB2_LIB.BASEBOARD_FAB2(SCH_1):PAGE222_I10@MSTR_DISCRETE.RES(CHIPS)':
 'A': CDS_PINID='A';
NODE_NAME     R6L9 1
 '@BASEBOARD_FAB2_LIB.BASEBOARD_FAB2(SCH_1):PAGE222_I23@MSTR_DISCRETE.RES(CHIPS)':
 'A': CDS_PINID='A';
NODE_NAME     R6U3 1
 '@BASEBOARD_FAB2_LIB.BASEBOARD_FAB2(SCH_1):PAGE229_I5@MSTR_DISCRETE.RES(CHIPS)':
 'A': CDS_PINID='A';
NODE_NAME     R6U7 1
 '@BASEBOARD_FAB2_LIB.BASEBOARD_FAB2(SCH_1):PAGE229_I9@MSTR_DISCRETE.RES(CHIPS)':
 'A': CDS_PINID='A';
NODE_NAME     R4G17 1
 '@BASEBOARD_FAB2_LIB.BASEBOARD_FAB2(SCH_1):PAGE229_I24@MSTR_DISCRETE.RES(CHIPS)':
 'A': CDS_PINID='A';
NODE_NAME     R6L5 1
 '@BASEBOARD_FAB2_LIB.BASEBOARD_FAB2(SCH_1):PAGE230_I5@MSTR_DISCRETE.RES(CHIPS)':
 'A': CDS_PINID='A';
NODE_NAME     R6L8 1
 '@BASEBOARD_FAB2_LIB.BASEBOARD_FAB2(SCH_1):PAGE230_I13@MSTR_DISCRETE.RES(CHIPS)':
 'A': CDS_PINID='A';
NODE_NAME     R4A5 1
 '@BASEBOARD_FAB2_LIB.BASEBOARD_FAB2(SCH_1):PAGE230_I21@MSTR_DISCRETE.RES(CHIPS)':
 'A': CDS_PINID='A';
NODE_NAME     R3P45 1
 '@BASEBOARD_FAB2_LIB.BASEBOARD_FAB2(SCH_1):PAGE92_I110@W_HDL.374R2F-1-GP(CHIPS)':
 '1': CDS_PINID='\1\';
NODE_NAME     R7D33 1
 '@BASEBOARD_FAB2_LIB.BASEBOARD_FAB2(SCH_1):PAGE92_I111@W_HDL.374R2F-1-GP(CHIPS)':
 '1': CDS_PINID='\1\';
NODE_NAME     R2T36 1
 '@BASEBOARD_FAB2_LIB.BASEBOARD_FAB2(SCH_1):PAGE93_I148@W_HDL.374R2F-1-GP(CHIPS)':
 '1': CDS_PINID='\1\';
NODE_NAME     R1U43 1
 '@BASEBOARD_FAB2_LIB.BASEBOARD_FAB2(SCH_1):PAGE152_I106@W_HDL.374R2F-1-GP(CHIPS)':
 '1': CDS_PINID='\1\';
NODE_NAME     R32W1 1
 '@BASEBOARD_FAB2_LIB.BASEBOARD_FAB2(SCH_1):PAGE185_I208@MSTR_DISCRETE.RES(CHIPS)':
 'A': CDS_PINID='A';
NODE_NAME     R6P48 1
 '@BASEBOARD_FAB2_LIB.BASEBOARD_FAB2(SCH_1):PAGE102_I115@MSTR_DISCRETE.RES(CHIPS)':
 'A': CDS_PINID='A';
NET_NAME
'P3V3_DB1200'
 '@BASEBOARD_FAB2_LIB.BASEBOARD_FAB2(SCH_1):P3V3_DB1200':
 C_SIGNAL='@baseboard_fab2_lib.baseboard_fab2(sch_1):p3v3_db1200';
NODE_NAME     EU4D2 24
 '@BASEBOARD_FAB2_LIB.BASEBOARD_FAB2(SCH_1):PAGE102_I1@MSTR_CLOCK.NB3W1200L(CHIPS)':
 'VDD'<0>: CDS_PINID='VDD(0)';
NODE_NAME     EU4D2 40
 '@BASEBOARD_FAB2_LIB.BASEBOARD_FAB2(SCH_1):PAGE102_I1@MSTR_CLOCK.NB3W1200L(CHIPS)':
 'VDD'<1>: CDS_PINID='VDD(1)';
NODE_NAME     EU4D2 57
 '@BASEBOARD_FAB2_LIB.BASEBOARD_FAB2(SCH_1):PAGE102_I1@MSTR_CLOCK.NB3W1200L(CHIPS)':
 'VDD'<2>: CDS_PINID='VDD(2)';
NODE_NAME     EU4D2 25
 '@BASEBOARD_FAB2_LIB.BASEBOARD_FAB2(SCH_1):PAGE102_I1@MSTR_CLOCK.NB3W1200L(CHIPS)':
 'VDDIO'<0>: CDS_PINID='VDDIO(0)';
NODE_NAME     EU4D2 32
 '@BASEBOARD_FAB2_LIB.BASEBOARD_FAB2(SCH_1):PAGE102_I1@MSTR_CLOCK.NB3W1200L(CHIPS)':
 'VDDIO'<1>: CDS_PINID='VDDIO(1)';
NODE_NAME     EU4D2 49
 '@BASEBOARD_FAB2_LIB.BASEBOARD_FAB2(SCH_1):PAGE102_I1@MSTR_CLOCK.NB3W1200L(CHIPS)':
 'VDDIO'<2>: CDS_PINID='VDDIO(2)';
NODE_NAME     EU4D2 56
 '@BASEBOARD_FAB2_LIB.BASEBOARD_FAB2(SCH_1):PAGE102_I1@MSTR_CLOCK.NB3W1200L(CHIPS)':
 'VDDIO'<3>: CDS_PINID='VDDIO(3)';
NODE_NAME     FB6P1 2
 '@BASEBOARD_FAB2_LIB.BASEBOARD_FAB2(SCH_1):PAGE102_I8@MSTR_DISCRETE.FERRITE(CHIPS)':
 'B': CDS_PINID='B';
NODE_NAME     C3D22 1
 '@BASEBOARD_FAB2_LIB.BASEBOARD_FAB2(SCH_1):PAGE102_I10@MSTR_DISCRETE.CAP(CHIPS)':
 'A': CDS_PINID='A';
NODE_NAME     C6P4 1
 '@BASEBOARD_FAB2_LIB.BASEBOARD_FAB2(SCH_1):PAGE102_I11@DEV_DISCRETE.CAP_A(CHIPS)':
 'A': CDS_PINID='A';
NODE_NAME     C6P6 1
 '@BASEBOARD_FAB2_LIB.BASEBOARD_FAB2(SCH_1):PAGE102_I12@DEV_DISCRETE.CAP_A(CHIPS)':
 'A': CDS_PINID='A';
NODE_NAME     C6P10 1
 '@BASEBOARD_FAB2_LIB.BASEBOARD_FAB2(SCH_1):PAGE102_I13@DEV_DISCRETE.CAP_A(CHIPS)':
 'A': CDS_PINID='A';
NODE_NAME     C6P5 1
 '@BASEBOARD_FAB2_LIB.BASEBOARD_FAB2(SCH_1):PAGE102_I14@DEV_DISCRETE.CAP_A(CHIPS)':
 'A': CDS_PINID='A';
NODE_NAME     C6P12 1
 '@BASEBOARD_FAB2_LIB.BASEBOARD_FAB2(SCH_1):PAGE102_I15@DEV_DISCRETE.CAP_A(CHIPS)':
 'A': CDS_PINID='A';
NODE_NAME     C6P11 1
 '@BASEBOARD_FAB2_LIB.BASEBOARD_FAB2(SCH_1):PAGE102_I16@DEV_DISCRETE.CAP_A(CHIPS)':
 'A': CDS_PINID='A';
NODE_NAME     R3D14 1
 '@BASEBOARD_FAB2_LIB.BASEBOARD_FAB2(SCH_1):PAGE102_I21@MSTR_DISCRETE.RES(CHIPS)':
 'A': CDS_PINID='A';
NODE_NAME     R6P25 1
 '@BASEBOARD_FAB2_LIB.BASEBOARD_FAB2(SCH_1):PAGE102_I26@MSTR_DISCRETE.RES(CHIPS)':
 'A': CDS_PINID='A';
NODE_NAME     R4D38 1
 '@BASEBOARD_FAB2_LIB.BASEBOARD_FAB2(SCH_1):PAGE102_I37@MSTR_DISCRETE.RES(CHIPS)':
 'A': CDS_PINID='A';
NODE_NAME     R4D35 1
 '@BASEBOARD_FAB2_LIB.BASEBOARD_FAB2(SCH_1):PAGE102_I38@MSTR_DISCRETE.RES(CHIPS)':
 'A': CDS_PINID='A';
NODE_NAME     R4D40 1
 '@BASEBOARD_FAB2_LIB.BASEBOARD_FAB2(SCH_1):PAGE102_I45@MSTR_DISCRETE.RES(CHIPS)':
 'A': CDS_PINID='A';
NODE_NAME     R4D41 1
 '@BASEBOARD_FAB2_LIB.BASEBOARD_FAB2(SCH_1):PAGE102_I53@MSTR_DISCRETE.RES(CHIPS)':
 'A': CDS_PINID='A';
NODE_NAME     C6P9 1
 '@BASEBOARD_FAB2_LIB.BASEBOARD_FAB2(SCH_1):PAGE102_I79@DEV_DISCRETE.CAP_A(CHIPS)':
 'A': CDS_PINID='A';
NODE_NAME     R4W2 1
 '@BASEBOARD_FAB2_LIB.BASEBOARD_FAB2(SCH_1):PAGE102_I103@MSTR_DISCRETE.RES(CHIPS)':
 'A': CDS_PINID='A';
NODE_NAME     R4W3 1
 '@BASEBOARD_FAB2_LIB.BASEBOARD_FAB2(SCH_1):PAGE102_I105@MSTR_DISCRETE.RES(CHIPS)':
 'A': CDS_PINID='A';
NODE_NAME     R4W4 1
 '@BASEBOARD_FAB2_LIB.BASEBOARD_FAB2(SCH_1):PAGE102_I106@MSTR_DISCRETE.RES(CHIPS)':
 'A': CDS_PINID='A';
NODE_NAME     R4W6 1
 '@BASEBOARD_FAB2_LIB.BASEBOARD_FAB2(SCH_1):PAGE102_I109@MSTR_DISCRETE.RES(CHIPS)':
 'A': CDS_PINID='A';
NET_NAME
'P3V3_DB1200_A'
 '@BASEBOARD_FAB2_LIB.BASEBOARD_FAB2(SCH_1):P3V3_DB1200_A':
 C_SIGNAL='@baseboard_fab2_lib.baseboard_fab2(sch_1):p3v3_db1200_a';
NODE_NAME     EU4D2 1
 '@BASEBOARD_FAB2_LIB.BASEBOARD_FAB2(SCH_1):PAGE102_I1@MSTR_CLOCK.NB3W1200L(CHIPS)':
 'VDDA': CDS_PINID='VDDA';
NODE_NAME     C4D24 1
 '@BASEBOARD_FAB2_LIB.BASEBOARD_FAB2(SCH_1):PAGE102_I18@DEV_DISCRETE.CAP_A(CHIPS)':
 'A': CDS_PINID='A';
NODE_NAME     C4D23 1
 '@BASEBOARD_FAB2_LIB.BASEBOARD_FAB2(SCH_1):PAGE102_I19@DEV_DISCRETE.CAP_A(CHIPS)':
 'A': CDS_PINID='A';
NODE_NAME     R3D14 2
 '@BASEBOARD_FAB2_LIB.BASEBOARD_FAB2(SCH_1):PAGE102_I21@MSTR_DISCRETE.RES(CHIPS)':
 'B': CDS_PINID='B';
NET_NAME
'P3V3_DB1200_R'
 '@BASEBOARD_FAB2_LIB.BASEBOARD_FAB2(SCH_1):P3V3_DB1200_R':
 C_SIGNAL='@baseboard_fab2_lib.baseboard_fab2(sch_1):p3v3_db1200_r';
NODE_NAME     EU4D2 8
 '@BASEBOARD_FAB2_LIB.BASEBOARD_FAB2(SCH_1):PAGE102_I1@MSTR_CLOCK.NB3W1200L(CHIPS)':
 'VDDR': CDS_PINID='VDDR';
NODE_NAME     R6P25 2
 '@BASEBOARD_FAB2_LIB.BASEBOARD_FAB2(SCH_1):PAGE102_I26@MSTR_DISCRETE.RES(CHIPS)':
 'B': CDS_PINID='B';
NODE_NAME     C4D22 1
 '@BASEBOARD_FAB2_LIB.BASEBOARD_FAB2(SCH_1):PAGE102_I28@DEV_DISCRETE.CAP_A(CHIPS)':
 'A': CDS_PINID='A';
NODE_NAME     C4D27 1
 '@BASEBOARD_FAB2_LIB.BASEBOARD_FAB2(SCH_1):PAGE102_I30@DEV_DISCRETE.CAP_A(CHIPS)':
 'A': CDS_PINID='A';
NET_NAME
'P3V3_DB1200_R1'
 '@BASEBOARD_FAB2_LIB.BASEBOARD_FAB2(SCH_1):P3V3_DB1200_R1':
 C_SIGNAL='@baseboard_fab2_lib.baseboard_fab2(sch_1):p3v3_db1200_r1';
NODE_NAME     Q4W1 5
 '@BASEBOARD_FAB2_LIB.BASEBOARD_FAB2(SCH_1):PAGE102_I101@MSTR_DISCRETE.FET_N_DUAL(CHIPS)':
 'GATE'<0>: CDS_PINID='GATE(0)';
NODE_NAME     Q4W1 2
 '@BASEBOARD_FAB2_LIB.BASEBOARD_FAB2(SCH_1):PAGE102_I102@MSTR_DISCRETE.FET_N_DUAL(CHIPS)':
 'GATE'<0>: CDS_PINID='GATE(0)';
NODE_NAME     R4W2 2
 '@BASEBOARD_FAB2_LIB.BASEBOARD_FAB2(SCH_1):PAGE102_I103@MSTR_DISCRETE.RES(CHIPS)':
 'B': CDS_PINID='B';
NET_NAME
'P3V3_RTC_STBY'
 '@BASEBOARD_FAB2_LIB.BASEBOARD_FAB2(SCH_1):P3V3_RTC_STBY':
 C_SIGNAL='@baseboard_fab2_lib.baseboard_fab2(sch_1):p3v3_rtc_stby';
NODE_NAME     U7C1 AJ27
 '@BASEBOARD_FAB2_LIB.BASEBOARD_FAB2(SCH_1):PAGE122_I63@MSTR_U_PROC.LBG_CORE_QAT_EXT_D(CHIPS)':
 'VCCPRTC': CDS_PINID='VCCPRTC';
NODE_NAME     R7C10 1
 '@BASEBOARD_FAB2_LIB.BASEBOARD_FAB2(SCH_1):PAGE137_I13@MSTR_DISCRETE.RES(CHIPS)':
 'A': CDS_PINID='A';
NODE_NAME     R3N4 1
 '@BASEBOARD_FAB2_LIB.BASEBOARD_FAB2(SCH_1):PAGE137_I19@MSTR_DISCRETE.RES(CHIPS)':
 'A': CDS_PINID='A';
NODE_NAME     CR2U1 3
 '@BASEBOARD_FAB2_LIB.BASEBOARD_FAB2(SCH_1):PAGE196_I53@MSTR_DISCRETE.DIODE2A_DUAL(CHIPS)':
 'C': CDS_PINID='C';
NODE_NAME     C2U26 1
 '@BASEBOARD_FAB2_LIB.BASEBOARD_FAB2(SCH_1):PAGE196_I102@DEV_DISCRETE.CAP_A(CHIPS)':
 'A': CDS_PINID='A';
NET_NAME
'P3V3_STBY'
 '@BASEBOARD_FAB2_LIB.BASEBOARD_FAB2(SCH_1):P3V3_STBY':
 C_SIGNAL='@baseboard_fab2_lib.baseboard_fab2(sch_1):p3v3_stby';
NODE_NAME     R5N2 1
 '@BASEBOARD_FAB2_LIB.BASEBOARD_FAB2(SCH_1):PAGE21_I227@MSTR_DISCRETE.RES(CHIPS)':
 'A': CDS_PINID='A';
NODE_NAME     R5N1 1
 '@BASEBOARD_FAB2_LIB.BASEBOARD_FAB2(SCH_1):PAGE21_I238@MSTR_DISCRETE.RES(CHIPS)':
 'A': CDS_PINID='A';
NODE_NAME     R5N5 1
 '@BASEBOARD_FAB2_LIB.BASEBOARD_FAB2(SCH_1):PAGE21_I239@MSTR_DISCRETE.RES(CHIPS)':
 'A': CDS_PINID='A';
NODE_NAME     R5N3 1
 '@BASEBOARD_FAB2_LIB.BASEBOARD_FAB2(SCH_1):PAGE21_I240@MSTR_DISCRETE.RES(CHIPS)':
 'A': CDS_PINID='A';
NODE_NAME     R5N4 1
 '@BASEBOARD_FAB2_LIB.BASEBOARD_FAB2(SCH_1):PAGE21_I241@MSTR_DISCRETE.RES(CHIPS)':
 'A': CDS_PINID='A';
NODE_NAME     R4R5 1
 '@BASEBOARD_FAB2_LIB.BASEBOARD_FAB2(SCH_1):PAGE21_I258@MSTR_DISCRETE.RES(CHIPS)':
 'A': CDS_PINID='A';
NODE_NAME     U5D1 CY55
 '@BASEBOARD_FAB2_LIB.BASEBOARD_FAB2(SCH_1):PAGE38_I34@CHPSET_LIB.SKX_EXT_B(CHIPS)':
 'VCC33': CDS_PINID='VCC33';
NODE_NAME     R8N1 1
 '@BASEBOARD_FAB2_LIB.BASEBOARD_FAB2(SCH_1):PAGE55_I157@MSTR_DISCRETE.RES(CHIPS)':
 'A': CDS_PINID='A';
NODE_NAME     R8N4 1
 '@BASEBOARD_FAB2_LIB.BASEBOARD_FAB2(SCH_1):PAGE55_I158@MSTR_DISCRETE.RES(CHIPS)':
 'A': CDS_PINID='A';
NODE_NAME     R8N3 1
 '@BASEBOARD_FAB2_LIB.BASEBOARD_FAB2(SCH_1):PAGE55_I159@MSTR_DISCRETE.RES(CHIPS)':
 'A': CDS_PINID='A';
NODE_NAME     R8N5 1
 '@BASEBOARD_FAB2_LIB.BASEBOARD_FAB2(SCH_1):PAGE55_I160@MSTR_DISCRETE.RES(CHIPS)':
 'A': CDS_PINID='A';
NODE_NAME     R8N2 1
 '@BASEBOARD_FAB2_LIB.BASEBOARD_FAB2(SCH_1):PAGE55_I161@MSTR_DISCRETE.RES(CHIPS)':
 'A': CDS_PINID='A';
NODE_NAME     R6P39 1
 '@BASEBOARD_FAB2_LIB.BASEBOARD_FAB2(SCH_1):PAGE55_I181@MSTR_DISCRETE.RES(CHIPS)':
 'A': CDS_PINID='A';
NODE_NAME     U2D1 CY55
 '@BASEBOARD_FAB2_LIB.BASEBOARD_FAB2(SCH_1):PAGE72_I33@CHPSET_LIB.SKX_EXT_B(CHIPS)':
 'VCC33': CDS_PINID='VCC33';
NODE_NAME     R8D29 1
 '@BASEBOARD_FAB2_LIB.BASEBOARD_FAB2(SCH_1):PAGE89_I26@MSTR_DISCRETE.RES(CHIPS)':
 'A': CDS_PINID='A';
NODE_NAME     R8D31 1
 '@BASEBOARD_FAB2_LIB.BASEBOARD_FAB2(SCH_1):PAGE89_I27@MSTR_DISCRETE.RES(CHIPS)':
 'A': CDS_PINID='A';
NODE_NAME     R4U1 1
 '@BASEBOARD_FAB2_LIB.BASEBOARD_FAB2(SCH_1):PAGE94_I91@MSTR_DISCRETE.RES(CHIPS)':
 'A': CDS_PINID='A';
NODE_NAME     C7E3 1
 '@BASEBOARD_FAB2_LIB.BASEBOARD_FAB2(SCH_1):PAGE95_I92@DEV_DISCRETE.CAP_A(CHIPS)':
 'A': CDS_PINID='A';
NODE_NAME     C7E4 1
 '@BASEBOARD_FAB2_LIB.BASEBOARD_FAB2(SCH_1):PAGE95_I115@DEV_DISCRETE.CAP_A(CHIPS)':
 'A': CDS_PINID='A';
NODE_NAME     R3P36 1
 '@BASEBOARD_FAB2_LIB.BASEBOARD_FAB2(SCH_1):PAGE96_I36@MSTR_DISCRETE.RES(CHIPS)':
 'A': CDS_PINID='A';
NODE_NAME     U3P1 14
 '@BASEBOARD_FAB2_LIB.BASEBOARD_FAB2(SCH_1):PAGE96_I42@MSTR_DIGITAL.GTL2014(CHIPS)':
 'VCC': CDS_PINID='VCC';
NODE_NAME     U4C2 14
 '@BASEBOARD_FAB2_LIB.BASEBOARD_FAB2(SCH_1):PAGE96_I46@MSTR_DIGITAL.GTL2014(CHIPS)':
 'VCC': CDS_PINID='VCC';
NODE_NAME     R4C8 1
 '@BASEBOARD_FAB2_LIB.BASEBOARD_FAB2(SCH_1):PAGE96_I55@MSTR_DISCRETE.RES(CHIPS)':
 'A': CDS_PINID='A';
NODE_NAME     C3P42 1
 '@BASEBOARD_FAB2_LIB.BASEBOARD_FAB2(SCH_1):PAGE96_I73@DEV_DISCRETE.CAP_A(CHIPS)':
 'A': CDS_PINID='A';
NODE_NAME     C4C3 1
 '@BASEBOARD_FAB2_LIB.BASEBOARD_FAB2(SCH_1):PAGE96_I75@DEV_DISCRETE.CAP_A(CHIPS)':
 'A': CDS_PINID='A';
NODE_NAME     FB2T2 1
 '@BASEBOARD_FAB2_LIB.BASEBOARD_FAB2(SCH_1):PAGE101_I114@MSTR_DISCRETE.FERRITE(CHIPS)':
 'A': CDS_PINID='A';
NODE_NAME     C2T28 1
 '@BASEBOARD_FAB2_LIB.BASEBOARD_FAB2(SCH_1):PAGE101_I116@DEV_DISCRETE.CAP_A(CHIPS)':
 'A': CDS_PINID='A';
NODE_NAME     J8G1 25
 '@BASEBOARD_FAB2_LIB.BASEBOARD_FAB2(SCH_1):PAGE108_I258@MSTR_SCONN.SCONN200_H68296001(CHIPS)':
 'IO25': CDS_PINID='IO25';
NODE_NAME     C2U23 1
 '@BASEBOARD_FAB2_LIB.BASEBOARD_FAB2(SCH_1):PAGE108_I315@DEV_DISCRETE.CAP_A(CHIPS)':
 'A': CDS_PINID='A';
NODE_NAME     C2U22 1
 '@BASEBOARD_FAB2_LIB.BASEBOARD_FAB2(SCH_1):PAGE108_I318@DEV_DISCRETE.CAP_A(CHIPS)':
 'A': CDS_PINID='A';
NODE_NAME     R1L13 2
 '@BASEBOARD_FAB2_LIB.BASEBOARD_FAB2(SCH_1):PAGE111_I6@MSTR_DISCRETE.RES(CHIPS)':
 'B': CDS_PINID='B';
NODE_NAME     R9A14 2
 '@BASEBOARD_FAB2_LIB.BASEBOARD_FAB2(SCH_1):PAGE111_I11@MSTR_DISCRETE.RES(CHIPS)':
 'B': CDS_PINID='B';
NODE_NAME     R1L23 2
 '@BASEBOARD_FAB2_LIB.BASEBOARD_FAB2(SCH_1):PAGE111_I13@MSTR_DISCRETE.RES(CHIPS)':
 'B': CDS_PINID='B';
NODE_NAME     C1L11 1
 '@BASEBOARD_FAB2_LIB.BASEBOARD_FAB2(SCH_1):PAGE111_I87@DEV_DISCRETE.CAP_A(CHIPS)':
 'A': CDS_PINID='A';
NODE_NAME     U1M7 5
 '@BASEBOARD_FAB2_LIB.BASEBOARD_FAB2(SCH_1):PAGE112_I40@MSTR_ANALOG.NC7SB3157(CHIPS)':
 'VCC': CDS_PINID='VCC';
NODE_NAME     C1M36 1
 '@BASEBOARD_FAB2_LIB.BASEBOARD_FAB2(SCH_1):PAGE112_I42@DEV_DISCRETE.CAP_A(CHIPS)':
 'A': CDS_PINID='A';
NODE_NAME     C1M37 1
 '@BASEBOARD_FAB2_LIB.BASEBOARD_FAB2(SCH_1):PAGE112_I47@DEV_DISCRETE.CAP_A(CHIPS)':
 'A': CDS_PINID='A';
NODE_NAME     C1M30 1
 '@BASEBOARD_FAB2_LIB.BASEBOARD_FAB2(SCH_1):PAGE112_I131@DEV_DISCRETE.CAP_A(CHIPS)':
 'A': CDS_PINID='A';
NODE_NAME     C1L1 1
 '@BASEBOARD_FAB2_LIB.BASEBOARD_FAB2(SCH_1):PAGE112_I136@MSTR_DISCRETE.CAP(CHIPS)':
 'A': CDS_PINID='A';
NODE_NAME     C1L19 1
 '@BASEBOARD_FAB2_LIB.BASEBOARD_FAB2(SCH_1):PAGE112_I140@MSTR_DISCRETE.CAP(CHIPS)':
 'A': CDS_PINID='A';
NODE_NAME     U1M2 5
 '@BASEBOARD_FAB2_LIB.BASEBOARD_FAB2(SCH_1):PAGE113_I107@MSTR_ANALOG.NC7SB3157(CHIPS)':
 'VCC': CDS_PINID='VCC';
NODE_NAME     C1M31 1
 '@BASEBOARD_FAB2_LIB.BASEBOARD_FAB2(SCH_1):PAGE113_I116@DEV_DISCRETE.CAP_A(CHIPS)':
 'A': CDS_PINID='A';
NODE_NAME     C1M32 1
 '@BASEBOARD_FAB2_LIB.BASEBOARD_FAB2(SCH_1):PAGE113_I117@DEV_DISCRETE.CAP_A(CHIPS)':
 'A': CDS_PINID='A';
NODE_NAME     C1M28 1
 '@BASEBOARD_FAB2_LIB.BASEBOARD_FAB2(SCH_1):PAGE113_I119@DEV_DISCRETE.CAP_A(CHIPS)':
 'A': CDS_PINID='A';
NODE_NAME     U2M1 5
 '@BASEBOARD_FAB2_LIB.BASEBOARD_FAB2(SCH_1):PAGE113_I255@MSTR_ANALOG.NC7SB3157(CHIPS)':
 'VCC': CDS_PINID='VCC';
NODE_NAME     C1M34 1
 '@BASEBOARD_FAB2_LIB.BASEBOARD_FAB2(SCH_1):PAGE113_I265@DEV_DISCRETE.CAP_A(CHIPS)':
 'A': CDS_PINID='A';
NODE_NAME     C1M35 1
 '@BASEBOARD_FAB2_LIB.BASEBOARD_FAB2(SCH_1):PAGE113_I266@DEV_DISCRETE.CAP_A(CHIPS)':
 'A': CDS_PINID='A';
NODE_NAME     C1L20 1
 '@BASEBOARD_FAB2_LIB.BASEBOARD_FAB2(SCH_1):PAGE113_I267@DEV_DISCRETE.CAP_A(CHIPS)':
 'A': CDS_PINID='A';
NODE_NAME     R3N13 1
 '@BASEBOARD_FAB2_LIB.BASEBOARD_FAB2(SCH_1):PAGE118_I71@MSTR_DISCRETE.RES(CHIPS)':
 'A': CDS_PINID='A';
NODE_NAME     R2N6 1
 '@BASEBOARD_FAB2_LIB.BASEBOARD_FAB2(SCH_1):PAGE118_I128@MSTR_DISCRETE.RES(CHIPS)':
 'A': CDS_PINID='A';
NODE_NAME     C7D1 1
 '@BASEBOARD_FAB2_LIB.BASEBOARD_FAB2(SCH_1):PAGE118_I136@DEV_DISCRETE.CAP_A(CHIPS)':
 'A': CDS_PINID='A';
NODE_NAME     R7C23 1
 '@BASEBOARD_FAB2_LIB.BASEBOARD_FAB2(SCH_1):PAGE118_I144@MSTR_DISCRETE.RES(CHIPS)':
 'A': CDS_PINID='A';
NODE_NAME     R9A20 2
 '@BASEBOARD_FAB2_LIB.BASEBOARD_FAB2(SCH_1):PAGE119_I178@MSTR_DISCRETE.RES(CHIPS)':
 'B': CDS_PINID='B';
NODE_NAME     R9A18 1
 '@BASEBOARD_FAB2_LIB.BASEBOARD_FAB2(SCH_1):PAGE119_I183@MSTR_DISCRETE.RES(CHIPS)':
 'A': CDS_PINID='A';
NODE_NAME     R9A21 1
 '@BASEBOARD_FAB2_LIB.BASEBOARD_FAB2(SCH_1):PAGE119_I186@MSTR_DISCRETE.RES(CHIPS)':
 'A': CDS_PINID='A';
NODE_NAME     R2U48 1
 '@BASEBOARD_FAB2_LIB.BASEBOARD_FAB2(SCH_1):PAGE119_I213@MSTR_DISCRETE.RES(CHIPS)':
 'A': CDS_PINID='A';
NODE_NAME     R3N10 1
 '@BASEBOARD_FAB2_LIB.BASEBOARD_FAB2(SCH_1):PAGE121_I37@MSTR_DISCRETE.RES(CHIPS)':
 'A': CDS_PINID='A';
NODE_NAME     U7C1 BA46
 '@BASEBOARD_FAB2_LIB.BASEBOARD_FAB2(SCH_1):PAGE122_I63@MSTR_U_PROC.LBG_CORE_QAT_EXT_D(CHIPS)':
 'VCCP_3P3'<0>: CDS_PINID='VCCP_3P3(0)';
NODE_NAME     U7C1 BA45
 '@BASEBOARD_FAB2_LIB.BASEBOARD_FAB2(SCH_1):PAGE122_I63@MSTR_U_PROC.LBG_CORE_QAT_EXT_D(CHIPS)':
 'VCCP_3P3'<1>: CDS_PINID='VCCP_3P3(1)';
NODE_NAME     U7C1 AD24
 '@BASEBOARD_FAB2_LIB.BASEBOARD_FAB2(SCH_1):PAGE122_I63@MSTR_U_PROC.LBG_CORE_QAT_EXT_D(CHIPS)':
 'VCCP_3P3'<2>: CDS_PINID='VCCP_3P3(2)';
NODE_NAME     U7C1 AN24
 '@BASEBOARD_FAB2_LIB.BASEBOARD_FAB2(SCH_1):PAGE122_I63@MSTR_U_PROC.LBG_CORE_QAT_EXT_D(CHIPS)':
 'VCCP_3P3'<5>: CDS_PINID='VCCP_3P3(5)';
NODE_NAME     U7C1 AH24
 '@BASEBOARD_FAB2_LIB.BASEBOARD_FAB2(SCH_1):PAGE122_I63@MSTR_U_PROC.LBG_CORE_QAT_EXT_D(CHIPS)':
 'VCCPDSW_3P3': CDS_PINID='VCCPDSW_3P3';
NODE_NAME     U7C1 AW24
 '@BASEBOARD_FAB2_LIB.BASEBOARD_FAB2(SCH_1):PAGE122_I63@MSTR_U_PROC.LBG_CORE_QAT_EXT_D(CHIPS)':
 'VCCPGPPA': CDS_PINID='VCCPGPPA';
NODE_NAME     U7C1 BE26
 '@BASEBOARD_FAB2_LIB.BASEBOARD_FAB2(SCH_1):PAGE122_I63@MSTR_U_PROC.LBG_CORE_QAT_EXT_D(CHIPS)':
 'VCCPGPPB': CDS_PINID='VCCPGPPB';
NODE_NAME     U7C1 BE40
 '@BASEBOARD_FAB2_LIB.BASEBOARD_FAB2(SCH_1):PAGE122_I63@MSTR_U_PROC.LBG_CORE_QAT_EXT_D(CHIPS)':
 'VCCPGPPC': CDS_PINID='VCCPGPPC';
NODE_NAME     U7C1 BA43
 '@BASEBOARD_FAB2_LIB.BASEBOARD_FAB2(SCH_1):PAGE122_I63@MSTR_U_PROC.LBG_CORE_QAT_EXT_D(CHIPS)':
 'VCCPGPPD': CDS_PINID='VCCPGPPD';
NODE_NAME     U7C1 BE44
 '@BASEBOARD_FAB2_LIB.BASEBOARD_FAB2(SCH_1):PAGE122_I63@MSTR_U_PROC.LBG_CORE_QAT_EXT_D(CHIPS)':
 'VCCPGPPE': CDS_PINID='VCCPGPPE';
NODE_NAME     U7C1 AU27
 '@BASEBOARD_FAB2_LIB.BASEBOARD_FAB2(SCH_1):PAGE122_I63@MSTR_U_PROC.LBG_CORE_QAT_EXT_D(CHIPS)':
 'VCCPGPPF': CDS_PINID='VCCPGPPF';
NODE_NAME     U7C1 BA26
 '@BASEBOARD_FAB2_LIB.BASEBOARD_FAB2(SCH_1):PAGE122_I63@MSTR_U_PROC.LBG_CORE_QAT_EXT_D(CHIPS)':
 'VCCPGPPG': CDS_PINID='VCCPGPPG';
NODE_NAME     U7C1 BA24
 '@BASEBOARD_FAB2_LIB.BASEBOARD_FAB2(SCH_1):PAGE122_I63@MSTR_U_PROC.LBG_CORE_QAT_EXT_D(CHIPS)':
 'VCCPGPPH': CDS_PINID='VCCPGPPH';
NODE_NAME     U7C1 BB26
 '@BASEBOARD_FAB2_LIB.BASEBOARD_FAB2(SCH_1):PAGE122_I63@MSTR_U_PROC.LBG_CORE_QAT_EXT_D(CHIPS)':
 'VCCPGPPJ': CDS_PINID='VCCPGPPJ';
NODE_NAME     U7C1 AU24
 '@BASEBOARD_FAB2_LIB.BASEBOARD_FAB2(SCH_1):PAGE122_I63@MSTR_U_PROC.LBG_CORE_QAT_EXT_D(CHIPS)':
 'VCCPGPPK': CDS_PINID='VCCPGPPK';
NODE_NAME     U7C1 AG29
 '@BASEBOARD_FAB2_LIB.BASEBOARD_FAB2(SCH_1):PAGE122_I63@MSTR_U_PROC.LBG_CORE_QAT_EXT_D(CHIPS)':
 'VCCPRTCPRIM_3P3': CDS_PINID='VCCPRTCPRIM_3P3';
NODE_NAME     U7C1 AR24
 '@BASEBOARD_FAB2_LIB.BASEBOARD_FAB2(SCH_1):PAGE122_I63@MSTR_U_PROC.LBG_CORE_QAT_EXT_D(CHIPS)':
 'VCCPSPI': CDS_PINID='VCCPSPI';
NODE_NAME     U7C1 BA48
 '@BASEBOARD_FAB2_LIB.BASEBOARD_FAB2(SCH_1):PAGE122_I63@MSTR_U_PROC.LBG_CORE_QAT_EXT_D(CHIPS)':
 'VCCPUSBDSW_3P3': CDS_PINID='VCCPUSBDSW_3P3';
NODE_NAME     R8E6 1
 '@BASEBOARD_FAB2_LIB.BASEBOARD_FAB2(SCH_1):PAGE125_I21@MSTR_DISCRETE.RES(CHIPS)':
 'A': CDS_PINID='A';
NODE_NAME     R8C18 1
 '@BASEBOARD_FAB2_LIB.BASEBOARD_FAB2(SCH_1):PAGE125_I40@MSTR_DISCRETE.RES(CHIPS)':
 'A': CDS_PINID='A';
NODE_NAME     R7D13 1
 '@BASEBOARD_FAB2_LIB.BASEBOARD_FAB2(SCH_1):PAGE125_I60@MSTR_DISCRETE.RES(CHIPS)':
 'A': CDS_PINID='A';
NODE_NAME     R3N2 1
 '@BASEBOARD_FAB2_LIB.BASEBOARD_FAB2(SCH_1):PAGE125_I72@MSTR_DISCRETE.RES(CHIPS)':
 'A': CDS_PINID='A';
NODE_NAME     R3N17 1
 '@BASEBOARD_FAB2_LIB.BASEBOARD_FAB2(SCH_1):PAGE125_I78@MSTR_DISCRETE.RES(CHIPS)':
 'A': CDS_PINID='A';
NODE_NAME     R2N14 1
 '@BASEBOARD_FAB2_LIB.BASEBOARD_FAB2(SCH_1):PAGE125_I83@MSTR_DISCRETE.RES(CHIPS)':
 'A': CDS_PINID='A';
NODE_NAME     R1D35 1
 '@BASEBOARD_FAB2_LIB.BASEBOARD_FAB2(SCH_1):PAGE126_I12@MSTR_DISCRETE.RES(CHIPS)':
 'A': CDS_PINID='A';
NODE_NAME     R8C9 1
 '@BASEBOARD_FAB2_LIB.BASEBOARD_FAB2(SCH_1):PAGE126_I20@MSTR_DISCRETE.RES(CHIPS)':
 'A': CDS_PINID='A';
NODE_NAME     R3P62 1
 '@BASEBOARD_FAB2_LIB.BASEBOARD_FAB2(SCH_1):PAGE126_I22@MSTR_DISCRETE.RES(CHIPS)':
 'A': CDS_PINID='A';
NODE_NAME     C7D2 1
 '@BASEBOARD_FAB2_LIB.BASEBOARD_FAB2(SCH_1):PAGE130_I2@MSTR_DISCRETE.CAP(CHIPS)':
 'A': CDS_PINID='A';
NODE_NAME     C2N26 1
 '@BASEBOARD_FAB2_LIB.BASEBOARD_FAB2(SCH_1):PAGE130_I4@DEV_DISCRETE.CAP_A(CHIPS)':
 'A': CDS_PINID='A';
NODE_NAME     C2N19 1
 '@BASEBOARD_FAB2_LIB.BASEBOARD_FAB2(SCH_1):PAGE130_I7@DEV_DISCRETE.CAP_A(CHIPS)':
 'A': CDS_PINID='A';
NODE_NAME     C2N24 1
 '@BASEBOARD_FAB2_LIB.BASEBOARD_FAB2(SCH_1):PAGE130_I8@MSTR_DISCRETE.CAP(CHIPS)':
 'A': CDS_PINID='A';
NODE_NAME     C2N22 1
 '@BASEBOARD_FAB2_LIB.BASEBOARD_FAB2(SCH_1):PAGE130_I9@MSTR_DISCRETE.CAP(CHIPS)':
 'A': CDS_PINID='A';
NODE_NAME     C2N20 1
 '@BASEBOARD_FAB2_LIB.BASEBOARD_FAB2(SCH_1):PAGE130_I12@DEV_DISCRETE.CAP_A(CHIPS)':
 'A': CDS_PINID='A';
NODE_NAME     C2N21 1
 '@BASEBOARD_FAB2_LIB.BASEBOARD_FAB2(SCH_1):PAGE130_I15@MSTR_DISCRETE.CAP(CHIPS)':
 'A': CDS_PINID='A';
NODE_NAME     C8C3 1
 '@BASEBOARD_FAB2_LIB.BASEBOARD_FAB2(SCH_1):PAGE130_I19@MSTR_DISCRETE.CAP(CHIPS)':
 'A': CDS_PINID='A';
NODE_NAME     C8C4 1
 '@BASEBOARD_FAB2_LIB.BASEBOARD_FAB2(SCH_1):PAGE130_I20@MSTR_DISCRETE.CAP(CHIPS)':
 'A': CDS_PINID='A';
NODE_NAME     C8C5 1
 '@BASEBOARD_FAB2_LIB.BASEBOARD_FAB2(SCH_1):PAGE130_I21@MSTR_DISCRETE.CAP(CHIPS)':
 'A': CDS_PINID='A';
NODE_NAME     C8C6 1
 '@BASEBOARD_FAB2_LIB.BASEBOARD_FAB2(SCH_1):PAGE130_I22@MSTR_DISCRETE.CAP(CHIPS)':
 'A': CDS_PINID='A';
NODE_NAME     C2N23 1
 '@BASEBOARD_FAB2_LIB.BASEBOARD_FAB2(SCH_1):PAGE130_I24@MSTR_DISCRETE.CAP(CHIPS)':
 'A': CDS_PINID='A';
NODE_NAME     C2N14 1
 '@BASEBOARD_FAB2_LIB.BASEBOARD_FAB2(SCH_1):PAGE130_I25@MSTR_DISCRETE.CAP(CHIPS)':
 'A': CDS_PINID='A';
NODE_NAME     C2N17 1
 '@BASEBOARD_FAB2_LIB.BASEBOARD_FAB2(SCH_1):PAGE130_I28@MSTR_DISCRETE.CAP(CHIPS)':
 'A': CDS_PINID='A';
NODE_NAME     C2N18 1
 '@BASEBOARD_FAB2_LIB.BASEBOARD_FAB2(SCH_1):PAGE130_I29@DEV_DISCRETE.CAP_A(CHIPS)':
 'A': CDS_PINID='A';
NODE_NAME     C2N25 1
 '@BASEBOARD_FAB2_LIB.BASEBOARD_FAB2(SCH_1):PAGE130_I34@DEV_DISCRETE.CAP_A(CHIPS)':
 'A': CDS_PINID='A';
NODE_NAME     C2M16 1
 '@BASEBOARD_FAB2_LIB.BASEBOARD_FAB2(SCH_1):PAGE130_I37@DEV_DISCRETE.CAP_A(CHIPS)':
 'A': CDS_PINID='A';
NODE_NAME     C3N23 1
 '@BASEBOARD_FAB2_LIB.BASEBOARD_FAB2(SCH_1):PAGE130_I42@DEV_DISCRETE.CAP_A(CHIPS)':
 'A': CDS_PINID='A';
NODE_NAME     R7D8 1
 '@BASEBOARD_FAB2_LIB.BASEBOARD_FAB2(SCH_1):PAGE133_I200@MSTR_DISCRETE.RES(CHIPS)':
 'A': CDS_PINID='A';
NODE_NAME     R7D10 1
 '@BASEBOARD_FAB2_LIB.BASEBOARD_FAB2(SCH_1):PAGE133_I202@MSTR_DISCRETE.RES(CHIPS)':
 'A': CDS_PINID='A';
NODE_NAME     R7D12 1
 '@BASEBOARD_FAB2_LIB.BASEBOARD_FAB2(SCH_1):PAGE133_I237@MSTR_DISCRETE.RES(CHIPS)':
 'A': CDS_PINID='A';
NODE_NAME     R7D3 1
 '@BASEBOARD_FAB2_LIB.BASEBOARD_FAB2(SCH_1):PAGE133_I243@MSTR_DISCRETE.RES(CHIPS)':
 'A': CDS_PINID='A';
NODE_NAME     R7D4 1
 '@BASEBOARD_FAB2_LIB.BASEBOARD_FAB2(SCH_1):PAGE133_I245@MSTR_DISCRETE.RES(CHIPS)':
 'A': CDS_PINID='A';
NODE_NAME     R2N16 1
 '@BASEBOARD_FAB2_LIB.BASEBOARD_FAB2(SCH_1):PAGE133_I247@MSTR_DISCRETE.RES(CHIPS)':
 'A': CDS_PINID='A';
NODE_NAME     R2R5 1
 '@BASEBOARD_FAB2_LIB.BASEBOARD_FAB2(SCH_1):PAGE133_I258@MSTR_DISCRETE.RES(CHIPS)':
 'A': CDS_PINID='A';
NODE_NAME     R2N9 1
 '@BASEBOARD_FAB2_LIB.BASEBOARD_FAB2(SCH_1):PAGE133_I267@MSTR_DISCRETE.RES(CHIPS)':
 'A': CDS_PINID='A';
NODE_NAME     R8B23 1
 '@BASEBOARD_FAB2_LIB.BASEBOARD_FAB2(SCH_1):PAGE133_I280@MSTR_DISCRETE.RES(CHIPS)':
 'A': CDS_PINID='A';
NODE_NAME     R8B30 1
 '@BASEBOARD_FAB2_LIB.BASEBOARD_FAB2(SCH_1):PAGE133_I282@MSTR_DISCRETE.RES(CHIPS)':
 'A': CDS_PINID='A';
NODE_NAME     R2M4 1
 '@BASEBOARD_FAB2_LIB.BASEBOARD_FAB2(SCH_1):PAGE133_I284@MSTR_DISCRETE.RES(CHIPS)':
 'A': CDS_PINID='A';
NODE_NAME     R8C4 1
 '@BASEBOARD_FAB2_LIB.BASEBOARD_FAB2(SCH_1):PAGE133_I286@MSTR_DISCRETE.RES(CHIPS)':
 'A': CDS_PINID='A';
NODE_NAME     R7B6 1
 '@BASEBOARD_FAB2_LIB.BASEBOARD_FAB2(SCH_1):PAGE133_I295@MSTR_DISCRETE.RES(CHIPS)':
 'A': CDS_PINID='A';
NODE_NAME     R7C8 1
 '@BASEBOARD_FAB2_LIB.BASEBOARD_FAB2(SCH_1):PAGE133_I296@MSTR_DISCRETE.RES(CHIPS)':
 'A': CDS_PINID='A';
NODE_NAME     R7C5 1
 '@BASEBOARD_FAB2_LIB.BASEBOARD_FAB2(SCH_1):PAGE133_I297@MSTR_DISCRETE.RES(CHIPS)':
 'A': CDS_PINID='A';
NODE_NAME     R8D14 1
 '@BASEBOARD_FAB2_LIB.BASEBOARD_FAB2(SCH_1):PAGE133_I301@MSTR_DISCRETE.RES(CHIPS)':
 'A': CDS_PINID='A';
NODE_NAME     R8C6 1
 '@BASEBOARD_FAB2_LIB.BASEBOARD_FAB2(SCH_1):PAGE133_I303@MSTR_DISCRETE.RES(CHIPS)':
 'A': CDS_PINID='A';
NODE_NAME     R8C2 1
 '@BASEBOARD_FAB2_LIB.BASEBOARD_FAB2(SCH_1):PAGE133_I304@MSTR_DISCRETE.RES(CHIPS)':
 'A': CDS_PINID='A';
NODE_NAME     R7D6 1
 '@BASEBOARD_FAB2_LIB.BASEBOARD_FAB2(SCH_1):PAGE133_I306@MSTR_DISCRETE.RES(CHIPS)':
 'A': CDS_PINID='A';
NODE_NAME     R8B31 1
 '@BASEBOARD_FAB2_LIB.BASEBOARD_FAB2(SCH_1):PAGE133_I307@MSTR_DISCRETE.RES(CHIPS)':
 'A': CDS_PINID='A';
NODE_NAME     R2N7 1
 '@BASEBOARD_FAB2_LIB.BASEBOARD_FAB2(SCH_1):PAGE133_I309@MSTR_DISCRETE.RES(CHIPS)':
 'A': CDS_PINID='A';
NODE_NAME     R8C1 1
 '@BASEBOARD_FAB2_LIB.BASEBOARD_FAB2(SCH_1):PAGE133_I326@MSTR_DISCRETE.RES(CHIPS)':
 'A': CDS_PINID='A';
NODE_NAME     R8C7 1
 '@BASEBOARD_FAB2_LIB.BASEBOARD_FAB2(SCH_1):PAGE133_I327@MSTR_DISCRETE.RES(CHIPS)':
 'A': CDS_PINID='A';
NODE_NAME     R7D7 1
 '@BASEBOARD_FAB2_LIB.BASEBOARD_FAB2(SCH_1):PAGE133_I331@MSTR_DISCRETE.RES(CHIPS)':
 'A': CDS_PINID='A';
NODE_NAME     R7D2 1
 '@BASEBOARD_FAB2_LIB.BASEBOARD_FAB2(SCH_1):PAGE133_I332@MSTR_DISCRETE.RES(CHIPS)':
 'A': CDS_PINID='A';
NODE_NAME     R8C25 1
 '@BASEBOARD_FAB2_LIB.BASEBOARD_FAB2(SCH_1):PAGE133_I333@MSTR_DISCRETE.RES(CHIPS)':
 'A': CDS_PINID='A';
NODE_NAME     R2N32 1
 '@BASEBOARD_FAB2_LIB.BASEBOARD_FAB2(SCH_1):PAGE133_I341@MSTR_DISCRETE.RES(CHIPS)':
 'A': CDS_PINID='A';
NODE_NAME     R2M8 1
 '@BASEBOARD_FAB2_LIB.BASEBOARD_FAB2(SCH_1):PAGE133_I349@MSTR_DISCRETE.RES(CHIPS)':
 'A': CDS_PINID='A';
NODE_NAME     R2N29 1
 '@BASEBOARD_FAB2_LIB.BASEBOARD_FAB2(SCH_1):PAGE133_I352@MSTR_DISCRETE.RES(CHIPS)':
 'A': CDS_PINID='A';
NODE_NAME     R2P22 1
 '@BASEBOARD_FAB2_LIB.BASEBOARD_FAB2(SCH_1):PAGE133_I360@MSTR_DISCRETE.RES(CHIPS)':
 'A': CDS_PINID='A';
NODE_NAME     R8D44 1
 '@BASEBOARD_FAB2_LIB.BASEBOARD_FAB2(SCH_1):PAGE133_I362@MSTR_DISCRETE.RES(CHIPS)':
 'A': CDS_PINID='A';
NODE_NAME     R2P17 1
 '@BASEBOARD_FAB2_LIB.BASEBOARD_FAB2(SCH_1):PAGE134_I3@MSTR_DISCRETE.RES(CHIPS)':
 'A': CDS_PINID='A';
NODE_NAME     R2P19 1
 '@BASEBOARD_FAB2_LIB.BASEBOARD_FAB2(SCH_1):PAGE135_I107@MSTR_DISCRETE.RES(CHIPS)':
 'A': CDS_PINID='A';
NODE_NAME     R2N23 1
 '@BASEBOARD_FAB2_LIB.BASEBOARD_FAB2(SCH_1):PAGE135_I112@MSTR_DISCRETE.RES(CHIPS)':
 'A': CDS_PINID='A';
NODE_NAME     R9A12 2
 '@BASEBOARD_FAB2_LIB.BASEBOARD_FAB2(SCH_1):PAGE135_I117@MSTR_DISCRETE.RES(CHIPS)':
 'B': CDS_PINID='B';
NODE_NAME     R8D21 1
 '@BASEBOARD_FAB2_LIB.BASEBOARD_FAB2(SCH_1):PAGE135_I120@MSTR_DISCRETE.RES(CHIPS)':
 'A': CDS_PINID='A';
NODE_NAME     R7D30 1
 '@BASEBOARD_FAB2_LIB.BASEBOARD_FAB2(SCH_1):PAGE135_I121@MSTR_DISCRETE.RES(CHIPS)':
 'A': CDS_PINID='A';
NODE_NAME     R9A16 2
 '@BASEBOARD_FAB2_LIB.BASEBOARD_FAB2(SCH_1):PAGE135_I129@MSTR_DISCRETE.RES(CHIPS)':
 'B': CDS_PINID='B';
NODE_NAME     R7G26 1
 '@BASEBOARD_FAB2_LIB.BASEBOARD_FAB2(SCH_1):PAGE136_I101@MSTR_DISCRETE.RES(CHIPS)':
 'A': CDS_PINID='A';
NODE_NAME     C8E8 1
 '@BASEBOARD_FAB2_LIB.BASEBOARD_FAB2(SCH_1):PAGE136_I128@DEV_DISCRETE.CAP_A(CHIPS)':
 'A': CDS_PINID='A';
NODE_NAME     R8E14 1
 '@BASEBOARD_FAB2_LIB.BASEBOARD_FAB2(SCH_1):PAGE136_I133@MSTR_DISCRETE.RES(CHIPS)':
 'A': CDS_PINID='A';
NODE_NAME     R7G31 1
 '@BASEBOARD_FAB2_LIB.BASEBOARD_FAB2(SCH_1):PAGE136_I139@MSTR_DISCRETE.RES(CHIPS)':
 'A': CDS_PINID='A';
NODE_NAME     R2N28 1
 '@BASEBOARD_FAB2_LIB.BASEBOARD_FAB2(SCH_1):PAGE136_I147@MSTR_DISCRETE.RES(CHIPS)':
 'A': CDS_PINID='A';
NODE_NAME     R7G27 1
 '@BASEBOARD_FAB2_LIB.BASEBOARD_FAB2(SCH_1):PAGE136_I155@MSTR_DISCRETE.RES(CHIPS)':
 'A': CDS_PINID='A';
NODE_NAME     R7C13 1
 '@BASEBOARD_FAB2_LIB.BASEBOARD_FAB2(SCH_1):PAGE137_I67@MSTR_DISCRETE.RES(CHIPS)':
 'A': CDS_PINID='A';
NODE_NAME     R2T53 1
 '@BASEBOARD_FAB2_LIB.BASEBOARD_FAB2(SCH_1):PAGE138_I83@MSTR_DISCRETE.RES(CHIPS)':
 'A': CDS_PINID='A';
NODE_NAME     R2T54 1
 '@BASEBOARD_FAB2_LIB.BASEBOARD_FAB2(SCH_1):PAGE138_I84@MSTR_DISCRETE.RES(CHIPS)':
 'A': CDS_PINID='A';
NODE_NAME     R8D17 1
 '@BASEBOARD_FAB2_LIB.BASEBOARD_FAB2(SCH_1):PAGE138_I87@MSTR_DISCRETE.RES(CHIPS)':
 'A': CDS_PINID='A';
NODE_NAME     R8D15 1
 '@BASEBOARD_FAB2_LIB.BASEBOARD_FAB2(SCH_1):PAGE138_I88@MSTR_DISCRETE.RES(CHIPS)':
 'A': CDS_PINID='A';
NODE_NAME     R2N8 1
 '@BASEBOARD_FAB2_LIB.BASEBOARD_FAB2(SCH_1):PAGE138_I89@MSTR_DISCRETE.RES(CHIPS)':
 'A': CDS_PINID='A';
NODE_NAME     R2N5 1
 '@BASEBOARD_FAB2_LIB.BASEBOARD_FAB2(SCH_1):PAGE138_I90@MSTR_DISCRETE.RES(CHIPS)':
 'A': CDS_PINID='A';
NODE_NAME     R2U11 1
 '@BASEBOARD_FAB2_LIB.BASEBOARD_FAB2(SCH_1):PAGE138_I97@MSTR_DISCRETE.RES(CHIPS)':
 'A': CDS_PINID='A';
NODE_NAME     R2U3 1
 '@BASEBOARD_FAB2_LIB.BASEBOARD_FAB2(SCH_1):PAGE138_I98@MSTR_DISCRETE.RES(CHIPS)':
 'A': CDS_PINID='A';
NODE_NAME     EU9E1 64
 '@BASEBOARD_FAB2_LIB.BASEBOARD_FAB2(SCH_1):PAGE139_I72@MSTR_INTEL.SPRINGVILLE(CHIPS)':
 'VDD3P3'<0>: CDS_PINID='VDD3P3(0)';
NODE_NAME     EU9E1 41
 '@BASEBOARD_FAB2_LIB.BASEBOARD_FAB2(SCH_1):PAGE139_I72@MSTR_INTEL.SPRINGVILLE(CHIPS)':
 'VDD3P3'<2>: CDS_PINID='VDD3P3(2)';
NODE_NAME     EU9E1 27
 '@BASEBOARD_FAB2_LIB.BASEBOARD_FAB2(SCH_1):PAGE139_I72@MSTR_INTEL.SPRINGVILLE(CHIPS)':
 'VDD3P3'<3>: CDS_PINID='VDD3P3(3)';
NODE_NAME     EU9E1 10
 '@BASEBOARD_FAB2_LIB.BASEBOARD_FAB2(SCH_1):PAGE139_I72@MSTR_INTEL.SPRINGVILLE(CHIPS)':
 'VDD3P3'<4>: CDS_PINID='VDD3P3(4)';
NODE_NAME     C1R22 1
 '@BASEBOARD_FAB2_LIB.BASEBOARD_FAB2(SCH_1):PAGE139_I136@MSTR_DISCRETE.CAP(CHIPS)':
 'A': CDS_PINID='A';
NODE_NAME     C1R13 1
 '@BASEBOARD_FAB2_LIB.BASEBOARD_FAB2(SCH_1):PAGE139_I142@MSTR_DISCRETE.CAP(CHIPS)':
 'A': CDS_PINID='A';
NODE_NAME     C1R20 1
 '@BASEBOARD_FAB2_LIB.BASEBOARD_FAB2(SCH_1):PAGE139_I143@DEV_DISCRETE.CAP_A(CHIPS)':
 'A': CDS_PINID='A';
NODE_NAME     C1T3 1
 '@BASEBOARD_FAB2_LIB.BASEBOARD_FAB2(SCH_1):PAGE139_I144@DEV_DISCRETE.CAP_A(CHIPS)':
 'A': CDS_PINID='A';
NODE_NAME     C1R14 1
 '@BASEBOARD_FAB2_LIB.BASEBOARD_FAB2(SCH_1):PAGE139_I145@DEV_DISCRETE.CAP_A(CHIPS)':
 'A': CDS_PINID='A';
NODE_NAME     C1R21 1
 '@BASEBOARD_FAB2_LIB.BASEBOARD_FAB2(SCH_1):PAGE139_I146@DEV_DISCRETE.CAP_A(CHIPS)':
 'A': CDS_PINID='A';
NODE_NAME     R9F5 1
 '@BASEBOARD_FAB2_LIB.BASEBOARD_FAB2(SCH_1):PAGE139_I173@MSTR_DISCRETE.RES(CHIPS)':
 'A': CDS_PINID='A';
NODE_NAME     R9E2 1
 '@BASEBOARD_FAB2_LIB.BASEBOARD_FAB2(SCH_1):PAGE139_I177@MSTR_DISCRETE.RES(CHIPS)':
 'A': CDS_PINID='A';
NODE_NAME     R9E3 1
 '@BASEBOARD_FAB2_LIB.BASEBOARD_FAB2(SCH_1):PAGE139_I178@MSTR_DISCRETE.RES(CHIPS)':
 'A': CDS_PINID='A';
NODE_NAME     R9E1 1
 '@BASEBOARD_FAB2_LIB.BASEBOARD_FAB2(SCH_1):PAGE139_I179@MSTR_DISCRETE.RES(CHIPS)':
 'A': CDS_PINID='A';
NODE_NAME     R9E22 2
 '@BASEBOARD_FAB2_LIB.BASEBOARD_FAB2(SCH_1):PAGE139_I181@MSTR_DISCRETE.RES(CHIPS)':
 'B': CDS_PINID='B';
NODE_NAME     R9E7 1
 '@BASEBOARD_FAB2_LIB.BASEBOARD_FAB2(SCH_1):PAGE139_I193@MSTR_DISCRETE.RES(CHIPS)':
 'A': CDS_PINID='A';
NODE_NAME     R9E4 1
 '@BASEBOARD_FAB2_LIB.BASEBOARD_FAB2(SCH_1):PAGE139_I200@MSTR_DISCRETE.RES(CHIPS)':
 'A': CDS_PINID='A';
NODE_NAME     R1T34 1
 '@BASEBOARD_FAB2_LIB.BASEBOARD_FAB2(SCH_1):PAGE139_I239@MSTR_DISCRETE.RES(CHIPS)':
 'A': CDS_PINID='A';
NODE_NAME     U9E1 8
 '@BASEBOARD_FAB2_LIB.BASEBOARD_FAB2(SCH_1):PAGE140_I1@MSTR_MEMORY.M25PE16(CHIPS)':
 'VCC': CDS_PINID='VCC';
NODE_NAME     C1R25 1
 '@BASEBOARD_FAB2_LIB.BASEBOARD_FAB2(SCH_1):PAGE140_I3@DEV_DISCRETE.CAP_A(CHIPS)':
 'A': CDS_PINID='A';
NODE_NAME     R1R9 1
 '@BASEBOARD_FAB2_LIB.BASEBOARD_FAB2(SCH_1):PAGE140_I10@MSTR_DISCRETE.RES(CHIPS)':
 'A': CDS_PINID='A';
NODE_NAME     R1R3 1
 '@BASEBOARD_FAB2_LIB.BASEBOARD_FAB2(SCH_1):PAGE140_I11@MSTR_DISCRETE.RES(CHIPS)':
 'A': CDS_PINID='A';
NODE_NAME     R1R7 1
 '@BASEBOARD_FAB2_LIB.BASEBOARD_FAB2(SCH_1):PAGE140_I12@MSTR_DISCRETE.RES(CHIPS)':
 'A': CDS_PINID='A';
NODE_NAME     R8E23 2
 '@BASEBOARD_FAB2_LIB.BASEBOARD_FAB2(SCH_1):PAGE142_I3@MSTR_DISCRETE.RES(CHIPS)':
 'B': CDS_PINID='B';
NODE_NAME     C8E5 1
 '@BASEBOARD_FAB2_LIB.BASEBOARD_FAB2(SCH_1):PAGE142_I20@DEV_DISCRETE.CAP_A(CHIPS)':
 'A': CDS_PINID='A';
NODE_NAME     R7F6 1
 '@BASEBOARD_FAB2_LIB.BASEBOARD_FAB2(SCH_1):PAGE153_I90@MSTR_DISCRETE.RES(CHIPS)':
 'A': CDS_PINID='A';
NODE_NAME     R7F5 1
 '@BASEBOARD_FAB2_LIB.BASEBOARD_FAB2(SCH_1):PAGE153_I94@MSTR_DISCRETE.RES(CHIPS)':
 'A': CDS_PINID='A';
NODE_NAME     C7F2 1
 '@BASEBOARD_FAB2_LIB.BASEBOARD_FAB2(SCH_1):PAGE153_I130@DEV_DISCRETE.CAP_A(CHIPS)':
 'A': CDS_PINID='A';
NODE_NAME     C7F1 1
 '@BASEBOARD_FAB2_LIB.BASEBOARD_FAB2(SCH_1):PAGE153_I131@DEV_DISCRETE.CAP_A(CHIPS)':
 'A': CDS_PINID='A';
NODE_NAME     C3T5 1
 '@BASEBOARD_FAB2_LIB.BASEBOARD_FAB2(SCH_1):PAGE153_I136@DEV_DISCRETE.CAP_A(CHIPS)':
 'A': CDS_PINID='A';
NODE_NAME     C3T4 1
 '@BASEBOARD_FAB2_LIB.BASEBOARD_FAB2(SCH_1):PAGE153_I138@DEV_DISCRETE.CAP_A(CHIPS)':
 'A': CDS_PINID='A';
NODE_NAME     R7F32 1
 '@BASEBOARD_FAB2_LIB.BASEBOARD_FAB2(SCH_1):PAGE153_I140@MSTR_DISCRETE.RES(CHIPS)':
 'A': CDS_PINID='A';
NODE_NAME     U7F1 2
 '@BASEBOARD_FAB2_LIB.BASEBOARD_FAB2(SCH_1):PAGE153_I146@MSTR_MEMORY.W25Q256(CHIPS)':
 'VCC': CDS_PINID='VCC';
NODE_NAME     R3T3 1
 '@BASEBOARD_FAB2_LIB.BASEBOARD_FAB2(SCH_1):PAGE153_I150@MSTR_DISCRETE.RES(CHIPS)':
 'A': CDS_PINID='A';
NODE_NAME     R3T5 1
 '@BASEBOARD_FAB2_LIB.BASEBOARD_FAB2(SCH_1):PAGE153_I152@MSTR_DISCRETE.RES(CHIPS)':
 'A': CDS_PINID='A';
NODE_NAME     R7F28 1
 '@BASEBOARD_FAB2_LIB.BASEBOARD_FAB2(SCH_1):PAGE153_I168@MSTR_DISCRETE.RES(CHIPS)':
 'A': CDS_PINID='A';
NODE_NAME     R3T4 1
 '@BASEBOARD_FAB2_LIB.BASEBOARD_FAB2(SCH_1):PAGE153_I174@MSTR_DISCRETE.RES(CHIPS)':
 'A': CDS_PINID='A';
NODE_NAME     R3T12 1
 '@BASEBOARD_FAB2_LIB.BASEBOARD_FAB2(SCH_1):PAGE153_I178@MSTR_DISCRETE.RES(CHIPS)':
 'A': CDS_PINID='A';
NODE_NAME     C8E18 1
 '@BASEBOARD_FAB2_LIB.BASEBOARD_FAB2(SCH_1):PAGE154_I14@DEV_DISCRETE.CAP_A(CHIPS)':
 'A': CDS_PINID='A';
NODE_NAME     U8F1 16
 '@BASEBOARD_FAB2_LIB.BASEBOARD_FAB2(SCH_1):PAGE154_I74@MSTR_DIGITAL.PI3B3257A(CHIPS)':
 'VCC': CDS_PINID='VCC';
NODE_NAME     U2T1 16
 '@BASEBOARD_FAB2_LIB.BASEBOARD_FAB2(SCH_1):PAGE154_I75@MSTR_DIGITAL.PI3B3257A(CHIPS)':
 'VCC': CDS_PINID='VCC';
NODE_NAME     C2T1 1
 '@BASEBOARD_FAB2_LIB.BASEBOARD_FAB2(SCH_1):PAGE154_I94@DEV_DISCRETE.CAP_A(CHIPS)':
 'A': CDS_PINID='A';
NODE_NAME     R2T11 1
 '@BASEBOARD_FAB2_LIB.BASEBOARD_FAB2(SCH_1):PAGE154_I105@MSTR_DISCRETE.RES(CHIPS)':
 'A': CDS_PINID='A';
NODE_NAME     R2T8 1
 '@BASEBOARD_FAB2_LIB.BASEBOARD_FAB2(SCH_1):PAGE154_I106@MSTR_DISCRETE.RES(CHIPS)':
 'A': CDS_PINID='A';
NODE_NAME     R2T6 1
 '@BASEBOARD_FAB2_LIB.BASEBOARD_FAB2(SCH_1):PAGE154_I127@MSTR_DISCRETE.RES(CHIPS)':
 'A': CDS_PINID='A';
NODE_NAME     C2T12 1
 '@BASEBOARD_FAB2_LIB.BASEBOARD_FAB2(SCH_1):PAGE154_I132@DEV_DISCRETE.CAP_A(CHIPS)':
 'A': CDS_PINID='A';
NODE_NAME     C2T8 1
 '@BASEBOARD_FAB2_LIB.BASEBOARD_FAB2(SCH_1):PAGE154_I135@DEV_DISCRETE.CAP_A(CHIPS)':
 'A': CDS_PINID='A';
NODE_NAME     R9A7 1
 '@BASEBOARD_FAB2_LIB.BASEBOARD_FAB2(SCH_1):PAGE155_I80@MSTR_DISCRETE.RES(CHIPS)':
 'A': CDS_PINID='A';
NODE_NAME     C1T56 1
 '@BASEBOARD_FAB2_LIB.BASEBOARD_FAB2(SCH_1):PAGE155_I184@DEV_DISCRETE.CAP_A(CHIPS)':
 'A': CDS_PINID='A';
NODE_NAME     R2T34 1
 '@BASEBOARD_FAB2_LIB.BASEBOARD_FAB2(SCH_1):PAGE156_I206@MSTR_DISCRETE.RES(CHIPS)':
 'A': CDS_PINID='A';
NODE_NAME     R2T35 1
 '@BASEBOARD_FAB2_LIB.BASEBOARD_FAB2(SCH_1):PAGE156_I207@MSTR_DISCRETE.RES(CHIPS)':
 'A': CDS_PINID='A';
NODE_NAME     R2T22 1
 '@BASEBOARD_FAB2_LIB.BASEBOARD_FAB2(SCH_1):PAGE156_I210@MSTR_DISCRETE.RES(CHIPS)':
 'A': CDS_PINID='A';
NODE_NAME     R8F26 1
 '@BASEBOARD_FAB2_LIB.BASEBOARD_FAB2(SCH_1):PAGE156_I211@MSTR_DISCRETE.RES(CHIPS)':
 'A': CDS_PINID='A';
NODE_NAME     R8E22 1
 '@BASEBOARD_FAB2_LIB.BASEBOARD_FAB2(SCH_1):PAGE156_I215@MSTR_DISCRETE.RES(CHIPS)':
 'A': CDS_PINID='A';
NODE_NAME     R2U2 1
 '@BASEBOARD_FAB2_LIB.BASEBOARD_FAB2(SCH_1):PAGE156_I265@MSTR_DISCRETE.RES(CHIPS)':
 'A': CDS_PINID='A';
NODE_NAME     R8G2 1
 '@BASEBOARD_FAB2_LIB.BASEBOARD_FAB2(SCH_1):PAGE156_I267@MSTR_DISCRETE.RES(CHIPS)':
 'A': CDS_PINID='A';
NODE_NAME     C2T35 1
 '@BASEBOARD_FAB2_LIB.BASEBOARD_FAB2(SCH_1):PAGE156_I273@DEV_DISCRETE.CAP_A(CHIPS)':
 'A': CDS_PINID='A';
NODE_NAME     C8F16 1
 '@BASEBOARD_FAB2_LIB.BASEBOARD_FAB2(SCH_1):PAGE156_I275@DEV_DISCRETE.CAP_A(CHIPS)':
 'A': CDS_PINID='A';
NODE_NAME     R1C34 1
 '@BASEBOARD_FAB2_LIB.BASEBOARD_FAB2(SCH_1):PAGE156_I320@MSTR_DISCRETE.RES(CHIPS)':
 'A': CDS_PINID='A';
NODE_NAME     R3P54 1
 '@BASEBOARD_FAB2_LIB.BASEBOARD_FAB2(SCH_1):PAGE156_I331@MSTR_DISCRETE.RES(CHIPS)':
 'A': CDS_PINID='A';
NODE_NAME     R1C35 1
 '@BASEBOARD_FAB2_LIB.BASEBOARD_FAB2(SCH_1):PAGE156_I336@MSTR_DISCRETE.RES(CHIPS)':
 'A': CDS_PINID='A';
NODE_NAME     R8F23 1
 '@BASEBOARD_FAB2_LIB.BASEBOARD_FAB2(SCH_1):PAGE157_I296@MSTR_DISCRETE.RES(CHIPS)':
 'A': CDS_PINID='A';
NODE_NAME     R2T29 1
 '@BASEBOARD_FAB2_LIB.BASEBOARD_FAB2(SCH_1):PAGE157_I298@MSTR_DISCRETE.RES(CHIPS)':
 'A': CDS_PINID='A';
NODE_NAME     R8F24 1
 '@BASEBOARD_FAB2_LIB.BASEBOARD_FAB2(SCH_1):PAGE157_I316@MSTR_DISCRETE.RES(CHIPS)':
 'A': CDS_PINID='A';
NODE_NAME     R2T5 1
 '@BASEBOARD_FAB2_LIB.BASEBOARD_FAB2(SCH_1):PAGE157_I326@MSTR_DISCRETE.RES(CHIPS)':
 'A': CDS_PINID='A';
NODE_NAME     R2T7 1
 '@BASEBOARD_FAB2_LIB.BASEBOARD_FAB2(SCH_1):PAGE157_I327@MSTR_DISCRETE.RES(CHIPS)':
 'A': CDS_PINID='A';
NODE_NAME     R8D25 1
 '@BASEBOARD_FAB2_LIB.BASEBOARD_FAB2(SCH_1):PAGE157_I335@MSTR_DISCRETE.RES(CHIPS)':
 'A': CDS_PINID='A';
NODE_NAME     R3N12 1
 '@BASEBOARD_FAB2_LIB.BASEBOARD_FAB2(SCH_1):PAGE157_I342@MSTR_DISCRETE.RES(CHIPS)':
 'A': CDS_PINID='A';
NODE_NAME     R3N11 1
 '@BASEBOARD_FAB2_LIB.BASEBOARD_FAB2(SCH_1):PAGE157_I344@MSTR_DISCRETE.RES(CHIPS)':
 'A': CDS_PINID='A';
NODE_NAME     R2M2 1
 '@BASEBOARD_FAB2_LIB.BASEBOARD_FAB2(SCH_1):PAGE157_I346@MSTR_DISCRETE.RES(CHIPS)':
 'A': CDS_PINID='A';
NODE_NAME     R2M5 1
 '@BASEBOARD_FAB2_LIB.BASEBOARD_FAB2(SCH_1):PAGE157_I348@MSTR_DISCRETE.RES(CHIPS)':
 'A': CDS_PINID='A';
NODE_NAME     R8E19 1
 '@BASEBOARD_FAB2_LIB.BASEBOARD_FAB2(SCH_1):PAGE157_I361@MSTR_DISCRETE.RES(CHIPS)':
 'A': CDS_PINID='A';
NODE_NAME     R2U4 1
 '@BASEBOARD_FAB2_LIB.BASEBOARD_FAB2(SCH_1):PAGE157_I367@MSTR_DISCRETE.RES(CHIPS)':
 'A': CDS_PINID='A';
NODE_NAME     C2T3 1
 '@BASEBOARD_FAB2_LIB.BASEBOARD_FAB2(SCH_1):PAGE157_I370@DEV_DISCRETE.CAP_A(CHIPS)':
 'A': CDS_PINID='A';
NODE_NAME     C8D1 1
 '@BASEBOARD_FAB2_LIB.BASEBOARD_FAB2(SCH_1):PAGE157_I376@DEV_DISCRETE.CAP_A(CHIPS)':
 'A': CDS_PINID='A';
NODE_NAME     R1L7 1
 '@BASEBOARD_FAB2_LIB.BASEBOARD_FAB2(SCH_1):PAGE157_I382@MSTR_DISCRETE.RES(CHIPS)':
 'A': CDS_PINID='A';
NODE_NAME     R8E32 1
 '@BASEBOARD_FAB2_LIB.BASEBOARD_FAB2(SCH_1):PAGE157_I385@MSTR_DISCRETE.RES(CHIPS)':
 'A': CDS_PINID='A';
NODE_NAME     C1T10 1
 '@BASEBOARD_FAB2_LIB.BASEBOARD_FAB2(SCH_1):PAGE158_I70@DEV_DISCRETE.CAP_A(CHIPS)':
 'A': CDS_PINID='A';
NODE_NAME     U9F2 8
 '@BASEBOARD_FAB2_LIB.BASEBOARD_FAB2(SCH_1):PAGE158_I74@MSTR_ANALOG.FSA3357(CHIPS)':
 'VCC': CDS_PINID='VCC';
NODE_NAME     U9F1 8
 '@BASEBOARD_FAB2_LIB.BASEBOARD_FAB2(SCH_1):PAGE158_I75@MSTR_ANALOG.FSA3357(CHIPS)':
 'VCC': CDS_PINID='VCC';
NODE_NAME     C1T11 1
 '@BASEBOARD_FAB2_LIB.BASEBOARD_FAB2(SCH_1):PAGE158_I97@DEV_DISCRETE.CAP_A(CHIPS)':
 'A': CDS_PINID='A';
NODE_NAME     R1L43 2
 '@BASEBOARD_FAB2_LIB.BASEBOARD_FAB2(SCH_1):PAGE158_I131@MSTR_DISCRETE.RES(CHIPS)':
 'B': CDS_PINID='B';
NODE_NAME     R1L44 2
 '@BASEBOARD_FAB2_LIB.BASEBOARD_FAB2(SCH_1):PAGE158_I136@MSTR_DISCRETE.RES(CHIPS)':
 'B': CDS_PINID='B';
NODE_NAME     R8G3 1
 '@BASEBOARD_FAB2_LIB.BASEBOARD_FAB2(SCH_1):PAGE159_I210@MSTR_DISCRETE.RES(CHIPS)':
 'A': CDS_PINID='A';
NODE_NAME     R8G6 1
 '@BASEBOARD_FAB2_LIB.BASEBOARD_FAB2(SCH_1):PAGE159_I212@MSTR_DISCRETE.RES(CHIPS)':
 'A': CDS_PINID='A';
NODE_NAME     R2U5 1
 '@BASEBOARD_FAB2_LIB.BASEBOARD_FAB2(SCH_1):PAGE159_I214@MSTR_DISCRETE.RES(CHIPS)':
 'A': CDS_PINID='A';
NODE_NAME     R2U13 1
 '@BASEBOARD_FAB2_LIB.BASEBOARD_FAB2(SCH_1):PAGE159_I216@MSTR_DISCRETE.RES(CHIPS)':
 'A': CDS_PINID='A';
NODE_NAME     R1T3 1
 '@BASEBOARD_FAB2_LIB.BASEBOARD_FAB2(SCH_1):PAGE160_I46@MSTR_DISCRETE.RES(CHIPS)':
 'A': CDS_PINID='A';
NODE_NAME     R1T2 1
 '@BASEBOARD_FAB2_LIB.BASEBOARD_FAB2(SCH_1):PAGE160_I49@MSTR_DISCRETE.RES(CHIPS)':
 'A': CDS_PINID='A';
NODE_NAME     R1F1 1
 '@BASEBOARD_FAB2_LIB.BASEBOARD_FAB2(SCH_1):PAGE161_I45@MSTR_DISCRETE.RES(CHIPS)':
 'A': CDS_PINID='A';
NODE_NAME     R1B21 1
 '@BASEBOARD_FAB2_LIB.BASEBOARD_FAB2(SCH_1):PAGE161_I70@MSTR_DISCRETE.RES(CHIPS)':
 'A': CDS_PINID='A';
NODE_NAME     C2U27 1
 '@BASEBOARD_FAB2_LIB.BASEBOARD_FAB2(SCH_1):PAGE161_I90@DEV_DISCRETE.CAP_A(CHIPS)':
 'A': CDS_PINID='A';
NODE_NAME     C2U28 1
 '@BASEBOARD_FAB2_LIB.BASEBOARD_FAB2(SCH_1):PAGE161_I93@DEV_DISCRETE.CAP_A(CHIPS)':
 'A': CDS_PINID='A';
NODE_NAME     C1E22 1
 '@BASEBOARD_FAB2_LIB.BASEBOARD_FAB2(SCH_1):PAGE161_I113@DEV_DISCRETE.CAP_A(CHIPS)':
 'A': CDS_PINID='A';
NODE_NAME     R1E11 1
 '@BASEBOARD_FAB2_LIB.BASEBOARD_FAB2(SCH_1):PAGE161_I120@MSTR_DISCRETE.RES(CHIPS)':
 'A': CDS_PINID='A';
NODE_NAME     R8F16 1
 '@BASEBOARD_FAB2_LIB.BASEBOARD_FAB2(SCH_1):PAGE162_I8@MSTR_DISCRETE.RES(CHIPS)':
 'A': CDS_PINID='A';
NODE_NAME     R8F14 1
 '@BASEBOARD_FAB2_LIB.BASEBOARD_FAB2(SCH_1):PAGE162_I9@MSTR_DISCRETE.RES(CHIPS)':
 'A': CDS_PINID='A';
NODE_NAME     R8F34 1
 '@BASEBOARD_FAB2_LIB.BASEBOARD_FAB2(SCH_1):PAGE162_I22@MSTR_DISCRETE.RES(CHIPS)':
 'A': CDS_PINID='A';
NODE_NAME     C8F5 1
 '@BASEBOARD_FAB2_LIB.BASEBOARD_FAB2(SCH_1):PAGE162_I28@DEV_DISCRETE.CAP_A(CHIPS)':
 'A': CDS_PINID='A';
NODE_NAME     C8F4 1
 '@BASEBOARD_FAB2_LIB.BASEBOARD_FAB2(SCH_1):PAGE162_I30@DEV_DISCRETE.CAP_A(CHIPS)':
 'A': CDS_PINID='A';
NODE_NAME     U8F2 2
 '@BASEBOARD_FAB2_LIB.BASEBOARD_FAB2(SCH_1):PAGE162_I32@MSTR_MEMORY.W25Q128(CHIPS)':
 'VCC': CDS_PINID='VCC';
NODE_NAME     C9M7 1
 '@BASEBOARD_FAB2_LIB.BASEBOARD_FAB2(SCH_1):PAGE163_I12@DEV_DISCRETE.CAP_A(CHIPS)':
 'A': CDS_PINID='A';
NODE_NAME     R9M17 1
 '@BASEBOARD_FAB2_LIB.BASEBOARD_FAB2(SCH_1):PAGE163_I15@MSTR_DISCRETE.RES(CHIPS)':
 'A': CDS_PINID='A';
NODE_NAME     R9M16 1
 '@BASEBOARD_FAB2_LIB.BASEBOARD_FAB2(SCH_1):PAGE163_I16@MSTR_DISCRETE.RES(CHIPS)':
 'A': CDS_PINID='A';
NODE_NAME     R1T5 1
 '@BASEBOARD_FAB2_LIB.BASEBOARD_FAB2(SCH_1):PAGE164_I11@MSTR_DISCRETE.RES(CHIPS)':
 'A': CDS_PINID='A';
NODE_NAME     U9B4 8
 '@BASEBOARD_FAB2_LIB.BASEBOARD_FAB2(SCH_1):PAGE167_I1@MSTR_ANALOG.TMP421(CHIPS)':
 'VP': CDS_PINID='VP';
NODE_NAME     U1E1 8
 '@BASEBOARD_FAB2_LIB.BASEBOARD_FAB2(SCH_1):PAGE167_I30@MSTR_ANALOG.TMP421(CHIPS)':
 'VP': CDS_PINID='VP';
NODE_NAME     R1E9 1
 '@BASEBOARD_FAB2_LIB.BASEBOARD_FAB2(SCH_1):PAGE167_I34@MSTR_DISCRETE.RES(CHIPS)':
 'A': CDS_PINID='A';
NODE_NAME     R9B6 1
 '@BASEBOARD_FAB2_LIB.BASEBOARD_FAB2(SCH_1):PAGE167_I35@MSTR_DISCRETE.RES(CHIPS)':
 'A': CDS_PINID='A';
NODE_NAME     R1E10 1
 '@BASEBOARD_FAB2_LIB.BASEBOARD_FAB2(SCH_1):PAGE167_I38@MSTR_DISCRETE.RES(CHIPS)':
 'A': CDS_PINID='A';
NODE_NAME     C9B7 1
 '@BASEBOARD_FAB2_LIB.BASEBOARD_FAB2(SCH_1):PAGE167_I39@DEV_DISCRETE.CAP_A(CHIPS)':
 'A': CDS_PINID='A';
NODE_NAME     C9R14 1
 '@BASEBOARD_FAB2_LIB.BASEBOARD_FAB2(SCH_1):PAGE167_I41@DEV_DISCRETE.CAP_A(CHIPS)':
 'A': CDS_PINID='A';
NODE_NAME     C9R13 1
 '@BASEBOARD_FAB2_LIB.BASEBOARD_FAB2(SCH_1):PAGE167_I42@DEV_DISCRETE.CAP_A(CHIPS)':
 'A': CDS_PINID='A';
NODE_NAME     R8D28 1
 '@BASEBOARD_FAB2_LIB.BASEBOARD_FAB2(SCH_1):PAGE167_I70@MSTR_DISCRETE.RES(CHIPS)':
 'A': CDS_PINID='A';
NODE_NAME     R2U38 1
 '@BASEBOARD_FAB2_LIB.BASEBOARD_FAB2(SCH_1):PAGE167_I80@MSTR_DISCRETE.RES(CHIPS)':
 'A': CDS_PINID='A';
NODE_NAME     R2U39 1
 '@BASEBOARD_FAB2_LIB.BASEBOARD_FAB2(SCH_1):PAGE167_I83@MSTR_DISCRETE.RES(CHIPS)':
 'A': CDS_PINID='A';
NODE_NAME     R1L36 1
 '@BASEBOARD_FAB2_LIB.BASEBOARD_FAB2(SCH_1):PAGE168_I11@MSTR_DISCRETE.RES(CHIPS)':
 'A': CDS_PINID='A';
NODE_NAME     R1L38 1
 '@BASEBOARD_FAB2_LIB.BASEBOARD_FAB2(SCH_1):PAGE168_I22@MSTR_DISCRETE.RES(CHIPS)':
 'A': CDS_PINID='A';
NODE_NAME     R1U39 1
 '@BASEBOARD_FAB2_LIB.BASEBOARD_FAB2(SCH_1):PAGE169_I88@MSTR_DISCRETE.RES(CHIPS)':
 'A': CDS_PINID='A';
NODE_NAME     R1U49 1
 '@BASEBOARD_FAB2_LIB.BASEBOARD_FAB2(SCH_1):PAGE169_I163@MSTR_DISCRETE.RES(CHIPS)':
 'A': CDS_PINID='A';
NODE_NAME     R9G35 1
 '@BASEBOARD_FAB2_LIB.BASEBOARD_FAB2(SCH_1):PAGE169_I164@MSTR_DISCRETE.RES(CHIPS)':
 'A': CDS_PINID='A';
NODE_NAME     R2P3 1
 '@BASEBOARD_FAB2_LIB.BASEBOARD_FAB2(SCH_1):PAGE170_I2@MSTR_DISCRETE.RES(CHIPS)':
 'A': CDS_PINID='A';
NODE_NAME     C2P1 1
 '@BASEBOARD_FAB2_LIB.BASEBOARD_FAB2(SCH_1):PAGE170_I8@DEV_DISCRETE.CAP_A(CHIPS)':
 'A': CDS_PINID='A';
NODE_NAME     C1R27 1
 '@BASEBOARD_FAB2_LIB.BASEBOARD_FAB2(SCH_1):PAGE170_I30@DEV_DISCRETE.CAP_A(CHIPS)':
 'A': CDS_PINID='A';
NODE_NAME     C8D2 1
 '@BASEBOARD_FAB2_LIB.BASEBOARD_FAB2(SCH_1):PAGE170_I33@DEV_DISCRETE.CAP_A(CHIPS)':
 'A': CDS_PINID='A';
NODE_NAME     C8E2 1
 '@BASEBOARD_FAB2_LIB.BASEBOARD_FAB2(SCH_1):PAGE170_I40@DEV_DISCRETE.CAP_A(CHIPS)':
 'A': CDS_PINID='A';
NODE_NAME     C1R28 1
 '@BASEBOARD_FAB2_LIB.BASEBOARD_FAB2(SCH_1):PAGE170_I49@DEV_DISCRETE.CAP_A(CHIPS)':
 'A': CDS_PINID='A';
NODE_NAME     R2T3 1
 '@BASEBOARD_FAB2_LIB.BASEBOARD_FAB2(SCH_1):PAGE170_I54@MSTR_DISCRETE.RES(CHIPS)':
 'A': CDS_PINID='A';
NODE_NAME     R2P5 1
 '@BASEBOARD_FAB2_LIB.BASEBOARD_FAB2(SCH_1):PAGE170_I56@MSTR_DISCRETE.RES(CHIPS)':
 'A': CDS_PINID='A';
NODE_NAME     R2P13 1
 '@BASEBOARD_FAB2_LIB.BASEBOARD_FAB2(SCH_1):PAGE170_I61@MSTR_DISCRETE.RES(CHIPS)':
 'A': CDS_PINID='A';
NODE_NAME     R9F3 1
 '@BASEBOARD_FAB2_LIB.BASEBOARD_FAB2(SCH_1):PAGE170_I65@MSTR_DISCRETE.RES(CHIPS)':
 'A': CDS_PINID='A';
NODE_NAME     R8D26 1
 '@BASEBOARD_FAB2_LIB.BASEBOARD_FAB2(SCH_1):PAGE170_I71@MSTR_DISCRETE.RES(CHIPS)':
 'A': CDS_PINID='A';
NODE_NAME     R1R5 1
 '@BASEBOARD_FAB2_LIB.BASEBOARD_FAB2(SCH_1):PAGE170_I73@MSTR_DISCRETE.RES(CHIPS)':
 'A': CDS_PINID='A';
NODE_NAME     R1L27 1
 '@BASEBOARD_FAB2_LIB.BASEBOARD_FAB2(SCH_1):PAGE175_I5@MSTR_DISCRETE.RES(CHIPS)':
 'A': CDS_PINID='A';
NODE_NAME     C1L17 1
 '@BASEBOARD_FAB2_LIB.BASEBOARD_FAB2(SCH_1):PAGE175_I37@DEV_DISCRETE.CAP_A(CHIPS)':
 'A': CDS_PINID='A';
NODE_NAME     C1L9 1
 '@BASEBOARD_FAB2_LIB.BASEBOARD_FAB2(SCH_1):PAGE175_I38@DEV_DISCRETE.CAP_A(CHIPS)':
 'A': CDS_PINID='A';
NODE_NAME     C9A3 1
 '@BASEBOARD_FAB2_LIB.BASEBOARD_FAB2(SCH_1):PAGE175_I40@DEV_DISCRETE.CAP_A(CHIPS)':
 'A': CDS_PINID='A';
NODE_NAME     R1L33 2
 '@BASEBOARD_FAB2_LIB.BASEBOARD_FAB2(SCH_1):PAGE175_I45@MSTR_DISCRETE.RES(CHIPS)':
 'B': CDS_PINID='B';
NODE_NAME     R1M24 1
 '@BASEBOARD_FAB2_LIB.BASEBOARD_FAB2(SCH_1):PAGE176_I105@MSTR_DISCRETE.RES(CHIPS)':
 'A': CDS_PINID='A';
NODE_NAME     R9F28 1
 '@BASEBOARD_FAB2_LIB.BASEBOARD_FAB2(SCH_1):PAGE177_I72@MSTR_DISCRETE.RES(CHIPS)':
 'A': CDS_PINID='A';
NODE_NAME     R9F30 1
 '@BASEBOARD_FAB2_LIB.BASEBOARD_FAB2(SCH_1):PAGE177_I76@MSTR_DISCRETE.RES(CHIPS)':
 'A': CDS_PINID='A';
NODE_NAME     R9F52 1
 '@BASEBOARD_FAB2_LIB.BASEBOARD_FAB2(SCH_1):PAGE177_I82@MSTR_DISCRETE.RES(CHIPS)':
 'A': CDS_PINID='A';
NODE_NAME     R2L12 1
 '@BASEBOARD_FAB2_LIB.BASEBOARD_FAB2(SCH_1):PAGE178_I2@MSTR_DISCRETE.RES(CHIPS)':
 'A': CDS_PINID='A';
NODE_NAME     R2L15 1
 '@BASEBOARD_FAB2_LIB.BASEBOARD_FAB2(SCH_1):PAGE178_I12@MSTR_DISCRETE.RES(CHIPS)':
 'A': CDS_PINID='A';
NODE_NAME     R2L11 1
 '@BASEBOARD_FAB2_LIB.BASEBOARD_FAB2(SCH_1):PAGE178_I13@MSTR_DISCRETE.RES(CHIPS)':
 'A': CDS_PINID='A';
NODE_NAME     R2L6 1
 '@BASEBOARD_FAB2_LIB.BASEBOARD_FAB2(SCH_1):PAGE178_I17@MSTR_DISCRETE.RES(CHIPS)':
 'A': CDS_PINID='A';
NODE_NAME     R2L4 1
 '@BASEBOARD_FAB2_LIB.BASEBOARD_FAB2(SCH_1):PAGE178_I18@MSTR_DISCRETE.RES(CHIPS)':
 'A': CDS_PINID='A';
NODE_NAME     R2L5 1
 '@BASEBOARD_FAB2_LIB.BASEBOARD_FAB2(SCH_1):PAGE178_I20@MSTR_DISCRETE.RES(CHIPS)':
 'A': CDS_PINID='A';
NODE_NAME     J8E1 7
 '@BASEBOARD_FAB2_LIB.BASEBOARD_FAB2(SCH_1):PAGE184_I87@MSTR_SCONN.SCONN11_H67026001(CHIPS)':
 'IO7': CDS_PINID='IO7';
NODE_NAME     R2P16 1
 '@BASEBOARD_FAB2_LIB.BASEBOARD_FAB2(SCH_1):PAGE185_I113@MSTR_DISCRETE.RES(CHIPS)':
 'A': CDS_PINID='A';
NODE_NAME     C2P9 1
 '@BASEBOARD_FAB2_LIB.BASEBOARD_FAB2(SCH_1):PAGE185_I117@DEV_DISCRETE.CAP_A(CHIPS)':
 'A': CDS_PINID='A';
NODE_NAME     C1M20 1
 '@BASEBOARD_FAB2_LIB.BASEBOARD_FAB2(SCH_1):PAGE186_I270@DEV_DISCRETE.CAP_A(CHIPS)':
 'A': CDS_PINID='A';
NODE_NAME     C1M25 1
 '@BASEBOARD_FAB2_LIB.BASEBOARD_FAB2(SCH_1):PAGE186_I335@DEV_DISCRETE.CAP_A(CHIPS)':
 'A': CDS_PINID='A';
NODE_NAME     J9B3 12
 '@BASEBOARD_FAB2_LIB.BASEBOARD_FAB2(SCH_1):PAGE186_I336@MSTR_SCONN.SCONN120_A28699018(CHIPS)':
 'IO12': CDS_PINID='IO12';
NODE_NAME     J9B3 13
 '@BASEBOARD_FAB2_LIB.BASEBOARD_FAB2(SCH_1):PAGE186_I336@MSTR_SCONN.SCONN120_A28699018(CHIPS)':
 'IO13': CDS_PINID='IO13';
NODE_NAME     R1R18 1
 '@BASEBOARD_FAB2_LIB.BASEBOARD_FAB2(SCH_1):PAGE188_I88@MSTR_DISCRETE.RES(CHIPS)':
 'A': CDS_PINID='A';
NODE_NAME     R1R19 1
 '@BASEBOARD_FAB2_LIB.BASEBOARD_FAB2(SCH_1):PAGE188_I89@MSTR_DISCRETE.RES(CHIPS)':
 'A': CDS_PINID='A';
NODE_NAME     R1R21 1
 '@BASEBOARD_FAB2_LIB.BASEBOARD_FAB2(SCH_1):PAGE188_I90@MSTR_DISCRETE.RES(CHIPS)':
 'A': CDS_PINID='A';
NODE_NAME     R1R20 1
 '@BASEBOARD_FAB2_LIB.BASEBOARD_FAB2(SCH_1):PAGE188_I91@MSTR_DISCRETE.RES(CHIPS)':
 'A': CDS_PINID='A';
NODE_NAME     R1R22 1
 '@BASEBOARD_FAB2_LIB.BASEBOARD_FAB2(SCH_1):PAGE188_I92@MSTR_DISCRETE.RES(CHIPS)':
 'A': CDS_PINID='A';
NODE_NAME     R1R16 1
 '@BASEBOARD_FAB2_LIB.BASEBOARD_FAB2(SCH_1):PAGE188_I93@MSTR_DISCRETE.RES(CHIPS)':
 'A': CDS_PINID='A';
NODE_NAME     R1R17 1
 '@BASEBOARD_FAB2_LIB.BASEBOARD_FAB2(SCH_1):PAGE188_I94@MSTR_DISCRETE.RES(CHIPS)':
 'A': CDS_PINID='A';
NODE_NAME     R1R23 1
 '@BASEBOARD_FAB2_LIB.BASEBOARD_FAB2(SCH_1):PAGE188_I95@MSTR_DISCRETE.RES(CHIPS)':
 'A': CDS_PINID='A';
NODE_NAME     R3R15 1
 '@BASEBOARD_FAB2_LIB.BASEBOARD_FAB2(SCH_1):PAGE189_I44@MSTR_DISCRETE.RES(CHIPS)':
 'A': CDS_PINID='A';
NODE_NAME     CR3U1 2
 '@BASEBOARD_FAB2_LIB.BASEBOARD_FAB2(SCH_1):PAGE189_I49@MSTR_DISCRETE.DIODE(CHIPS)':
 'A': CDS_PINID='A';
NODE_NAME     R8G20 1
 '@BASEBOARD_FAB2_LIB.BASEBOARD_FAB2(SCH_1):PAGE189_I50@MSTR_DISCRETE.RES(CHIPS)':
 'A': CDS_PINID='A';
NODE_NAME     R7G23 1
 '@BASEBOARD_FAB2_LIB.BASEBOARD_FAB2(SCH_1):PAGE189_I51@MSTR_DISCRETE.RES(CHIPS)':
 'A': CDS_PINID='A';
NODE_NAME     R7G22 1
 '@BASEBOARD_FAB2_LIB.BASEBOARD_FAB2(SCH_1):PAGE189_I53@MSTR_DISCRETE.RES(CHIPS)':
 'A': CDS_PINID='A';
NODE_NAME     R2R7 1
 '@BASEBOARD_FAB2_LIB.BASEBOARD_FAB2(SCH_1):PAGE191_I172@MSTR_DISCRETE.RES(CHIPS)':
 'A': CDS_PINID='A';
NODE_NAME     R7D42 1
 '@BASEBOARD_FAB2_LIB.BASEBOARD_FAB2(SCH_1):PAGE191_I193@MSTR_DISCRETE.RES(CHIPS)':
 'A': CDS_PINID='A';
NODE_NAME     C2P8 1
 '@BASEBOARD_FAB2_LIB.BASEBOARD_FAB2(SCH_1):PAGE192_I1@DEV_DISCRETE.CAP_A(CHIPS)':
 'A': CDS_PINID='A';
NODE_NAME     C2P5 1
 '@BASEBOARD_FAB2_LIB.BASEBOARD_FAB2(SCH_1):PAGE192_I3@DEV_DISCRETE.CAP_A(CHIPS)':
 'A': CDS_PINID='A';
NODE_NAME     C3R1 1
 '@BASEBOARD_FAB2_LIB.BASEBOARD_FAB2(SCH_1):PAGE192_I4@DEV_DISCRETE.CAP_A(CHIPS)':
 'A': CDS_PINID='A';
NODE_NAME     C3P43 1
 '@BASEBOARD_FAB2_LIB.BASEBOARD_FAB2(SCH_1):PAGE192_I6@DEV_DISCRETE.CAP_A(CHIPS)':
 'A': CDS_PINID='A';
NODE_NAME     C3R3 1
 '@BASEBOARD_FAB2_LIB.BASEBOARD_FAB2(SCH_1):PAGE192_I7@DEV_DISCRETE.CAP_A(CHIPS)':
 'A': CDS_PINID='A';
NODE_NAME     C2R1 1
 '@BASEBOARD_FAB2_LIB.BASEBOARD_FAB2(SCH_1):PAGE192_I8@DEV_DISCRETE.CAP_A(CHIPS)':
 'A': CDS_PINID='A';
NODE_NAME     C2P2 1
 '@BASEBOARD_FAB2_LIB.BASEBOARD_FAB2(SCH_1):PAGE192_I9@DEV_DISCRETE.CAP_A(CHIPS)':
 'A': CDS_PINID='A';
NODE_NAME     C3R2 1
 '@BASEBOARD_FAB2_LIB.BASEBOARD_FAB2(SCH_1):PAGE192_I10@DEV_DISCRETE.CAP_A(CHIPS)':
 'A': CDS_PINID='A';
NODE_NAME     C3P51 1
 '@BASEBOARD_FAB2_LIB.BASEBOARD_FAB2(SCH_1):PAGE192_I11@DEV_DISCRETE.CAP_A(CHIPS)':
 'A': CDS_PINID='A';
NODE_NAME     C3P47 1
 '@BASEBOARD_FAB2_LIB.BASEBOARD_FAB2(SCH_1):PAGE192_I12@DEV_DISCRETE.CAP_A(CHIPS)':
 'A': CDS_PINID='A';
NODE_NAME     U8D7 A1
 '@BASEBOARD_FAB2_LIB.BASEBOARD_FAB2(SCH_1):PAGE192_I14@MSTR_MEMORY.LCMXO2_A(CHIPS)':
 'VCC'<0>: CDS_PINID='VCC(0)';
NODE_NAME     U8D7 A16
 '@BASEBOARD_FAB2_LIB.BASEBOARD_FAB2(SCH_1):PAGE192_I14@MSTR_MEMORY.LCMXO2_A(CHIPS)':
 'VCC'<1>: CDS_PINID='VCC(1)';
NODE_NAME     U8D7 T1
 '@BASEBOARD_FAB2_LIB.BASEBOARD_FAB2(SCH_1):PAGE192_I14@MSTR_MEMORY.LCMXO2_A(CHIPS)':
 'VCC'<2>: CDS_PINID='VCC(2)';
NODE_NAME     U8D7 T16
 '@BASEBOARD_FAB2_LIB.BASEBOARD_FAB2(SCH_1):PAGE192_I14@MSTR_MEMORY.LCMXO2_A(CHIPS)':
 'VCC'<3>: CDS_PINID='VCC(3)';
NODE_NAME     U8D7 G7
 '@BASEBOARD_FAB2_LIB.BASEBOARD_FAB2(SCH_1):PAGE192_I14@MSTR_MEMORY.LCMXO2_A(CHIPS)':
 'VCC'<4>: CDS_PINID='VCC(4)';
NODE_NAME     U8D7 G10
 '@BASEBOARD_FAB2_LIB.BASEBOARD_FAB2(SCH_1):PAGE192_I14@MSTR_MEMORY.LCMXO2_A(CHIPS)':
 'VCC'<5>: CDS_PINID='VCC(5)';
NODE_NAME     U8D7 K7
 '@BASEBOARD_FAB2_LIB.BASEBOARD_FAB2(SCH_1):PAGE192_I14@MSTR_MEMORY.LCMXO2_A(CHIPS)':
 'VCC'<6>: CDS_PINID='VCC(6)';
NODE_NAME     U8D7 K10
 '@BASEBOARD_FAB2_LIB.BASEBOARD_FAB2(SCH_1):PAGE192_I14@MSTR_MEMORY.LCMXO2_A(CHIPS)':
 'VCC'<7>: CDS_PINID='VCC(7)';
NODE_NAME     U8D7 G8
 '@BASEBOARD_FAB2_LIB.BASEBOARD_FAB2(SCH_1):PAGE192_I14@MSTR_MEMORY.LCMXO2_A(CHIPS)':
 'VCCIO0'<0>: CDS_PINID='VCCIO0(0)';
NODE_NAME     U8D7 D12
 '@BASEBOARD_FAB2_LIB.BASEBOARD_FAB2(SCH_1):PAGE192_I14@MSTR_MEMORY.LCMXO2_A(CHIPS)':
 'VCCIO0'<1>: CDS_PINID='VCCIO0(1)';
NODE_NAME     U8D7 G9
 '@BASEBOARD_FAB2_LIB.BASEBOARD_FAB2(SCH_1):PAGE192_I14@MSTR_MEMORY.LCMXO2_A(CHIPS)':
 'VCCIO0'<2>: CDS_PINID='VCCIO0(2)';
NODE_NAME     U8D7 D5
 '@BASEBOARD_FAB2_LIB.BASEBOARD_FAB2(SCH_1):PAGE192_I14@MSTR_MEMORY.LCMXO2_A(CHIPS)':
 'VCCIO0'<3>: CDS_PINID='VCCIO0(3)';
NODE_NAME     U8D7 E13
 '@BASEBOARD_FAB2_LIB.BASEBOARD_FAB2(SCH_1):PAGE192_I14@MSTR_MEMORY.LCMXO2_A(CHIPS)':
 'VCCIO1'<0>: CDS_PINID='VCCIO1(0)';
NODE_NAME     U8D7 H10
 '@BASEBOARD_FAB2_LIB.BASEBOARD_FAB2(SCH_1):PAGE192_I14@MSTR_MEMORY.LCMXO2_A(CHIPS)':
 'VCCIO1'<1>: CDS_PINID='VCCIO1(1)';
NODE_NAME     U8D7 J10
 '@BASEBOARD_FAB2_LIB.BASEBOARD_FAB2(SCH_1):PAGE192_I14@MSTR_MEMORY.LCMXO2_A(CHIPS)':
 'VCCIO1'<2>: CDS_PINID='VCCIO1(2)';
NODE_NAME     U8D7 M13
 '@BASEBOARD_FAB2_LIB.BASEBOARD_FAB2(SCH_1):PAGE192_I14@MSTR_MEMORY.LCMXO2_A(CHIPS)':
 'VCCIO1'<3>: CDS_PINID='VCCIO1(3)';
NODE_NAME     U8D7 K9
 '@BASEBOARD_FAB2_LIB.BASEBOARD_FAB2(SCH_1):PAGE192_I14@MSTR_MEMORY.LCMXO2_A(CHIPS)':
 'VCCIO2'<0>: CDS_PINID='VCCIO2(0)';
NODE_NAME     U8D7 N12
 '@BASEBOARD_FAB2_LIB.BASEBOARD_FAB2(SCH_1):PAGE192_I14@MSTR_MEMORY.LCMXO2_A(CHIPS)':
 'VCCIO2'<1>: CDS_PINID='VCCIO2(1)';
NODE_NAME     U8D7 K8
 '@BASEBOARD_FAB2_LIB.BASEBOARD_FAB2(SCH_1):PAGE192_I14@MSTR_MEMORY.LCMXO2_A(CHIPS)':
 'VCCIO2'<2>: CDS_PINID='VCCIO2(2)';
NODE_NAME     U8D7 N5
 '@BASEBOARD_FAB2_LIB.BASEBOARD_FAB2(SCH_1):PAGE192_I14@MSTR_MEMORY.LCMXO2_A(CHIPS)':
 'VCCIO2'<3>: CDS_PINID='VCCIO2(3)';
NODE_NAME     U8D7 M4
 '@BASEBOARD_FAB2_LIB.BASEBOARD_FAB2(SCH_1):PAGE192_I14@MSTR_MEMORY.LCMXO2_A(CHIPS)':
 'VCCIO3'<0>: CDS_PINID='VCCIO3(0)';
NODE_NAME     U8D7 J7
 '@BASEBOARD_FAB2_LIB.BASEBOARD_FAB2(SCH_1):PAGE192_I14@MSTR_MEMORY.LCMXO2_A(CHIPS)':
 'VCCIO4'<0>: CDS_PINID='VCCIO4(0)';
NODE_NAME     U8D7 H7
 '@BASEBOARD_FAB2_LIB.BASEBOARD_FAB2(SCH_1):PAGE192_I14@MSTR_MEMORY.LCMXO2_A(CHIPS)':
 'VCCIO4'<1>: CDS_PINID='VCCIO4(1)';
NODE_NAME     U8D7 E4
 '@BASEBOARD_FAB2_LIB.BASEBOARD_FAB2(SCH_1):PAGE192_I14@MSTR_MEMORY.LCMXO2_A(CHIPS)':
 'VCCIO5'<0>: CDS_PINID='VCCIO5(0)';
NODE_NAME     C2R5 1
 '@BASEBOARD_FAB2_LIB.BASEBOARD_FAB2(SCH_1):PAGE192_I15@DEV_DISCRETE.CAP_A(CHIPS)':
 'A': CDS_PINID='A';
NODE_NAME     C2P4 1
 '@BASEBOARD_FAB2_LIB.BASEBOARD_FAB2(SCH_1):PAGE192_I16@DEV_DISCRETE.CAP_A(CHIPS)':
 'A': CDS_PINID='A';
NODE_NAME     C3P52 1
 '@BASEBOARD_FAB2_LIB.BASEBOARD_FAB2(SCH_1):PAGE192_I17@DEV_DISCRETE.CAP_A(CHIPS)':
 'A': CDS_PINID='A';
NODE_NAME     C2P6 1
 '@BASEBOARD_FAB2_LIB.BASEBOARD_FAB2(SCH_1):PAGE192_I18@DEV_DISCRETE.CAP_A(CHIPS)':
 'A': CDS_PINID='A';
NODE_NAME     C2R3 1
 '@BASEBOARD_FAB2_LIB.BASEBOARD_FAB2(SCH_1):PAGE192_I19@DEV_DISCRETE.CAP_A(CHIPS)':
 'A': CDS_PINID='A';
NODE_NAME     C2P7 1
 '@BASEBOARD_FAB2_LIB.BASEBOARD_FAB2(SCH_1):PAGE192_I20@DEV_DISCRETE.CAP_A(CHIPS)':
 'A': CDS_PINID='A';
NODE_NAME     C2R4 1
 '@BASEBOARD_FAB2_LIB.BASEBOARD_FAB2(SCH_1):PAGE192_I21@DEV_DISCRETE.CAP_A(CHIPS)':
 'A': CDS_PINID='A';
NODE_NAME     C2P3 1
 '@BASEBOARD_FAB2_LIB.BASEBOARD_FAB2(SCH_1):PAGE192_I22@DEV_DISCRETE.CAP_A(CHIPS)':
 'A': CDS_PINID='A';
NODE_NAME     C3P44 1
 '@BASEBOARD_FAB2_LIB.BASEBOARD_FAB2(SCH_1):PAGE192_I23@DEV_DISCRETE.CAP_A(CHIPS)':
 'A': CDS_PINID='A';
NODE_NAME     C3P48 1
 '@BASEBOARD_FAB2_LIB.BASEBOARD_FAB2(SCH_1):PAGE192_I25@DEV_DISCRETE.CAP_A(CHIPS)':
 'A': CDS_PINID='A';
NODE_NAME     C2R2 1
 '@BASEBOARD_FAB2_LIB.BASEBOARD_FAB2(SCH_1):PAGE192_I28@DEV_DISCRETE.CAP_A(CHIPS)':
 'A': CDS_PINID='A';
NODE_NAME     R7E6 1
 '@BASEBOARD_FAB2_LIB.BASEBOARD_FAB2(SCH_1):PAGE192_I33@MSTR_DISCRETE.RES(CHIPS)':
 'A': CDS_PINID='A';
NODE_NAME     R2R1 1
 '@BASEBOARD_FAB2_LIB.BASEBOARD_FAB2(SCH_1):PAGE192_I34@MSTR_DISCRETE.RES(CHIPS)':
 'A': CDS_PINID='A';
NODE_NAME     R7E5 1
 '@BASEBOARD_FAB2_LIB.BASEBOARD_FAB2(SCH_1):PAGE192_I38@MSTR_DISCRETE.RES(CHIPS)':
 'A': CDS_PINID='A';
NODE_NAME     R2R3 1
 '@BASEBOARD_FAB2_LIB.BASEBOARD_FAB2(SCH_1):PAGE192_I41@MSTR_DISCRETE.RES(CHIPS)':
 'A': CDS_PINID='A';
NODE_NAME     R7E18 1
 '@BASEBOARD_FAB2_LIB.BASEBOARD_FAB2(SCH_1):PAGE192_I55@MSTR_DISCRETE.RES(CHIPS)':
 'A': CDS_PINID='A';
NODE_NAME     R7E19 1
 '@BASEBOARD_FAB2_LIB.BASEBOARD_FAB2(SCH_1):PAGE192_I57@MSTR_DISCRETE.RES(CHIPS)':
 'A': CDS_PINID='A';
NODE_NAME     J4B2 A11
 '@BASEBOARD_FAB2_LIB.BASEBOARD_FAB2(SCH_1):PAGE193_I46@MSTR_SCONN.SCONN120_H61426002(CHIPS)':
 'IOA11': CDS_PINID='IOA11';
NODE_NAME     J4B2 B11
 '@BASEBOARD_FAB2_LIB.BASEBOARD_FAB2(SCH_1):PAGE193_I46@MSTR_SCONN.SCONN120_H61426002(CHIPS)':
 'IOB11': CDS_PINID='IOB11';
NODE_NAME     J4B2 C11
 '@BASEBOARD_FAB2_LIB.BASEBOARD_FAB2(SCH_1):PAGE193_I46@MSTR_SCONN.SCONN120_H61426002(CHIPS)':
 'IOC11': CDS_PINID='IOC11';
NODE_NAME     J6B1 A11
 '@BASEBOARD_FAB2_LIB.BASEBOARD_FAB2(SCH_1):PAGE194_I56@MSTR_SCONN.SCONN120_H61426002(CHIPS)':
 'IOA11': CDS_PINID='IOA11';
NODE_NAME     J6B1 B11
 '@BASEBOARD_FAB2_LIB.BASEBOARD_FAB2(SCH_1):PAGE194_I56@MSTR_SCONN.SCONN120_H61426002(CHIPS)':
 'IOB11': CDS_PINID='IOB11';
NODE_NAME     J6B1 C11
 '@BASEBOARD_FAB2_LIB.BASEBOARD_FAB2(SCH_1):PAGE194_I56@MSTR_SCONN.SCONN120_H61426002(CHIPS)':
 'IOC11': CDS_PINID='IOC11';
NODE_NAME     CR2U1 1
 '@BASEBOARD_FAB2_LIB.BASEBOARD_FAB2(SCH_1):PAGE196_I53@MSTR_DISCRETE.DIODE2A_DUAL(CHIPS)':
 'A1': CDS_PINID='A1';
NODE_NAME     R3P44 1
 '@BASEBOARD_FAB2_LIB.BASEBOARD_FAB2(SCH_1):PAGE196_I59@MSTR_DISCRETE.RES(CHIPS)':
 'A': CDS_PINID='A';
NODE_NAME     U7D3 6
 '@BASEBOARD_FAB2_LIB.BASEBOARD_FAB2(SCH_1):PAGE196_I70@MSTR_ANALOG.ADM1085(CHIPS)':
 'VCC': CDS_PINID='VCC';
NODE_NAME     R3P50 1
 '@BASEBOARD_FAB2_LIB.BASEBOARD_FAB2(SCH_1):PAGE196_I71@MSTR_DISCRETE.RES(CHIPS)':
 'A': CDS_PINID='A';
NODE_NAME     C3P46 1
 '@BASEBOARD_FAB2_LIB.BASEBOARD_FAB2(SCH_1):PAGE196_I72@DEV_DISCRETE.CAP_A(CHIPS)':
 'A': CDS_PINID='A';
NODE_NAME     U8D8 2
 '@BASEBOARD_FAB2_LIB.BASEBOARD_FAB2(SCH_1):PAGE196_I104@MSTR_VREG.TPS3700(CHIPS)':
 'VDD': CDS_PINID='VDD';
NODE_NAME     C8D4 1
 '@BASEBOARD_FAB2_LIB.BASEBOARD_FAB2(SCH_1):PAGE196_I105@DEV_DISCRETE.CAP_A(CHIPS)':
 'A': CDS_PINID='A';
NODE_NAME     R8D41 1
 '@BASEBOARD_FAB2_LIB.BASEBOARD_FAB2(SCH_1):PAGE196_I120@MSTR_DISCRETE.RES(CHIPS)':
 'A': CDS_PINID='A';
NODE_NAME     R2P18 1
 '@BASEBOARD_FAB2_LIB.BASEBOARD_FAB2(SCH_1):PAGE196_I121@MSTR_DISCRETE.RES(CHIPS)':
 'A': CDS_PINID='A';
NODE_NAME     R2P21 1
 '@BASEBOARD_FAB2_LIB.BASEBOARD_FAB2(SCH_1):PAGE196_I122@MSTR_DISCRETE.RES(CHIPS)':
 'A': CDS_PINID='A';
NODE_NAME     EU2T1 5
 '@BASEBOARD_FAB2_LIB.BASEBOARD_FAB2(SCH_1):PAGE198_I1@MSTR_VREG.SLG55021(CHIPS)':
 'D': CDS_PINID='D';
NODE_NAME     C2T36 1
 '@BASEBOARD_FAB2_LIB.BASEBOARD_FAB2(SCH_1):PAGE198_I43@DEV_DISCRETE.CAP_A(CHIPS)':
 'A': CDS_PINID='A';
NODE_NAME     C2U1 1
 '@BASEBOARD_FAB2_LIB.BASEBOARD_FAB2(SCH_1):PAGE198_I44@MSTR_DISCRETE.CAP(CHIPS)':
 'A': CDS_PINID='A';
NODE_NAME     R8E12 1
 '@BASEBOARD_FAB2_LIB.BASEBOARD_FAB2(SCH_1):PAGE198_I78@MSTR_DISCRETE.RES(CHIPS)':
 'A': CDS_PINID='A';
NODE_NAME     Q8G1 5
 '@BASEBOARD_FAB2_LIB.BASEBOARD_FAB2(SCH_1):PAGE198_I85@MSTR_DISCRETE.MOSFET_N(CHIPS)':
 'DRN': CDS_PINID='DRN';
NODE_NAME     R9P20 1
 '@BASEBOARD_FAB2_LIB.BASEBOARD_FAB2(SCH_1):PAGE200_I86@MSTR_DISCRETE.RES(CHIPS)':
 'A': CDS_PINID='A';
NODE_NAME     R9P6 1
 '@BASEBOARD_FAB2_LIB.BASEBOARD_FAB2(SCH_1):PAGE200_I149@MSTR_DISCRETE.RES(CHIPS)':
 'A': CDS_PINID='A';
NODE_NAME     R1D22 1
 '@BASEBOARD_FAB2_LIB.BASEBOARD_FAB2(SCH_1):PAGE200_I158@MSTR_DISCRETE.RES(CHIPS)':
 'A': CDS_PINID='A';
NODE_NAME     R1D23 1
 '@BASEBOARD_FAB2_LIB.BASEBOARD_FAB2(SCH_1):PAGE200_I191@MSTR_DISCRETE.RES(CHIPS)':
 'A': CDS_PINID='A';
NODE_NAME     R9P10 1
 '@BASEBOARD_FAB2_LIB.BASEBOARD_FAB2(SCH_1):PAGE200_I192@MSTR_DISCRETE.RES(CHIPS)':
 'A': CDS_PINID='A';
NODE_NAME     U9P2 2
 '@BASEBOARD_FAB2_LIB.BASEBOARD_FAB2(SCH_1):PAGE200_I200@MSTR_VREG.TPS3700(CHIPS)':
 'VDD': CDS_PINID='VDD';
NODE_NAME     C9P11 1
 '@BASEBOARD_FAB2_LIB.BASEBOARD_FAB2(SCH_1):PAGE200_I201@DEV_DISCRETE.CAP_A(CHIPS)':
 'A': CDS_PINID='A';
NODE_NAME     R1D21 1
 '@BASEBOARD_FAB2_LIB.BASEBOARD_FAB2(SCH_1):PAGE200_I204@MSTR_DISCRETE.RES(CHIPS)':
 'A': CDS_PINID='A';
NODE_NAME     R9P4 1
 '@BASEBOARD_FAB2_LIB.BASEBOARD_FAB2(SCH_1):PAGE200_I210@MSTR_DISCRETE.RES(CHIPS)':
 'A': CDS_PINID='A';
NODE_NAME     R9P5 1
 '@BASEBOARD_FAB2_LIB.BASEBOARD_FAB2(SCH_1):PAGE200_I215@MSTR_DISCRETE.RES(CHIPS)':
 'A': CDS_PINID='A';
NODE_NAME     R4D31 1
 '@BASEBOARD_FAB2_LIB.BASEBOARD_FAB2(SCH_1):PAGE201_I22@MSTR_DISCRETE.RES(CHIPS)':
 'A': CDS_PINID='A';
NODE_NAME     R4D58 1
 '@BASEBOARD_FAB2_LIB.BASEBOARD_FAB2(SCH_1):PAGE201_I25@MSTR_DISCRETE.RES(CHIPS)':
 'A': CDS_PINID='A';
NODE_NAME     R4E5 1
 '@BASEBOARD_FAB2_LIB.BASEBOARD_FAB2(SCH_1):PAGE201_I27@MSTR_DISCRETE.RES(CHIPS)':
 'A': CDS_PINID='A';
NODE_NAME     R4D26 1
 '@BASEBOARD_FAB2_LIB.BASEBOARD_FAB2(SCH_1):PAGE201_I40@MSTR_DISCRETE.RES(CHIPS)':
 'A': CDS_PINID='A';
NODE_NAME     R6P32 1
 '@BASEBOARD_FAB2_LIB.BASEBOARD_FAB2(SCH_1):PAGE201_I102@MSTR_DISCRETE.RES(CHIPS)':
 'A': CDS_PINID='A';
NODE_NAME     R6P37 1
 '@BASEBOARD_FAB2_LIB.BASEBOARD_FAB2(SCH_1):PAGE201_I103@MSTR_DISCRETE.RES(CHIPS)':
 'A': CDS_PINID='A';
NODE_NAME     R4E3 1
 '@BASEBOARD_FAB2_LIB.BASEBOARD_FAB2(SCH_1):PAGE201_I111@MSTR_DISCRETE.RES(CHIPS)':
 'A': CDS_PINID='A';
NODE_NAME     R4E20 1
 '@BASEBOARD_FAB2_LIB.BASEBOARD_FAB2(SCH_1):PAGE201_I116@MSTR_DISCRETE.RES(CHIPS)':
 'A': CDS_PINID='A';
NODE_NAME     R1D6 1
 '@BASEBOARD_FAB2_LIB.BASEBOARD_FAB2(SCH_1):PAGE206_I6@MSTR_DISCRETE.RES(CHIPS)':
 'A': CDS_PINID='A';
NODE_NAME     R1D53 1
 '@BASEBOARD_FAB2_LIB.BASEBOARD_FAB2(SCH_1):PAGE206_I33@MSTR_DISCRETE.RES(CHIPS)':
 'A': CDS_PINID='A';
NODE_NAME     R1C18 1
 '@BASEBOARD_FAB2_LIB.BASEBOARD_FAB2(SCH_1):PAGE206_I34@MSTR_DISCRETE.RES(CHIPS)':
 'A': CDS_PINID='A';
NODE_NAME     R1C28 1
 '@BASEBOARD_FAB2_LIB.BASEBOARD_FAB2(SCH_1):PAGE206_I35@MSTR_DISCRETE.RES(CHIPS)':
 'A': CDS_PINID='A';
NODE_NAME     R1D8 1
 '@BASEBOARD_FAB2_LIB.BASEBOARD_FAB2(SCH_1):PAGE206_I36@MSTR_DISCRETE.RES(CHIPS)':
 'A': CDS_PINID='A';
NODE_NAME     R1C14 1
 '@BASEBOARD_FAB2_LIB.BASEBOARD_FAB2(SCH_1):PAGE206_I46@MSTR_DISCRETE.RES(CHIPS)':
 'A': CDS_PINID='A';
NODE_NAME     R3P22 1
 '@BASEBOARD_FAB2_LIB.BASEBOARD_FAB2(SCH_1):PAGE211_I24@MSTR_DISCRETE.RES(CHIPS)':
 'A': CDS_PINID='A';
NODE_NAME     R3P25 1
 '@BASEBOARD_FAB2_LIB.BASEBOARD_FAB2(SCH_1):PAGE211_I56@MSTR_DISCRETE.RES(CHIPS)':
 'A': CDS_PINID='A';
NODE_NAME     R3N23 1
 '@BASEBOARD_FAB2_LIB.BASEBOARD_FAB2(SCH_1):PAGE211_I60@MSTR_DISCRETE.RES(CHIPS)':
 'A': CDS_PINID='A';
NODE_NAME     R3P18 1
 '@BASEBOARD_FAB2_LIB.BASEBOARD_FAB2(SCH_1):PAGE211_I64@MSTR_DISCRETE.RES(CHIPS)':
 'A': CDS_PINID='A';
NODE_NAME     R3P21 1
 '@BASEBOARD_FAB2_LIB.BASEBOARD_FAB2(SCH_1):PAGE211_I88@MSTR_DISCRETE.RES(CHIPS)':
 'A': CDS_PINID='A';
NODE_NAME     R6P49 1
 '@BASEBOARD_FAB2_LIB.BASEBOARD_FAB2(SCH_1):PAGE213_I14@MSTR_DISCRETE.RES(CHIPS)':
 'A': CDS_PINID='A';
NODE_NAME     R4D42 1
 '@BASEBOARD_FAB2_LIB.BASEBOARD_FAB2(SCH_1):PAGE213_I15@MSTR_DISCRETE.RES(CHIPS)':
 'A': CDS_PINID='A';
NODE_NAME     R4D47 1
 '@BASEBOARD_FAB2_LIB.BASEBOARD_FAB2(SCH_1):PAGE213_I25@MSTR_DISCRETE.RES(CHIPS)':
 'A': CDS_PINID='A';
NODE_NAME     R4D49 1
 '@BASEBOARD_FAB2_LIB.BASEBOARD_FAB2(SCH_1):PAGE213_I63@MSTR_DISCRETE.RES(CHIPS)':
 'A': CDS_PINID='A';
NODE_NAME     R6P40 1
 '@BASEBOARD_FAB2_LIB.BASEBOARD_FAB2(SCH_1):PAGE213_I91@MSTR_DISCRETE.RES(CHIPS)':
 'A': CDS_PINID='A';
NODE_NAME     R3M5 1
 '@BASEBOARD_FAB2_LIB.BASEBOARD_FAB2(SCH_1):PAGE218_I34@MSTR_DISCRETE.RES(CHIPS)':
 'A': CDS_PINID='A';
NODE_NAME     R3M1 1
 '@BASEBOARD_FAB2_LIB.BASEBOARD_FAB2(SCH_1):PAGE218_I35@MSTR_DISCRETE.RES(CHIPS)':
 'A': CDS_PINID='A';
NODE_NAME     R1B2 1
 '@BASEBOARD_FAB2_LIB.BASEBOARD_FAB2(SCH_1):PAGE226_I50@MSTR_DISCRETE.RES(CHIPS)':
 'A': CDS_PINID='A';
NODE_NAME     R7F19 1
 '@BASEBOARD_FAB2_LIB.BASEBOARD_FAB2(SCH_1):PAGE231_I143@MSTR_DISCRETE.RES(CHIPS)':
 'A': CDS_PINID='A';
NODE_NAME     R7B17 1
 '@BASEBOARD_FAB2_LIB.BASEBOARD_FAB2(SCH_1):PAGE232_I210@MSTR_DISCRETE.RES(CHIPS)':
 'A': CDS_PINID='A';
NODE_NAME     R4G14 1
 '@BASEBOARD_FAB2_LIB.BASEBOARD_FAB2(SCH_1):PAGE233_I185@MSTR_DISCRETE.RES(CHIPS)':
 'A': CDS_PINID='A';
NODE_NAME     R4B10 1
 '@BASEBOARD_FAB2_LIB.BASEBOARD_FAB2(SCH_1):PAGE234_I143@MSTR_DISCRETE.RES(CHIPS)':
 'A': CDS_PINID='A';
NODE_NAME     R2L24 1
 '@BASEBOARD_FAB2_LIB.BASEBOARD_FAB2(SCH_1):PAGE235_I148@MSTR_DISCRETE.RES(CHIPS)':
 'A': CDS_PINID='A';
NODE_NAME     R8A6 1
 '@BASEBOARD_FAB2_LIB.BASEBOARD_FAB2(SCH_1):PAGE235_I149@MSTR_DISCRETE.RES(CHIPS)':
 'A': CDS_PINID='A';
NODE_NAME     R2L14 1
 '@BASEBOARD_FAB2_LIB.BASEBOARD_FAB2(SCH_1):PAGE235_I159@MSTR_DISCRETE.RES(CHIPS)':
 'A': CDS_PINID='A';
NODE_NAME     R8A5 1
 '@BASEBOARD_FAB2_LIB.BASEBOARD_FAB2(SCH_1):PAGE235_I216@MSTR_DISCRETE.RES(CHIPS)':
 'A': CDS_PINID='A';
NODE_NAME     R8A7 1
 '@BASEBOARD_FAB2_LIB.BASEBOARD_FAB2(SCH_1):PAGE235_I222@MSTR_DISCRETE.RES(CHIPS)':
 'A': CDS_PINID='A';
NODE_NAME     R8A10 1
 '@BASEBOARD_FAB2_LIB.BASEBOARD_FAB2(SCH_1):PAGE237_I3@MSTR_DISCRETE.RES(CHIPS)':
 'A': CDS_PINID='A';
NODE_NAME     C8A6 1
 '@BASEBOARD_FAB2_LIB.BASEBOARD_FAB2(SCH_1):PAGE237_I29@MSTR_DISCRETE.CAP(CHIPS)':
 'A': CDS_PINID='A';
NODE_NAME     C8A4 1
 '@BASEBOARD_FAB2_LIB.BASEBOARD_FAB2(SCH_1):PAGE237_I31@MSTR_DISCRETE.CAP(CHIPS)':
 'A': CDS_PINID='A';
NODE_NAME     EU8A2 10
 '@BASEBOARD_FAB2_LIB.BASEBOARD_FAB2(SCH_1):PAGE237_I86@MSTR_VREG.RT9059(CHIPS)':
 'VDD': CDS_PINID='VDD';
NODE_NAME     EU8A2 7
 '@BASEBOARD_FAB2_LIB.BASEBOARD_FAB2(SCH_1):PAGE237_I86@MSTR_VREG.RT9059(CHIPS)':
 'VIN'<0>: CDS_PINID='VIN(0)';
NODE_NAME     EU8A2 8
 '@BASEBOARD_FAB2_LIB.BASEBOARD_FAB2(SCH_1):PAGE237_I86@MSTR_VREG.RT9059(CHIPS)':
 'VIN'<1>: CDS_PINID='VIN(1)';
NODE_NAME     EU8A2 9
 '@BASEBOARD_FAB2_LIB.BASEBOARD_FAB2(SCH_1):PAGE237_I86@MSTR_VREG.RT9059(CHIPS)':
 'VIN'<2>: CDS_PINID='VIN(2)';
NODE_NAME     C9F3 1
 '@BASEBOARD_FAB2_LIB.BASEBOARD_FAB2(SCH_1):PAGE238_I7@MSTR_DISCRETE.CAP(CHIPS)':
 'A': CDS_PINID='A';
NODE_NAME     R9F13 1
 '@BASEBOARD_FAB2_LIB.BASEBOARD_FAB2(SCH_1):PAGE238_I21@MSTR_DISCRETE.RES(CHIPS)':
 'A': CDS_PINID='A';
NODE_NAME     C9E11 1
 '@BASEBOARD_FAB2_LIB.BASEBOARD_FAB2(SCH_1):PAGE238_I39@MSTR_DISCRETE.CAP(CHIPS)':
 'A': CDS_PINID='A';
NODE_NAME     EU9F1 10
 '@BASEBOARD_FAB2_LIB.BASEBOARD_FAB2(SCH_1):PAGE238_I40@MSTR_VREG.RT9059(CHIPS)':
 'VDD': CDS_PINID='VDD';
NODE_NAME     EU9F1 7
 '@BASEBOARD_FAB2_LIB.BASEBOARD_FAB2(SCH_1):PAGE238_I40@MSTR_VREG.RT9059(CHIPS)':
 'VIN'<0>: CDS_PINID='VIN(0)';
NODE_NAME     EU9F1 8
 '@BASEBOARD_FAB2_LIB.BASEBOARD_FAB2(SCH_1):PAGE238_I40@MSTR_VREG.RT9059(CHIPS)':
 'VIN'<1>: CDS_PINID='VIN(1)';
NODE_NAME     EU9F1 9
 '@BASEBOARD_FAB2_LIB.BASEBOARD_FAB2(SCH_1):PAGE238_I40@MSTR_VREG.RT9059(CHIPS)':
 'VIN'<2>: CDS_PINID='VIN(2)';
NODE_NAME     R9F12 1
 '@BASEBOARD_FAB2_LIB.BASEBOARD_FAB2(SCH_1):PAGE239_I6@MSTR_DISCRETE.RES(CHIPS)':
 'A': CDS_PINID='A';
NODE_NAME     C1T7 1
 '@BASEBOARD_FAB2_LIB.BASEBOARD_FAB2(SCH_1):PAGE239_I22@MSTR_DISCRETE.CAP(CHIPS)':
 'A': CDS_PINID='A';
NODE_NAME     EU9F2 10
 '@BASEBOARD_FAB2_LIB.BASEBOARD_FAB2(SCH_1):PAGE239_I70@MSTR_VREG.RT9059(CHIPS)':
 'VDD': CDS_PINID='VDD';
NODE_NAME     EU9F2 7
 '@BASEBOARD_FAB2_LIB.BASEBOARD_FAB2(SCH_1):PAGE239_I70@MSTR_VREG.RT9059(CHIPS)':
 'VIN'<0>: CDS_PINID='VIN(0)';
NODE_NAME     EU9F2 8
 '@BASEBOARD_FAB2_LIB.BASEBOARD_FAB2(SCH_1):PAGE239_I70@MSTR_VREG.RT9059(CHIPS)':
 'VIN'<1>: CDS_PINID='VIN(1)';
NODE_NAME     EU9F2 9
 '@BASEBOARD_FAB2_LIB.BASEBOARD_FAB2(SCH_1):PAGE239_I70@MSTR_VREG.RT9059(CHIPS)':
 'VIN'<2>: CDS_PINID='VIN(2)';
NODE_NAME     C9F5 1
 '@BASEBOARD_FAB2_LIB.BASEBOARD_FAB2(SCH_1):PAGE239_I71@DEV_DISCRETE.CAP_A(CHIPS)':
 'A': CDS_PINID='A';
NODE_NAME     R8F5 1
 '@BASEBOARD_FAB2_LIB.BASEBOARD_FAB2(SCH_1):PAGE240_I117@MSTR_DISCRETE.RES(CHIPS)':
 'A': CDS_PINID='A';
NODE_NAME     R8E25 1
 '@BASEBOARD_FAB2_LIB.BASEBOARD_FAB2(SCH_1):PAGE240_I144@MSTR_DISCRETE.RES(CHIPS)':
 'A': CDS_PINID='A';
NODE_NAME     R2T4 1
 '@BASEBOARD_FAB2_LIB.BASEBOARD_FAB2(SCH_1):PAGE240_I152@MSTR_DISCRETE.RES(CHIPS)':
 'A': CDS_PINID='A';
NODE_NAME     C2T7 1
 '@BASEBOARD_FAB2_LIB.BASEBOARD_FAB2(SCH_1):PAGE240_I158@MSTR_DISCRETE.CAP(CHIPS)':
 'A': CDS_PINID='A';
NODE_NAME     C2T6 1
 '@BASEBOARD_FAB2_LIB.BASEBOARD_FAB2(SCH_1):PAGE240_I160@MSTR_DISCRETE.CAP(CHIPS)':
 'A': CDS_PINID='A';
NODE_NAME     C2T9 1
 '@BASEBOARD_FAB2_LIB.BASEBOARD_FAB2(SCH_1):PAGE240_I174@MSTR_DISCRETE.CAP(CHIPS)':
 'A': CDS_PINID='A';
NODE_NAME     R8E40 1
 '@BASEBOARD_FAB2_LIB.BASEBOARD_FAB2(SCH_1):PAGE240_I177@MSTR_DISCRETE.RES(CHIPS)':
 'A': CDS_PINID='A';
NODE_NAME     RN8F3 1
 '@BASEBOARD_FAB2_LIB.BASEBOARD_FAB2(SCH_1):PAGE246_I11@MSTR_DISCRETE.RES(CHIPS)':
 'A': CDS_PINID='A';
NODE_NAME     RN8F4 1
 '@BASEBOARD_FAB2_LIB.BASEBOARD_FAB2(SCH_1):PAGE246_I12@MSTR_DISCRETE.RES(CHIPS)':
 'A': CDS_PINID='A';
NODE_NAME     UN8F2 2
 '@BASEBOARD_FAB2_LIB.BASEBOARD_FAB2(SCH_1):PAGE246_I17@MSTR_MEMORY.W25Q256(CHIPS)':
 'VCC': CDS_PINID='VCC';
NODE_NAME     R6W10 1
 '@BASEBOARD_FAB2_LIB.BASEBOARD_FAB2(SCH_1):PAGE247_I1@MSTR_DISCRETE.RES(CHIPS)':
 'A': CDS_PINID='A';
NODE_NAME     R3W7 1
 '@BASEBOARD_FAB2_LIB.BASEBOARD_FAB2(SCH_1):PAGE249_I8@MSTR_DISCRETE.RES(CHIPS)':
 'A': CDS_PINID='A';
NODE_NAME     EU25F2 10
 '@BASEBOARD_FAB2_LIB.BASEBOARD_FAB2(SCH_1):PAGE239_I73@MSTR_VREG.RT9059(CHIPS)':
 'VDD': CDS_PINID='VDD';
NODE_NAME     EU25F2 7
 '@BASEBOARD_FAB2_LIB.BASEBOARD_FAB2(SCH_1):PAGE239_I73@MSTR_VREG.RT9059(CHIPS)':
 'VIN'<0>: CDS_PINID='VIN(0)';
NODE_NAME     EU25F2 8
 '@BASEBOARD_FAB2_LIB.BASEBOARD_FAB2(SCH_1):PAGE239_I73@MSTR_VREG.RT9059(CHIPS)':
 'VIN'<1>: CDS_PINID='VIN(1)';
NODE_NAME     EU25F2 9
 '@BASEBOARD_FAB2_LIB.BASEBOARD_FAB2(SCH_1):PAGE239_I73@MSTR_VREG.RT9059(CHIPS)':
 'VIN'<2>: CDS_PINID='VIN(2)';
NODE_NAME     R9W12 1
 '@BASEBOARD_FAB2_LIB.BASEBOARD_FAB2(SCH_1):PAGE239_I79@MSTR_DISCRETE.RES(CHIPS)':
 'A': CDS_PINID='A';
NODE_NAME     C9W5 1
 '@BASEBOARD_FAB2_LIB.BASEBOARD_FAB2(SCH_1):PAGE239_I90@DEV_DISCRETE.CAP_A(CHIPS)':
 'A': CDS_PINID='A';
NODE_NAME     C1W7 1
 '@BASEBOARD_FAB2_LIB.BASEBOARD_FAB2(SCH_1):PAGE239_I92@MSTR_DISCRETE.CAP(CHIPS)':
 'A': CDS_PINID='A';
NODE_NAME     Y9F2 4
 '@BASEBOARD_FAB2_LIB.BASEBOARD_FAB2(SCH_1):PAGE145_I8@MSTR_DISCRETE.OSC_C(CHIPS)':
 'VDD': CDS_PINID='VDD';
NODE_NAME     R9F61 1
 '@BASEBOARD_FAB2_LIB.BASEBOARD_FAB2(SCH_1):PAGE145_I14@MSTR_DISCRETE.RES(CHIPS)':
 'A': CDS_PINID='A';
NODE_NAME     C9F23 1
 '@BASEBOARD_FAB2_LIB.BASEBOARD_FAB2(SCH_1):PAGE145_I15@DEV_DISCRETE.CAP_A(CHIPS)':
 'A': CDS_PINID='A';
NODE_NAME     R25W79 1
 '@BASEBOARD_FAB2_LIB.BASEBOARD_FAB2(SCH_1):PAGE147_I42@MSTR_DISCRETE.RES(CHIPS)':
 'A': CDS_PINID='A';
NODE_NAME     R25W80 1
 '@BASEBOARD_FAB2_LIB.BASEBOARD_FAB2(SCH_1):PAGE147_I43@MSTR_DISCRETE.RES(CHIPS)':
 'A': CDS_PINID='A';
NODE_NAME     R25W59 1
 '@BASEBOARD_FAB2_LIB.BASEBOARD_FAB2(SCH_1):PAGE148_I16@MSTR_DISCRETE.RES(CHIPS)':
 'A': CDS_PINID='A';
NODE_NAME     C6W3 1
 '@BASEBOARD_FAB2_LIB.BASEBOARD_FAB2(SCH_1):PAGE247_I85@DEV_DISCRETE.CAP_A(CHIPS)':
 'A': CDS_PINID='A';
NODE_NAME     R6W21 1
 '@BASEBOARD_FAB2_LIB.BASEBOARD_FAB2(SCH_1):PAGE247_I90@MSTR_DISCRETE.RES(CHIPS)':
 'A': CDS_PINID='A';
NODE_NAME     U25W4 J17
 '@BASEBOARD_FAB2_LIB.BASEBOARD_FAB2(SCH_1):PAGE148_I28@W_HDL.AST2520A1-GP-GP(CHIPS)':
 'LPVDD0': CDS_PINID='LPVDD0';
NODE_NAME     U25W4 K17
 '@BASEBOARD_FAB2_LIB.BASEBOARD_FAB2(SCH_1):PAGE148_I28@W_HDL.AST2520A1-GP-GP(CHIPS)':
 'LPVDD1': CDS_PINID='LPVDD1';
NODE_NAME     U25W4 F10
 '@BASEBOARD_FAB2_LIB.BASEBOARD_FAB2(SCH_1):PAGE148_I28@W_HDL.AST2520A1-GP-GP(CHIPS)':
 'R1VDD0': CDS_PINID='R1VDD0';
NODE_NAME     U25W4 F11
 '@BASEBOARD_FAB2_LIB.BASEBOARD_FAB2(SCH_1):PAGE148_I28@W_HDL.AST2520A1-GP-GP(CHIPS)':
 'R1VDD1': CDS_PINID='R1VDD1';
NODE_NAME     U25W4 F7
 '@BASEBOARD_FAB2_LIB.BASEBOARD_FAB2(SCH_1):PAGE148_I28@W_HDL.AST2520A1-GP-GP(CHIPS)':
 'R2VDD0': CDS_PINID='R2VDD0';
NODE_NAME     U25W4 F8
 '@BASEBOARD_FAB2_LIB.BASEBOARD_FAB2(SCH_1):PAGE148_I28@W_HDL.AST2520A1-GP-GP(CHIPS)':
 'R2VDD1': CDS_PINID='R2VDD1';
NODE_NAME     U3T1 2
 '@BASEBOARD_FAB2_LIB.BASEBOARD_FAB2(SCH_1):PAGE153_I185@W_HDL.W25Q256FVFIG-GP(CHIPS)':
 'VCC': CDS_PINID='VCC';
NODE_NAME     R6W11 2
 '@BASEBOARD_FAB2_LIB.BASEBOARD_FAB2(SCH_1):PAGE247_I98@MSTR_DISCRETE.RES(CHIPS)':
 'B': CDS_PINID='B';
NODE_NAME     R6W12 2
 '@BASEBOARD_FAB2_LIB.BASEBOARD_FAB2(SCH_1):PAGE247_I99@MSTR_DISCRETE.RES(CHIPS)':
 'B': CDS_PINID='B';
NODE_NAME     FB2T1 1
 '@BASEBOARD_FAB2_LIB.BASEBOARD_FAB2(SCH_1):PAGE149_I22@W_HDL.HCB1608KF-800T30-GP(CHIPS)':
 '1': CDS_PINID='\1\';
NODE_NAME     C25W50 1
 '@BASEBOARD_FAB2_LIB.BASEBOARD_FAB2(SCH_1):PAGE149_I31@MSTR_DISCRETE.CAP(CHIPS)':
 'A': CDS_PINID='A';
NODE_NAME     C25W62 1
 '@BASEBOARD_FAB2_LIB.BASEBOARD_FAB2(SCH_1):PAGE149_I40@MSTR_DISCRETE.CAP(CHIPS)':
 'A': CDS_PINID='A';
NODE_NAME     FB2T3 1
 '@BASEBOARD_FAB2_LIB.BASEBOARD_FAB2(SCH_1):PAGE149_I85@W_HDL.HCB1608KF-800T30-GP(CHIPS)':
 '1': CDS_PINID='\1\';
NODE_NAME     FB2T4 1
 '@BASEBOARD_FAB2_LIB.BASEBOARD_FAB2(SCH_1):PAGE149_I86@W_HDL.HCB1608KF-800T30-GP(CHIPS)':
 '1': CDS_PINID='\1\';
NODE_NAME     FB2T5 1
 '@BASEBOARD_FAB2_LIB.BASEBOARD_FAB2(SCH_1):PAGE149_I88@W_HDL.HCB1608KF-800T30-GP(CHIPS)':
 '1': CDS_PINID='\1\';
NODE_NAME     R9E24 2
 '@BASEBOARD_FAB2_LIB.BASEBOARD_FAB2(SCH_1):PAGE151_I138@MSTR_DISCRETE.RES(CHIPS)':
 'B': CDS_PINID='B';
NODE_NAME     R9E21 1
 '@BASEBOARD_FAB2_LIB.BASEBOARD_FAB2(SCH_1):PAGE151_I173@MSTR_DISCRETE.RES(CHIPS)':
 'A': CDS_PINID='A';
NODE_NAME     R8B25 1
 '@BASEBOARD_FAB2_LIB.BASEBOARD_FAB2(SCH_1):PAGE151_I175@MSTR_DISCRETE.RES(CHIPS)':
 'A': CDS_PINID='A';
NODE_NAME     R25W95 1
 '@BASEBOARD_FAB2_LIB.BASEBOARD_FAB2(SCH_1):PAGE150_I144@MSTR_DISCRETE.RES(CHIPS)':
 'A': CDS_PINID='A';
NODE_NAME     R25W96 1
 '@BASEBOARD_FAB2_LIB.BASEBOARD_FAB2(SCH_1):PAGE150_I145@MSTR_DISCRETE.RES(CHIPS)':
 'A': CDS_PINID='A';
NODE_NAME     R25W97 1
 '@BASEBOARD_FAB2_LIB.BASEBOARD_FAB2(SCH_1):PAGE150_I146@MSTR_DISCRETE.RES(CHIPS)':
 'A': CDS_PINID='A';
NODE_NAME     R25W106 1
 '@BASEBOARD_FAB2_LIB.BASEBOARD_FAB2(SCH_1):PAGE150_I175@MSTR_DISCRETE.RES(CHIPS)':
 'A': CDS_PINID='A';
NODE_NAME     R25W111 1
 '@BASEBOARD_FAB2_LIB.BASEBOARD_FAB2(SCH_1):PAGE150_I180@MSTR_DISCRETE.RES(CHIPS)':
 'A': CDS_PINID='A';
NODE_NAME     R6W24 1
 '@BASEBOARD_FAB2_LIB.BASEBOARD_FAB2(SCH_1):PAGE247_I100@MSTR_DISCRETE.RES(CHIPS)':
 'A': CDS_PINID='A';
NODE_NAME     R6W25 1
 '@BASEBOARD_FAB2_LIB.BASEBOARD_FAB2(SCH_1):PAGE247_I101@MSTR_DISCRETE.RES(CHIPS)':
 'A': CDS_PINID='A';
NODE_NAME     C6W4 1
 '@BASEBOARD_FAB2_LIB.BASEBOARD_FAB2(SCH_1):PAGE247_I105@DEV_DISCRETE.CAP_A(CHIPS)':
 'A': CDS_PINID='A';
NODE_NAME     C6W2 1
 '@BASEBOARD_FAB2_LIB.BASEBOARD_FAB2(SCH_1):PAGE247_I107@DEV_DISCRETE.CAP_A(CHIPS)':
 'A': CDS_PINID='A';
NODE_NAME     C9W7 1
 '@BASEBOARD_FAB2_LIB.BASEBOARD_FAB2(SCH_1):PAGE248_I32@DEV_DISCRETE.CAP_A(CHIPS)':
 'A': CDS_PINID='A';
NODE_NAME     R9W16 1
 '@BASEBOARD_FAB2_LIB.BASEBOARD_FAB2(SCH_1):PAGE248_I34@MSTR_DISCRETE.RES(CHIPS)':
 'A': CDS_PINID='A';
NODE_NAME     R9W17 1
 '@BASEBOARD_FAB2_LIB.BASEBOARD_FAB2(SCH_1):PAGE248_I35@MSTR_DISCRETE.RES(CHIPS)':
 'A': CDS_PINID='A';
NODE_NAME     R1U23 1
 '@BASEBOARD_FAB2_LIB.BASEBOARD_FAB2(SCH_1):PAGE164_I34@MSTR_DISCRETE.RES(CHIPS)':
 'A': CDS_PINID='A';
NODE_NAME     R6W28 1
 '@BASEBOARD_FAB2_LIB.BASEBOARD_FAB2(SCH_1):PAGE247_I112@MSTR_DISCRETE.RES(CHIPS)':
 'A': CDS_PINID='A';
NODE_NAME     R25W93 1
 '@BASEBOARD_FAB2_LIB.BASEBOARD_FAB2(SCH_1):PAGE149_I90@MSTR_DISCRETE.RES(CHIPS)':
 'A': CDS_PINID='A';
NODE_NAME     R25W120 1
 '@BASEBOARD_FAB2_LIB.BASEBOARD_FAB2(SCH_1):PAGE149_I91@MSTR_DISCRETE.RES(CHIPS)':
 'A': CDS_PINID='A';
NODE_NAME     R1W6 1
 '@BASEBOARD_FAB2_LIB.BASEBOARD_FAB2(SCH_1):PAGE250_I2@W_HDL.1MR2F-L-GP(CHIPS)':
 '1': CDS_PINID='\1\';
NODE_NAME     R1W7 2
 '@BASEBOARD_FAB2_LIB.BASEBOARD_FAB2(SCH_1):PAGE250_I6@MSTR_DISCRETE.RES(CHIPS)':
 'B': CDS_PINID='B';
NODE_NAME     RN8F2 1
 '@BASEBOARD_FAB2_LIB.BASEBOARD_FAB2(SCH_1):PAGE246_I20@MSTR_DISCRETE.RES(CHIPS)':
 'A': CDS_PINID='A';
NODE_NAME     R9W1 1
 '@BASEBOARD_FAB2_LIB.BASEBOARD_FAB2(SCH_1):PAGE186_I356@MSTR_DISCRETE.RES(CHIPS)':
 'A': CDS_PINID='A';
NODE_NAME     R2W1 1
 '@BASEBOARD_FAB2_LIB.BASEBOARD_FAB2(SCH_1):PAGE187_I174@MSTR_DISCRETE.RES(CHIPS)':
 'A': CDS_PINID='A';
NODE_NAME     C25W60 1
 '@BASEBOARD_FAB2_LIB.BASEBOARD_FAB2(SCH_1):PAGE149_I109@MSTR_DISCRETE.CAP(CHIPS)':
 'A': CDS_PINID='A';
NODE_NAME     C25W48 1
 '@BASEBOARD_FAB2_LIB.BASEBOARD_FAB2(SCH_1):PAGE149_I112@MSTR_DISCRETE.CAP(CHIPS)':
 'A': CDS_PINID='A';
NODE_NAME     R3W3 1
 '@BASEBOARD_FAB2_LIB.BASEBOARD_FAB2(SCH_1):PAGE249_I36@MSTR_DISCRETE.RES(CHIPS)':
 'A': CDS_PINID='A';
NODE_NAME     U2R1 5
 '@BASEBOARD_FAB2_LIB.BASEBOARD_FAB2(SCH_1):PAGE157_I390@W_HDL.TC7PZ14FU-GP(CHIPS)':
 'VCC': CDS_PINID='VCC';
NODE_NAME     U9A3 5
 '@BASEBOARD_FAB2_LIB.BASEBOARD_FAB2(SCH_1):PAGE175_I93@W_HDL.TC7PZ14FU-GP(CHIPS)':
 'VCC': CDS_PINID='VCC';
NODE_NAME     U9A4 5
 '@BASEBOARD_FAB2_LIB.BASEBOARD_FAB2(SCH_1):PAGE175_I97@W_HDL.TC7PZ14FU-GP(CHIPS)':
 'VCC': CDS_PINID='VCC';
NODE_NAME     U8F3 5
 '@BASEBOARD_FAB2_LIB.BASEBOARD_FAB2(SCH_1):PAGE156_I340@W_HDL.SN74LVC2G07DCKR-GP(CHIPS)':
 'VCC': CDS_PINID='VCC';
NODE_NAME     U8G1 5
 '@BASEBOARD_FAB2_LIB.BASEBOARD_FAB2(SCH_1):PAGE156_I342@W_HDL.SN74LVC2G07DCKR-GP(CHIPS)':
 'VCC': CDS_PINID='VCC';
NODE_NAME     R10W2 1
 '@BASEBOARD_FAB2_LIB.BASEBOARD_FAB2(SCH_1):PAGE251_I15@MSTR_DISCRETE.RES(CHIPS)':
 'A': CDS_PINID='A';
NODE_NAME     C10W4 1
 '@BASEBOARD_FAB2_LIB.BASEBOARD_FAB2(SCH_1):PAGE251_I21@DEV_DISCRETE.CAP_A(CHIPS)':
 'A': CDS_PINID='A';
NODE_NAME     R1W1 1
 '@BASEBOARD_FAB2_LIB.BASEBOARD_FAB2(SCH_1):PAGE250_I18@W_HDL.1MR2F-L-GP(CHIPS)':
 '1': CDS_PINID='\1\';
NODE_NAME     R1W4 2
 '@BASEBOARD_FAB2_LIB.BASEBOARD_FAB2(SCH_1):PAGE250_I22@MSTR_DISCRETE.RES(CHIPS)':
 'B': CDS_PINID='B';
NODE_NAME     R1W3 1
 '@BASEBOARD_FAB2_LIB.BASEBOARD_FAB2(SCH_1):PAGE250_I27@W_HDL.1MR2F-L-GP(CHIPS)':
 '1': CDS_PINID='\1\';
NODE_NAME     R1D10 1
 '@BASEBOARD_FAB2_LIB.BASEBOARD_FAB2(SCH_1):PAGE200_I244@MSTR_DISCRETE.RES(CHIPS)':
 'A': CDS_PINID='A';
NODE_NAME     R25W107 1
 '@BASEBOARD_FAB2_LIB.BASEBOARD_FAB2(SCH_1):PAGE150_I190@MSTR_DISCRETE.RES(CHIPS)':
 'A': CDS_PINID='A';
NODE_NAME     R25W108 1
 '@BASEBOARD_FAB2_LIB.BASEBOARD_FAB2(SCH_1):PAGE150_I191@MSTR_DISCRETE.RES(CHIPS)':
 'A': CDS_PINID='A';
NODE_NAME     U1B2 8
 '@BASEBOARD_FAB2_LIB.BASEBOARD_FAB2(SCH_1):PAGE163_I28@W_HDL.TCA9517DGKR-GP(CHIPS)':
 'VCCB': CDS_PINID='VCCB';
NODE_NAME     U6W2 1
 '@BASEBOARD_FAB2_LIB.BASEBOARD_FAB2(SCH_1):PAGE247_I118@W_HDL.TCA9517DGKR-GP(CHIPS)':
 'VCCA': CDS_PINID='VCCA';
NODE_NAME     U6W2 8
 '@BASEBOARD_FAB2_LIB.BASEBOARD_FAB2(SCH_1):PAGE247_I118@W_HDL.TCA9517DGKR-GP(CHIPS)':
 'VCCB': CDS_PINID='VCCB';
NODE_NAME     U1W2 8
 '@BASEBOARD_FAB2_LIB.BASEBOARD_FAB2(SCH_1):PAGE248_I49@W_HDL.TCA9517DGKR-GP(CHIPS)':
 'VCCB': CDS_PINID='VCCB';
NODE_NAME     R8D16 1
 '@BASEBOARD_FAB2_LIB.BASEBOARD_FAB2(SCH_1):PAGE125_I85@MSTR_DISCRETE.RES(CHIPS)':
 'A': CDS_PINID='A';
NODE_NAME     R8D13 1
 '@BASEBOARD_FAB2_LIB.BASEBOARD_FAB2(SCH_1):PAGE125_I87@MSTR_DISCRETE.RES(CHIPS)':
 'A': CDS_PINID='A';
NODE_NAME     C22W34 1
 '@BASEBOARD_FAB2_LIB.BASEBOARD_FAB2(SCH_1):PAGE139_I244@W_HDL.SC22U16V5MX-4-GP(CHIPS)':
 '1': CDS_PINID='\1\';
NODE_NAME     C9F2 1
 '@BASEBOARD_FAB2_LIB.BASEBOARD_FAB2(SCH_1):PAGE139_I245@W_HDL.SC22U16V5MX-4-GP(CHIPS)':
 '1': CDS_PINID='\1\';
NODE_NAME     R2N10 1
 '@BASEBOARD_FAB2_LIB.BASEBOARD_FAB2(SCH_1):PAGE126_I27@MSTR_DISCRETE.RES(CHIPS)':
 'A': CDS_PINID='A';
NODE_NAME     U6W1 24
 '@BASEBOARD_FAB2_LIB.BASEBOARD_FAB2(SCH_1):PAGE247_I120@W_HDL.TCA9555PWR-GP(CHIPS)':
 'VCC': CDS_PINID='VCC';
NODE_NAME     R2U30 1
 '@BASEBOARD_FAB2_LIB.BASEBOARD_FAB2(SCH_1):PAGE125_I88@MSTR_DISCRETE.RES(CHIPS)':
 'A': CDS_PINID='A';
NODE_NAME     R9F55 1
 '@BASEBOARD_FAB2_LIB.BASEBOARD_FAB2(SCH_1):PAGE183_I3@MSTR_DISCRETE.RES(CHIPS)':
 'A': CDS_PINID='A';
NODE_NAME     C9G2 1
 '@BASEBOARD_FAB2_LIB.BASEBOARD_FAB2(SCH_1):PAGE141_I152@MSTR_DISCRETE.CAP(CHIPS)':
 'A': CDS_PINID='A';
NODE_NAME     R9G4 2
 '@BASEBOARD_FAB2_LIB.BASEBOARD_FAB2(SCH_1):PAGE141_I156@MSTR_DISCRETE.RES(CHIPS)':
 'B': CDS_PINID='B';
NODE_NAME     R1L19 1
 '@BASEBOARD_FAB2_LIB.BASEBOARD_FAB2(SCH_1):PAGE175_I99@MSTR_DISCRETE.RES(CHIPS)':
 'A': CDS_PINID='A';
NODE_NAME     R1L28 1
 '@BASEBOARD_FAB2_LIB.BASEBOARD_FAB2(SCH_1):PAGE111_I97@MSTR_DISCRETE.RES(CHIPS)':
 'A': CDS_PINID='A';
NODE_NAME     L8F1 2
 '@BASEBOARD_FAB2_LIB.BASEBOARD_FAB2(SCH_1):PAGE240_I188@W_HDL.IND-1UH-361-GP(CHIPS)':
 '2': CDS_PINID='\2\';
NODE_NAME     C8F14 1
 '@BASEBOARD_FAB2_LIB.BASEBOARD_FAB2(SCH_1):PAGE240_I189@W_HDL.ST470U6D3VDM-7-GP(CHIPS)':
 '1': CDS_PINID='\1\';
NODE_NAME     C8F8 1
 '@BASEBOARD_FAB2_LIB.BASEBOARD_FAB2(SCH_1):PAGE240_I190@W_HDL.ST470U6D3VDM-7-GP(CHIPS)':
 '1': CDS_PINID='\1\';
NODE_NAME     R4W1 1
 '@BASEBOARD_FAB2_LIB.BASEBOARD_FAB2(SCH_1):PAGE191_I195@MSTR_DISCRETE.RES(CHIPS)':
 'A': CDS_PINID='A';
NODE_NAME     R4E4 1
 '@BASEBOARD_FAB2_LIB.BASEBOARD_FAB2(SCH_1):PAGE201_I187@MSTR_DISCRETE.RES(CHIPS)':
 'A': CDS_PINID='A';
NODE_NAME     R1D7 1
 '@BASEBOARD_FAB2_LIB.BASEBOARD_FAB2(SCH_1):PAGE206_I155@MSTR_DISCRETE.RES(CHIPS)':
 'A': CDS_PINID='A';
NODE_NAME     R25W105 1
 '@BASEBOARD_FAB2_LIB.BASEBOARD_FAB2(SCH_1):PAGE150_I196@MSTR_DISCRETE.RES(CHIPS)':
 'A': CDS_PINID='A';
NODE_NAME     R8F13 1
 '@BASEBOARD_FAB2_LIB.BASEBOARD_FAB2(SCH_1):PAGE162_I35@MSTR_DISCRETE.RES(CHIPS)':
 'A': CDS_PINID='A';
NODE_NAME     R25W98 1
 '@BASEBOARD_FAB2_LIB.BASEBOARD_FAB2(SCH_1):PAGE150_I209@MSTR_DISCRETE.RES(CHIPS)':
 'A': CDS_PINID='A';
NODE_NAME     R25W99 1
 '@BASEBOARD_FAB2_LIB.BASEBOARD_FAB2(SCH_1):PAGE150_I210@MSTR_DISCRETE.RES(CHIPS)':
 'A': CDS_PINID='A';
NODE_NAME     R25W100 1
 '@BASEBOARD_FAB2_LIB.BASEBOARD_FAB2(SCH_1):PAGE150_I211@MSTR_DISCRETE.RES(CHIPS)':
 'A': CDS_PINID='A';
NODE_NAME     R25W103 1
 '@BASEBOARD_FAB2_LIB.BASEBOARD_FAB2(SCH_1):PAGE150_I214@MSTR_DISCRETE.RES(CHIPS)':
 'A': CDS_PINID='A';
NODE_NAME     R25W104 1
 '@BASEBOARD_FAB2_LIB.BASEBOARD_FAB2(SCH_1):PAGE150_I215@MSTR_DISCRETE.RES(CHIPS)':
 'A': CDS_PINID='A';
NODE_NAME     R25W112 1
 '@BASEBOARD_FAB2_LIB.BASEBOARD_FAB2(SCH_1):PAGE150_I228@MSTR_DISCRETE.RES(CHIPS)':
 'A': CDS_PINID='A';
NODE_NAME     R25W113 1
 '@BASEBOARD_FAB2_LIB.BASEBOARD_FAB2(SCH_1):PAGE150_I230@MSTR_DISCRETE.RES(CHIPS)':
 'A': CDS_PINID='A';
NODE_NAME     R25W114 1
 '@BASEBOARD_FAB2_LIB.BASEBOARD_FAB2(SCH_1):PAGE150_I218@MSTR_DISCRETE.RES(CHIPS)':
 'A': CDS_PINID='A';
NODE_NAME     R25W110 1
 '@BASEBOARD_FAB2_LIB.BASEBOARD_FAB2(SCH_1):PAGE150_I233@MSTR_DISCRETE.RES(CHIPS)':
 'A': CDS_PINID='A';
NODE_NAME     R25W109 1
 '@BASEBOARD_FAB2_LIB.BASEBOARD_FAB2(SCH_1):PAGE150_I236@MSTR_DISCRETE.RES(CHIPS)':
 'A': CDS_PINID='A';
NODE_NAME     R25W102 1
 '@BASEBOARD_FAB2_LIB.BASEBOARD_FAB2(SCH_1):PAGE150_I239@MSTR_DISCRETE.RES(CHIPS)':
 'A': CDS_PINID='A';
NODE_NAME     R8B24 1
 '@BASEBOARD_FAB2_LIB.BASEBOARD_FAB2(SCH_1):PAGE138_I186@MSTR_DISCRETE.RES(CHIPS)':
 'A': CDS_PINID='A';
NODE_NAME     R8B26 1
 '@BASEBOARD_FAB2_LIB.BASEBOARD_FAB2(SCH_1):PAGE138_I187@MSTR_DISCRETE.RES(CHIPS)':
 'A': CDS_PINID='A';
NODE_NAME     R25W153 1
 '@BASEBOARD_FAB2_LIB.BASEBOARD_FAB2(SCH_1):PAGE157_I396@MSTR_DISCRETE.RES(CHIPS)':
 'A': CDS_PINID='A';
NODE_NAME     RN8F1 1
 '@BASEBOARD_FAB2_LIB.BASEBOARD_FAB2(SCH_1):PAGE137_I142@MSTR_DISCRETE.RES(CHIPS)':
 'A': CDS_PINID='A';
NODE_NAME     R7F20 1
 '@BASEBOARD_FAB2_LIB.BASEBOARD_FAB2(SCH_1):PAGE215_I29@MSTR_DISCRETE.RES(CHIPS)':
 'A': CDS_PINID='A';
NODE_NAME     R3T13 1
 '@BASEBOARD_FAB2_LIB.BASEBOARD_FAB2(SCH_1):PAGE215_I33@MSTR_DISCRETE.RES(CHIPS)':
 'A': CDS_PINID='A';
NODE_NAME     R7F27 1
 '@BASEBOARD_FAB2_LIB.BASEBOARD_FAB2(SCH_1):PAGE215_I50@MSTR_DISCRETE.RES(CHIPS)':
 'A': CDS_PINID='A';
NODE_NAME     R7F22 1
 '@BASEBOARD_FAB2_LIB.BASEBOARD_FAB2(SCH_1):PAGE215_I51@MSTR_DISCRETE.RES(CHIPS)':
 'A': CDS_PINID='A';
NODE_NAME     R7B4 1
 '@BASEBOARD_FAB2_LIB.BASEBOARD_FAB2(SCH_1):PAGE218_I57@MSTR_DISCRETE.RES(CHIPS)':
 'A': CDS_PINID='A';
NODE_NAME     R7B5 1
 '@BASEBOARD_FAB2_LIB.BASEBOARD_FAB2(SCH_1):PAGE218_I58@MSTR_DISCRETE.RES(CHIPS)':
 'A': CDS_PINID='A';
NODE_NAME     R9U8 1
 '@BASEBOARD_FAB2_LIB.BASEBOARD_FAB2(SCH_1):PAGE223_I31@MSTR_DISCRETE.RES(CHIPS)':
 'A': CDS_PINID='A';
NODE_NAME     R1G16 1
 '@BASEBOARD_FAB2_LIB.BASEBOARD_FAB2(SCH_1):PAGE223_I48@MSTR_DISCRETE.RES(CHIPS)':
 'A': CDS_PINID='A';
NODE_NAME     R1G11 1
 '@BASEBOARD_FAB2_LIB.BASEBOARD_FAB2(SCH_1):PAGE223_I49@MSTR_DISCRETE.RES(CHIPS)':
 'A': CDS_PINID='A';
NODE_NAME     R9U10 1
 '@BASEBOARD_FAB2_LIB.BASEBOARD_FAB2(SCH_1):PAGE223_I32@MSTR_DISCRETE.RES(CHIPS)':
 'A': CDS_PINID='A';
NODE_NAME     R9M5 1
 '@BASEBOARD_FAB2_LIB.BASEBOARD_FAB2(SCH_1):PAGE226_I34@MSTR_DISCRETE.RES(CHIPS)':
 'A': CDS_PINID='A';
NODE_NAME     R1B1 1
 '@BASEBOARD_FAB2_LIB.BASEBOARD_FAB2(SCH_1):PAGE226_I49@MSTR_DISCRETE.RES(CHIPS)':
 'A': CDS_PINID='A';
NODE_NAME     R9M3 1
 '@BASEBOARD_FAB2_LIB.BASEBOARD_FAB2(SCH_1):PAGE226_I36@MSTR_DISCRETE.RES(CHIPS)':
 'A': CDS_PINID='A';
NODE_NAME     C8E1 1
 '@BASEBOARD_FAB2_LIB.BASEBOARD_FAB2(SCH_1):PAGE181_I34@DEV_DISCRETE.CAP_A(CHIPS)':
 'A': CDS_PINID='A';
NODE_NAME     R7D9 1
 '@BASEBOARD_FAB2_LIB.BASEBOARD_FAB2(SCH_1):PAGE181_I80@MSTR_DISCRETE.RES(CHIPS)':
 'A': CDS_PINID='A';
NODE_NAME     R3P61 1
 '@BASEBOARD_FAB2_LIB.BASEBOARD_FAB2(SCH_1):PAGE181_I81@MSTR_DISCRETE.RES(CHIPS)':
 'A': CDS_PINID='A';
NODE_NAME     R7D5 1
 '@BASEBOARD_FAB2_LIB.BASEBOARD_FAB2(SCH_1):PAGE181_I82@MSTR_DISCRETE.RES(CHIPS)':
 'A': CDS_PINID='A';
NODE_NAME     J1F3 1
 '@BASEBOARD_FAB2_LIB.BASEBOARD_FAB2(SCH_1):PAGE181_I106@MSTR_CONN.CONN8_H62179001(CHIPS)':
 'IO1': CDS_PINID='IO1';
NODE_NAME     R24W1 1
 '@BASEBOARD_FAB2_LIB.BASEBOARD_FAB2(SCH_1):PAGE138_I198@MSTR_DISCRETE.RES(CHIPS)':
 'A': CDS_PINID='A';
NODE_NAME     R24W2 1
 '@BASEBOARD_FAB2_LIB.BASEBOARD_FAB2(SCH_1):PAGE138_I199@MSTR_DISCRETE.RES(CHIPS)':
 'A': CDS_PINID='A';
NODE_NAME     R1U21 1
 '@BASEBOARD_FAB2_LIB.BASEBOARD_FAB2(SCH_1):PAGE164_I41@MSTR_DISCRETE.RES(CHIPS)':
 'A': CDS_PINID='A';
NODE_NAME     R1U22 1
 '@BASEBOARD_FAB2_LIB.BASEBOARD_FAB2(SCH_1):PAGE164_I43@MSTR_DISCRETE.RES(CHIPS)':
 'A': CDS_PINID='A';
NODE_NAME     CN8F1 1
 '@BASEBOARD_FAB2_LIB.BASEBOARD_FAB2(SCH_1):PAGE246_I21@DEV_DISCRETE.CAP_A(CHIPS)':
 'A': CDS_PINID='A';
NODE_NAME     CN8F2 1
 '@BASEBOARD_FAB2_LIB.BASEBOARD_FAB2(SCH_1):PAGE246_I22@DEV_DISCRETE.CAP_A(CHIPS)':
 'A': CDS_PINID='A';
NODE_NAME     C25W49 1
 '@BASEBOARD_FAB2_LIB.BASEBOARD_FAB2(SCH_1):PAGE149_I123@DEV_DISCRETE.CAP_A(CHIPS)':
 'A': CDS_PINID='A';
NODE_NAME     C25W61 1
 '@BASEBOARD_FAB2_LIB.BASEBOARD_FAB2(SCH_1):PAGE149_I126@DEV_DISCRETE.CAP_A(CHIPS)':
 'A': CDS_PINID='A';
NODE_NAME     C6W1 1
 '@BASEBOARD_FAB2_LIB.BASEBOARD_FAB2(SCH_1):PAGE247_I151@DEV_DISCRETE.CAP_A(CHIPS)':
 'A': CDS_PINID='A';
NODE_NAME     C6W10 1
 '@BASEBOARD_FAB2_LIB.BASEBOARD_FAB2(SCH_1):PAGE176_I139@DEV_DISCRETE.CAP_A(CHIPS)':
 'A': CDS_PINID='A';
NODE_NAME     U7W1 5
 '@BASEBOARD_FAB2_LIB.BASEBOARD_FAB2(SCH_1):PAGE166_I34@W_HDL.PI5A3157BC6E-GP(CHIPS)':
 'VCC': CDS_PINID='VCC';
NODE_NAME     C7W1 1
 '@BASEBOARD_FAB2_LIB.BASEBOARD_FAB2(SCH_1):PAGE166_I36@DEV_DISCRETE.CAP_A(CHIPS)':
 'A': CDS_PINID='A';
NODE_NAME     R7W3 1
 '@BASEBOARD_FAB2_LIB.BASEBOARD_FAB2(SCH_1):PAGE166_I46@MSTR_DISCRETE.RES(CHIPS)':
 'A': CDS_PINID='A';
NODE_NAME     R8W7 1
 '@BASEBOARD_FAB2_LIB.BASEBOARD_FAB2(SCH_1):PAGE138_I202@MSTR_DISCRETE.RES(CHIPS)':
 'A': CDS_PINID='A';
NODE_NAME     R8W6 1
 '@BASEBOARD_FAB2_LIB.BASEBOARD_FAB2(SCH_1):PAGE138_I205@MSTR_DISCRETE.RES(CHIPS)':
 'A': CDS_PINID='A';
NODE_NAME     R8C15 1
 '@BASEBOARD_FAB2_LIB.BASEBOARD_FAB2(SCH_1):PAGE159_I235@MSTR_DISCRETE.RES(CHIPS)':
 'A': CDS_PINID='A';
NODE_NAME     R8C16 1
 '@BASEBOARD_FAB2_LIB.BASEBOARD_FAB2(SCH_1):PAGE159_I237@MSTR_DISCRETE.RES(CHIPS)':
 'A': CDS_PINID='A';
NODE_NAME     R8W8 1
 '@BASEBOARD_FAB2_LIB.BASEBOARD_FAB2(SCH_1):PAGE235_I249@MSTR_DISCRETE.RES(CHIPS)':
 'A': CDS_PINID='A';
NODE_NAME     R8W9 1
 '@BASEBOARD_FAB2_LIB.BASEBOARD_FAB2(SCH_1):PAGE89_I49@MSTR_DISCRETE.RES(CHIPS)':
 'A': CDS_PINID='A';
NODE_NAME     R2N17 1
 '@BASEBOARD_FAB2_LIB.BASEBOARD_FAB2(SCH_1):PAGE164_I46@MSTR_DISCRETE.RES(CHIPS)':
 'A': CDS_PINID='A';
NODE_NAME     R1U24 1
 '@BASEBOARD_FAB2_LIB.BASEBOARD_FAB2(SCH_1):PAGE164_I47@MSTR_DISCRETE.RES(CHIPS)':
 'A': CDS_PINID='A';
NODE_NAME     R2L25 1
 '@BASEBOARD_FAB2_LIB.BASEBOARD_FAB2(SCH_1):PAGE235_I252@MSTR_DISCRETE.RES(CHIPS)':
 'A': CDS_PINID='A';
NODE_NAME     R2L26 1
 '@BASEBOARD_FAB2_LIB.BASEBOARD_FAB2(SCH_1):PAGE235_I253@MSTR_DISCRETE.RES(CHIPS)':
 'A': CDS_PINID='A';
NODE_NAME     R2P8 1
 '@BASEBOARD_FAB2_LIB.BASEBOARD_FAB2(SCH_1):PAGE170_I75@MSTR_DISCRETE.RES(CHIPS)':
 'A': CDS_PINID='A';
NODE_NAME     R25W156 1
 '@BASEBOARD_FAB2_LIB.BASEBOARD_FAB2(SCH_1):PAGE150_I240@MSTR_DISCRETE.RES(CHIPS)':
 'A': CDS_PINID='A';
NODE_NAME     R6W1 1
 '@BASEBOARD_FAB2_LIB.BASEBOARD_FAB2(SCH_1):PAGE137_I149@MSTR_DISCRETE.RES(CHIPS)':
 'A': CDS_PINID='A';
NODE_NAME     R6W30 1
 '@BASEBOARD_FAB2_LIB.BASEBOARD_FAB2(SCH_1):PAGE176_I147@MSTR_DISCRETE.RES(CHIPS)':
 'A': CDS_PINID='A';
NODE_NAME     R6W39 2
 '@BASEBOARD_FAB2_LIB.BASEBOARD_FAB2(SCH_1):PAGE176_I158@MSTR_DISCRETE.RES(CHIPS)':
 'B': CDS_PINID='B';
NODE_NAME     U1W3 1
 '@BASEBOARD_FAB2_LIB.BASEBOARD_FAB2(SCH_1):PAGE176_I162@MSTR_DIGITAL.PCA9617(CHIPS)':
 'VCCA': CDS_PINID='VCCA';
NODE_NAME     U1W3 8
 '@BASEBOARD_FAB2_LIB.BASEBOARD_FAB2(SCH_1):PAGE176_I162@MSTR_DIGITAL.PCA9617(CHIPS)':
 'VCCB': CDS_PINID='VCCB';
NODE_NAME     C1W18 1
 '@BASEBOARD_FAB2_LIB.BASEBOARD_FAB2(SCH_1):PAGE176_I163@DEV_DISCRETE.CAP_A(CHIPS)':
 'A': CDS_PINID='A';
NODE_NAME     C1W19 1
 '@BASEBOARD_FAB2_LIB.BASEBOARD_FAB2(SCH_1):PAGE176_I166@DEV_DISCRETE.CAP_A(CHIPS)':
 'A': CDS_PINID='A';
NODE_NAME     R1W36 1
 '@BASEBOARD_FAB2_LIB.BASEBOARD_FAB2(SCH_1):PAGE176_I172@MSTR_DISCRETE.RES(CHIPS)':
 'A': CDS_PINID='A';
NODE_NAME     R1W37 1
 '@BASEBOARD_FAB2_LIB.BASEBOARD_FAB2(SCH_1):PAGE176_I173@MSTR_DISCRETE.RES(CHIPS)':
 'A': CDS_PINID='A';
NODE_NAME     R8E36 1
 '@BASEBOARD_FAB2_LIB.BASEBOARD_FAB2(SCH_1):PAGE142_I34@W_HDL.2K15R2F-1-GP(CHIPS)':
 '1': CDS_PINID='\1\';
NODE_NAME     R8E30 1
 '@BASEBOARD_FAB2_LIB.BASEBOARD_FAB2(SCH_1):PAGE142_I35@W_HDL.2K15R2F-1-GP(CHIPS)':
 '1': CDS_PINID='\1\';
NODE_NAME     R6W40 1
 '@BASEBOARD_FAB2_LIB.BASEBOARD_FAB2(SCH_1):PAGE155_I201@MSTR_DISCRETE.RES(CHIPS)':
 'A': CDS_PINID='A';
NODE_NAME     R1T6 1
 '@BASEBOARD_FAB2_LIB.BASEBOARD_FAB2(SCH_1):PAGE164_I51@MSTR_DISCRETE.RES(CHIPS)':
 'A': CDS_PINID='A';
NODE_NAME     R6W4 1
 '@BASEBOARD_FAB2_LIB.BASEBOARD_FAB2(SCH_1):PAGE247_I159@MSTR_DISCRETE.RES(CHIPS)':
 'A': CDS_PINID='A';
NODE_NAME     R6W5 1
 '@BASEBOARD_FAB2_LIB.BASEBOARD_FAB2(SCH_1):PAGE247_I160@MSTR_DISCRETE.RES(CHIPS)':
 'A': CDS_PINID='A';
NODE_NAME     R6W6 1
 '@BASEBOARD_FAB2_LIB.BASEBOARD_FAB2(SCH_1):PAGE247_I161@MSTR_DISCRETE.RES(CHIPS)':
 'A': CDS_PINID='A';
NODE_NAME     R10W7 1
 '@BASEBOARD_FAB2_LIB.BASEBOARD_FAB2(SCH_1):PAGE251_I31@MSTR_DISCRETE.RES(CHIPS)':
 'A': CDS_PINID='A';
NODE_NAME     R6W35 1
 '@BASEBOARD_FAB2_LIB.BASEBOARD_FAB2(SCH_1):PAGE247_I165@MSTR_DISCRETE.RES(CHIPS)':
 'A': CDS_PINID='A';
NODE_NAME     U32W1 8
 '@BASEBOARD_FAB2_LIB.BASEBOARD_FAB2(SCH_1):PAGE185_I191@W_HDL.TCA9517DGKR-GP(CHIPS)':
 'VCCB': CDS_PINID='VCCB';
NODE_NAME     C32W2 1
 '@BASEBOARD_FAB2_LIB.BASEBOARD_FAB2(SCH_1):PAGE185_I193@DEV_DISCRETE.CAP_A(CHIPS)':
 'A': CDS_PINID='A';
NODE_NAME     C32W4 1
 '@BASEBOARD_FAB2_LIB.BASEBOARD_FAB2(SCH_1):PAGE185_I196@DEV_DISCRETE.CAP_A(CHIPS)':
 'A': CDS_PINID='A';
NODE_NAME     U32W2 8
 '@BASEBOARD_FAB2_LIB.BASEBOARD_FAB2(SCH_1):PAGE185_I204@W_HDL.TCA9517DGKR-GP(CHIPS)':
 'VCCB': CDS_PINID='VCCB';
NODE_NAME     R3W6 1
 '@BASEBOARD_FAB2_LIB.BASEBOARD_FAB2(SCH_1):PAGE249_I48@MSTR_DISCRETE.RES(CHIPS)':
 'A': CDS_PINID='A';
NODE_NAME     R3W5 1
 '@BASEBOARD_FAB2_LIB.BASEBOARD_FAB2(SCH_1):PAGE249_I58@MSTR_DISCRETE.RES(CHIPS)':
 'A': CDS_PINID='A';
NODE_NAME     C6W14 1
 '@BASEBOARD_FAB2_LIB.BASEBOARD_FAB2(SCH_1):PAGE164_I66@DEV_DISCRETE.CAP_A(CHIPS)':
 'A': CDS_PINID='A';
NODE_NAME     R6W44 1
 '@BASEBOARD_FAB2_LIB.BASEBOARD_FAB2(SCH_1):PAGE164_I78@MSTR_DISCRETE.RES(CHIPS)':
 'A': CDS_PINID='A';
NODE_NAME     R6W41 1
 '@BASEBOARD_FAB2_LIB.BASEBOARD_FAB2(SCH_1):PAGE164_I87@MSTR_DISCRETE.RES(CHIPS)':
 'A': CDS_PINID='A';
NODE_NAME     R25W174 1
 '@BASEBOARD_FAB2_LIB.BASEBOARD_FAB2(SCH_1):PAGE269_I4@MSTR_DISCRETE.RES(CHIPS)':
 'A': CDS_PINID='A';
NODE_NAME     R25W177 1
 '@BASEBOARD_FAB2_LIB.BASEBOARD_FAB2(SCH_1):PAGE269_I18@MSTR_DISCRETE.RES(CHIPS)':
 'A': CDS_PINID='A';
NODE_NAME     R25W178 1
 '@BASEBOARD_FAB2_LIB.BASEBOARD_FAB2(SCH_1):PAGE269_I19@MSTR_DISCRETE.RES(CHIPS)':
 'A': CDS_PINID='A';
NODE_NAME     R25W160 1
 '@BASEBOARD_FAB2_LIB.BASEBOARD_FAB2(SCH_1):PAGE269_I20@MSTR_DISCRETE.RES(CHIPS)':
 'A': CDS_PINID='A';
NODE_NAME     R25W161 1
 '@BASEBOARD_FAB2_LIB.BASEBOARD_FAB2(SCH_1):PAGE269_I21@MSTR_DISCRETE.RES(CHIPS)':
 'A': CDS_PINID='A';
NODE_NAME     R25W158 1
 '@BASEBOARD_FAB2_LIB.BASEBOARD_FAB2(SCH_1):PAGE269_I22@MSTR_DISCRETE.RES(CHIPS)':
 'A': CDS_PINID='A';
NODE_NAME     C25W91 1
 '@BASEBOARD_FAB2_LIB.BASEBOARD_FAB2(SCH_1):PAGE269_I26@DEV_DISCRETE.CAP_A(CHIPS)':
 'A': CDS_PINID='A';
NODE_NAME     C25W94 1
 '@BASEBOARD_FAB2_LIB.BASEBOARD_FAB2(SCH_1):PAGE269_I32@MSTR_DISCRETE.CAP(CHIPS)':
 'A': CDS_PINID='A';
NODE_NAME     U25W10 14
 '@BASEBOARD_FAB2_LIB.BASEBOARD_FAB2(SCH_1):PAGE269_I49@MSTR_DIGITAL.GTL2014(CHIPS)':
 'VCC': CDS_PINID='VCC';
NODE_NAME     R25W180 1
 '@BASEBOARD_FAB2_LIB.BASEBOARD_FAB2(SCH_1):PAGE268_I2@MSTR_DISCRETE.RES(CHIPS)':
 'A': CDS_PINID='A';
NODE_NAME     C25W97 1
 '@BASEBOARD_FAB2_LIB.BASEBOARD_FAB2(SCH_1):PAGE268_I4@DEV_DISCRETE.CAP_A(CHIPS)':
 'A': CDS_PINID='A';
NODE_NAME     R25W179 1
 '@BASEBOARD_FAB2_LIB.BASEBOARD_FAB2(SCH_1):PAGE268_I7@MSTR_DISCRETE.RES(CHIPS)':
 'A': CDS_PINID='A';
NODE_NAME     C25W96 1
 '@BASEBOARD_FAB2_LIB.BASEBOARD_FAB2(SCH_1):PAGE268_I9@DEV_DISCRETE.CAP_A(CHIPS)':
 'A': CDS_PINID='A';
NODE_NAME     C25W92 1
 '@BASEBOARD_FAB2_LIB.BASEBOARD_FAB2(SCH_1):PAGE268_I23@MSTR_DISCRETE.CAP(CHIPS)':
 'A': CDS_PINID='A';
NODE_NAME     U25W11 14
 '@BASEBOARD_FAB2_LIB.BASEBOARD_FAB2(SCH_1):PAGE268_I33@MSTR_DIGITAL.GTL2014(CHIPS)':
 'VCC': CDS_PINID='VCC';
NODE_NAME     U25W13 2
 '@BASEBOARD_FAB2_LIB.BASEBOARD_FAB2(SCH_1):PAGE269_I53@W_HDL.MAX4564EKA-GP(CHIPS)':
 'V+': CDS_PINID='\v+\';
NODE_NAME     C25W95 1
 '@BASEBOARD_FAB2_LIB.BASEBOARD_FAB2(SCH_1):PAGE269_I56@DEV_DISCRETE.CAP_A(CHIPS)':
 'A': CDS_PINID='A';
NODE_NAME     R6W42 1
 '@BASEBOARD_FAB2_LIB.BASEBOARD_FAB2(SCH_1):PAGE164_I95@MSTR_DISCRETE.RES(CHIPS)':
 'A': CDS_PINID='A';
NODE_NAME     R6W43 1
 '@BASEBOARD_FAB2_LIB.BASEBOARD_FAB2(SCH_1):PAGE164_I96@MSTR_DISCRETE.RES(CHIPS)':
 'A': CDS_PINID='A';
NODE_NAME     R25W183 1
 '@BASEBOARD_FAB2_LIB.BASEBOARD_FAB2(SCH_1):PAGE268_I36@W_HDL.374R2F-1-GP(CHIPS)':
 '1': CDS_PINID='\1\';
NODE_NAME     R6W16 1
 '@BASEBOARD_FAB2_LIB.BASEBOARD_FAB2(SCH_1):PAGE168_I46@MSTR_DISCRETE.RES(CHIPS)':
 'A': CDS_PINID='A';
NODE_NAME     U6W11 16
 '@BASEBOARD_FAB2_LIB.BASEBOARD_FAB2(SCH_1):PAGE164_I97@W_HDL.PCA9554PWR-GP(CHIPS)':
 'VCC': CDS_PINID='VCC';
NODE_NAME     C1L119 1
 '@BASEBOARD_FAB2_LIB.BASEBOARD_FAB2(SCH_1):PAGE189_I69@MSTR_DISCRETE.CAP(CHIPS)':
 'A': CDS_PINID='A';
NODE_NAME     R8E3 1
 '@BASEBOARD_FAB2_LIB.BASEBOARD_FAB2(SCH_1):PAGE133_I371@MSTR_DISCRETE.RES(CHIPS)':
 'A': CDS_PINID='A';
NODE_NAME     R7F36 1
 '@BASEBOARD_FAB2_LIB.BASEBOARD_FAB2(SCH_1):PAGE215_I75@MSTR_DISCRETE.RES(CHIPS)':
 'A': CDS_PINID='A';
NODE_NAME     R7A9 1
 '@BASEBOARD_FAB2_LIB.BASEBOARD_FAB2(SCH_1):PAGE218_I76@MSTR_DISCRETE.RES(CHIPS)':
 'A': CDS_PINID='A';
NODE_NAME     R1G6 1
 '@BASEBOARD_FAB2_LIB.BASEBOARD_FAB2(SCH_1):PAGE223_I76@MSTR_DISCRETE.RES(CHIPS)':
 'A': CDS_PINID='A';
NODE_NAME     R1B13 1
 '@BASEBOARD_FAB2_LIB.BASEBOARD_FAB2(SCH_1):PAGE226_I75@MSTR_DISCRETE.RES(CHIPS)':
 'A': CDS_PINID='A';
NODE_NAME     C25W98 1
 '@BASEBOARD_FAB2_LIB.BASEBOARD_FAB2(SCH_1):PAGE268_I40@MSTR_DISCRETE.CAP(CHIPS)':
 'A': CDS_PINID='A';
NODE_NAME     R25W185 1
 '@BASEBOARD_FAB2_LIB.BASEBOARD_FAB2(SCH_1):PAGE268_I54@MSTR_DISCRETE.RES(CHIPS)':
 'A': CDS_PINID='A';
NODE_NAME     C25W99 1
 '@BASEBOARD_FAB2_LIB.BASEBOARD_FAB2(SCH_1):PAGE269_I62@DEV_DISCRETE.CAP_A(CHIPS)':
 'A': CDS_PINID='A';
NODE_NAME     C25W100 1
 '@BASEBOARD_FAB2_LIB.BASEBOARD_FAB2(SCH_1):PAGE268_I60@DEV_DISCRETE.CAP_A(CHIPS)':
 'A': CDS_PINID='A';
NODE_NAME     R9W33 1
 '@BASEBOARD_FAB2_LIB.BASEBOARD_FAB2(SCH_1):PAGE158_I153@MSTR_DISCRETE.RES(CHIPS)':
 'A': CDS_PINID='A';
NODE_NAME     R9W34 1
 '@BASEBOARD_FAB2_LIB.BASEBOARD_FAB2(SCH_1):PAGE158_I154@MSTR_DISCRETE.RES(CHIPS)':
 'A': CDS_PINID='A';
NODE_NAME     R9W35 1
 '@BASEBOARD_FAB2_LIB.BASEBOARD_FAB2(SCH_1):PAGE158_I155@MSTR_DISCRETE.RES(CHIPS)':
 'A': CDS_PINID='A';
NODE_NAME     C9W14 1
 '@BASEBOARD_FAB2_LIB.BASEBOARD_FAB2(SCH_1):PAGE238_I46@MSTR_DISCRETE.CAP(CHIPS)':
 'A': CDS_PINID='A';
NODE_NAME     C9W17 1
 '@BASEBOARD_FAB2_LIB.BASEBOARD_FAB2(SCH_1):PAGE239_I104@MSTR_DISCRETE.CAP(CHIPS)':
 'A': CDS_PINID='A';
NODE_NAME     R9W36 1
 '@BASEBOARD_FAB2_LIB.BASEBOARD_FAB2(SCH_1):PAGE139_I252@MSTR_DISCRETE.RES(CHIPS)':
 'A': CDS_PINID='A';
NODE_NAME     R6W50 1
 '@BASEBOARD_FAB2_LIB.BASEBOARD_FAB2(SCH_1):PAGE176_I178@MSTR_DISCRETE.RES(CHIPS)':
 'A': CDS_PINID='A';
NODE_NAME     R1W40 1
 '@BASEBOARD_FAB2_LIB.BASEBOARD_FAB2(SCH_1):PAGE188_I128@MSTR_DISCRETE.RES(CHIPS)':
 'A': CDS_PINID='A';
NODE_NAME     R1W42 1
 '@BASEBOARD_FAB2_LIB.BASEBOARD_FAB2(SCH_1):PAGE188_I131@MSTR_DISCRETE.RES(CHIPS)':
 'A': CDS_PINID='A';
NODE_NAME     R1W43 1
 '@BASEBOARD_FAB2_LIB.BASEBOARD_FAB2(SCH_1):PAGE188_I132@MSTR_DISCRETE.RES(CHIPS)':
 'A': CDS_PINID='A';
NODE_NAME     R1W44 1
 '@BASEBOARD_FAB2_LIB.BASEBOARD_FAB2(SCH_1):PAGE188_I133@MSTR_DISCRETE.RES(CHIPS)':
 'A': CDS_PINID='A';
NODE_NAME     R1W45 1
 '@BASEBOARD_FAB2_LIB.BASEBOARD_FAB2(SCH_1):PAGE188_I134@MSTR_DISCRETE.RES(CHIPS)':
 'A': CDS_PINID='A';
NODE_NAME     C25W101 1
 '@BASEBOARD_FAB2_LIB.BASEBOARD_FAB2(SCH_1):PAGE269_I79@DEV_DISCRETE.CAP_A(CHIPS)':
 'A': CDS_PINID='A';
NODE_NAME     U8W2 5
 '@BASEBOARD_FAB2_LIB.BASEBOARD_FAB2(SCH_1):PAGE245_I66@MSTR_ANALOG.NC7SB3157(CHIPS)':
 'VCC': CDS_PINID='VCC';
NODE_NAME     C8W6 1
 '@BASEBOARD_FAB2_LIB.BASEBOARD_FAB2(SCH_1):PAGE245_I71@DEV_DISCRETE.CAP_A(CHIPS)':
 'A': CDS_PINID='A';
NODE_NAME     C8W5 1
 '@BASEBOARD_FAB2_LIB.BASEBOARD_FAB2(SCH_1):PAGE245_I74@DEV_DISCRETE.CAP_A(CHIPS)':
 'A': CDS_PINID='A';
NODE_NAME     R8W15 1
 '@BASEBOARD_FAB2_LIB.BASEBOARD_FAB2(SCH_1):PAGE245_I78@MSTR_DISCRETE.RES(CHIPS)':
 'A': CDS_PINID='A';
NODE_NAME     R7W19 1
 '@BASEBOARD_FAB2_LIB.BASEBOARD_FAB2(SCH_1):PAGE118_I180@MSTR_DISCRETE.RES(CHIPS)':
 'A': CDS_PINID='A';
NODE_NAME     R7W20 1
 '@BASEBOARD_FAB2_LIB.BASEBOARD_FAB2(SCH_1):PAGE120_I278@MSTR_DISCRETE.RES(CHIPS)':
 'A': CDS_PINID='A';
NODE_NAME     R1T4 1
 '@BASEBOARD_FAB2_LIB.BASEBOARD_FAB2(SCH_1):PAGE164_I100@MSTR_DISCRETE.RES(CHIPS)':
 'A': CDS_PINID='A';
NODE_NAME     R25W101 1
 '@BASEBOARD_FAB2_LIB.BASEBOARD_FAB2(SCH_1):PAGE150_I241@MSTR_DISCRETE.RES(CHIPS)':
 'A': CDS_PINID='A';
NODE_NAME     U6W12 5
 '@BASEBOARD_FAB2_LIB.BASEBOARD_FAB2(SCH_1):PAGE176_I182@MSTR_ANALOG.NC7SB3157(CHIPS)':
 'VCC': CDS_PINID='VCC';
NODE_NAME     R7W22 1
 '@BASEBOARD_FAB2_LIB.BASEBOARD_FAB2(SCH_1):PAGE119_I230@MSTR_DISCRETE.RES(CHIPS)':
 'A': CDS_PINID='A';
NODE_NAME     R7W21 1
 '@BASEBOARD_FAB2_LIB.BASEBOARD_FAB2(SCH_1):PAGE118_I183@MSTR_DISCRETE.RES(CHIPS)':
 'A': CDS_PINID='A';
NODE_NAME     R25W115 1
 '@BASEBOARD_FAB2_LIB.BASEBOARD_FAB2(SCH_1):PAGE150_I242@MSTR_DISCRETE.RES(CHIPS)':
 'A': CDS_PINID='A';
NET_NAME
'P3V3_STBY_BMC_ADCVREFN'
 '@BASEBOARD_FAB2_LIB.BASEBOARD_FAB2(SCH_1):P3V3_STBY_BMC_ADCVREFN':
 C_SIGNAL='@baseboard_fab2_lib.baseboard_fab2(sch_1):p3v3_stby_bmc_adcvrefn';
NODE_NAME     U25W4 H1
 '@BASEBOARD_FAB2_LIB.BASEBOARD_FAB2(SCH_1):PAGE147_I106@W_HDL.AST2520A1-GP-GP(CHIPS)':
 'ADCVREFN': CDS_PINID='ADCVREFN';
NODE_NAME     C25W9 2
 '@BASEBOARD_FAB2_LIB.BASEBOARD_FAB2(SCH_1):PAGE147_I160@DEV_DISCRETE.CAP_A(CHIPS)':
 'B': CDS_PINID='B';
NODE_NAME     C25W8 1
 '@BASEBOARD_FAB2_LIB.BASEBOARD_FAB2(SCH_1):PAGE147_I162@DEV_DISCRETE.CAP_A(CHIPS)':
 'A': CDS_PINID='A';
NET_NAME
'P3V3_STBY_BMC_ADCVREFP'
 '@BASEBOARD_FAB2_LIB.BASEBOARD_FAB2(SCH_1):P3V3_STBY_BMC_ADCVREFP':
 C_SIGNAL='@baseboard_fab2_lib.baseboard_fab2(sch_1):p3v3_stby_bmc_adcvrefp';
NODE_NAME     U25W4 H2
 '@BASEBOARD_FAB2_LIB.BASEBOARD_FAB2(SCH_1):PAGE147_I106@W_HDL.AST2520A1-GP-GP(CHIPS)':
 'ADCVREFP': CDS_PINID='ADCVREFP';
NODE_NAME     C25W9 1
 '@BASEBOARD_FAB2_LIB.BASEBOARD_FAB2(SCH_1):PAGE147_I160@DEV_DISCRETE.CAP_A(CHIPS)':
 'A': CDS_PINID='A';
NODE_NAME     C25W7 1
 '@BASEBOARD_FAB2_LIB.BASEBOARD_FAB2(SCH_1):PAGE147_I161@DEV_DISCRETE.CAP_A(CHIPS)':
 'A': CDS_PINID='A';
NET_NAME
'P3V3_STBY_MNG'
 '@BASEBOARD_FAB2_LIB.BASEBOARD_FAB2(SCH_1):P3V3_STBY_MNG':
 C_SIGNAL='@baseboard_fab2_lib.baseboard_fab2(sch_1):p3v3_stby_mng';
NODE_NAME     EU8F2 12
 '@BASEBOARD_FAB2_LIB.BASEBOARD_FAB2(SCH_1):PAGE101_I34@MSTR_CLOCK.ICS9FGP204(CHIPS)':
 'VDD32K': CDS_PINID='VDD32K';
NODE_NAME     EU8F2 23
 '@BASEBOARD_FAB2_LIB.BASEBOARD_FAB2(SCH_1):PAGE101_I34@MSTR_CLOCK.ICS9FGP204(CHIPS)':
 'VDD33': CDS_PINID='VDD33';
NODE_NAME     EU8F2 2
 '@BASEBOARD_FAB2_LIB.BASEBOARD_FAB2(SCH_1):PAGE101_I34@MSTR_CLOCK.ICS9FGP204(CHIPS)':
 'VDD96': CDS_PINID='VDD96';
NODE_NAME     EU8F2 15
 '@BASEBOARD_FAB2_LIB.BASEBOARD_FAB2(SCH_1):PAGE101_I34@MSTR_CLOCK.ICS9FGP204(CHIPS)':
 'VDDREF': CDS_PINID='VDDREF';
NODE_NAME     R2T23 1
 '@BASEBOARD_FAB2_LIB.BASEBOARD_FAB2(SCH_1):PAGE101_I94@MSTR_DISCRETE.RES(CHIPS)':
 'A': CDS_PINID='A';
NODE_NAME     R2T52 1
 '@BASEBOARD_FAB2_LIB.BASEBOARD_FAB2(SCH_1):PAGE101_I95@MSTR_DISCRETE.RES(CHIPS)':
 'A': CDS_PINID='A';
NODE_NAME     R2T21 1
 '@BASEBOARD_FAB2_LIB.BASEBOARD_FAB2(SCH_1):PAGE101_I105@MSTR_DISCRETE.RES(CHIPS)':
 'A': CDS_PINID='A';
NODE_NAME     C2T34 1
 '@BASEBOARD_FAB2_LIB.BASEBOARD_FAB2(SCH_1):PAGE101_I109@DEV_DISCRETE.CAP_A(CHIPS)':
 'A': CDS_PINID='A';
NODE_NAME     C2T30 1
 '@BASEBOARD_FAB2_LIB.BASEBOARD_FAB2(SCH_1):PAGE101_I110@DEV_DISCRETE.CAP_A(CHIPS)':
 'A': CDS_PINID='A';
NODE_NAME     C2T25 1
 '@BASEBOARD_FAB2_LIB.BASEBOARD_FAB2(SCH_1):PAGE101_I111@DEV_DISCRETE.CAP_A(CHIPS)':
 'A': CDS_PINID='A';
NODE_NAME     C2T17 1
 '@BASEBOARD_FAB2_LIB.BASEBOARD_FAB2(SCH_1):PAGE101_I112@DEV_DISCRETE.CAP_A(CHIPS)':
 'A': CDS_PINID='A';
NODE_NAME     C2T22 1
 '@BASEBOARD_FAB2_LIB.BASEBOARD_FAB2(SCH_1):PAGE101_I113@MSTR_DISCRETE.CAP(CHIPS)':
 'A': CDS_PINID='A';
NODE_NAME     FB2T2 2
 '@BASEBOARD_FAB2_LIB.BASEBOARD_FAB2(SCH_1):PAGE101_I114@MSTR_DISCRETE.FERRITE(CHIPS)':
 'B': CDS_PINID='B';
NET_NAME
'P3V3_STBY_MNG_CPU'
 '@BASEBOARD_FAB2_LIB.BASEBOARD_FAB2(SCH_1):P3V3_STBY_MNG_CPU':
 C_SIGNAL='@baseboard_fab2_lib.baseboard_fab2(sch_1):p3v3_stby_mng_cpu';
NODE_NAME     EU8F2 9
 '@BASEBOARD_FAB2_LIB.BASEBOARD_FAB2(SCH_1):PAGE101_I34@MSTR_CLOCK.ICS9FGP204(CHIPS)':
 'VDDCPU': CDS_PINID='VDDCPU';
NODE_NAME     C2T18 1
 '@BASEBOARD_FAB2_LIB.BASEBOARD_FAB2(SCH_1):PAGE101_I104@DEV_DISCRETE.CAP_A(CHIPS)':
 'A': CDS_PINID='A';
NODE_NAME     R2T21 2
 '@BASEBOARD_FAB2_LIB.BASEBOARD_FAB2(SCH_1):PAGE101_I105@MSTR_DISCRETE.RES(CHIPS)':
 'B': CDS_PINID='B';
NODE_NAME     C2T19 1
 '@BASEBOARD_FAB2_LIB.BASEBOARD_FAB2(SCH_1):PAGE101_I106@DEV_DISCRETE.CAP_A(CHIPS)':
 'A': CDS_PINID='A';
NET_NAME
'P3V3_STBY_MNG_RGMII'
 '@BASEBOARD_FAB2_LIB.BASEBOARD_FAB2(SCH_1):P3V3_STBY_MNG_RGMII':
 C_SIGNAL='@baseboard_fab2_lib.baseboard_fab2(sch_1):p3v3_stby_mng_rgmii';
NODE_NAME     EU8F2 34
 '@BASEBOARD_FAB2_LIB.BASEBOARD_FAB2(SCH_1):PAGE101_I34@MSTR_CLOCK.ICS9FGP204(CHIPS)':
 'VDD_RGMII': CDS_PINID='VDD_RGMII';
NODE_NAME     C2T31 1
 '@BASEBOARD_FAB2_LIB.BASEBOARD_FAB2(SCH_1):PAGE101_I89@DEV_DISCRETE.CAP_A(CHIPS)':
 'A': CDS_PINID='A';
NODE_NAME     C2T27 1
 '@BASEBOARD_FAB2_LIB.BASEBOARD_FAB2(SCH_1):PAGE101_I90@DEV_DISCRETE.CAP_A(CHIPS)':
 'A': CDS_PINID='A';
NODE_NAME     R2T23 2
 '@BASEBOARD_FAB2_LIB.BASEBOARD_FAB2(SCH_1):PAGE101_I94@MSTR_DISCRETE.RES(CHIPS)':
 'B': CDS_PINID='B';
NET_NAME
'P3V3_STBY_MNG_RMII'
 '@BASEBOARD_FAB2_LIB.BASEBOARD_FAB2(SCH_1):P3V3_STBY_MNG_RMII':
 C_SIGNAL='@baseboard_fab2_lib.baseboard_fab2(sch_1):p3v3_stby_mng_rmii';
NODE_NAME     EU8F2 26
 '@BASEBOARD_FAB2_LIB.BASEBOARD_FAB2(SCH_1):PAGE101_I34@MSTR_CLOCK.ICS9FGP204(CHIPS)':
 'VDDRMII'<0>: CDS_PINID='VDDRMII(0)';
NODE_NAME     EU8F2 31
 '@BASEBOARD_FAB2_LIB.BASEBOARD_FAB2(SCH_1):PAGE101_I34@MSTR_CLOCK.ICS9FGP204(CHIPS)':
 'VDDRMII'<1>: CDS_PINID='VDDRMII(1)';
NODE_NAME     R2T52 2
 '@BASEBOARD_FAB2_LIB.BASEBOARD_FAB2(SCH_1):PAGE101_I95@MSTR_DISCRETE.RES(CHIPS)':
 'B': CDS_PINID='B';
NODE_NAME     C2T38 1
 '@BASEBOARD_FAB2_LIB.BASEBOARD_FAB2(SCH_1):PAGE101_I97@DEV_DISCRETE.CAP_A(CHIPS)':
 'A': CDS_PINID='A';
NODE_NAME     C2T37 1
 '@BASEBOARD_FAB2_LIB.BASEBOARD_FAB2(SCH_1):PAGE101_I99@DEV_DISCRETE.CAP_A(CHIPS)':
 'A': CDS_PINID='A';
NODE_NAME     C1W17 1
 '@BASEBOARD_FAB2_LIB.BASEBOARD_FAB2(SCH_1):PAGE101_I139@MSTR_DISCRETE.CAP(CHIPS)':
 'A': CDS_PINID='A';
NET_NAME
'P3V3_STBY_P1V5_LAN_I210'
 '@BASEBOARD_FAB2_LIB.BASEBOARD_FAB2(SCH_1):P3V3_STBY_P1V5_LAN_I210':
 C_SIGNAL='@baseboard_fab2_lib.baseboard_fab2(sch_1):p3v3_stby_p1v5_lan_i210';
NODE_NAME     EU9E1 51
 '@BASEBOARD_FAB2_LIB.BASEBOARD_FAB2(SCH_1):PAGE139_I72@MSTR_INTEL.SPRINGVILLE(CHIPS)':
 'VDD3P3'<1>: CDS_PINID='VDD3P3(1)';
NODE_NAME     R1T34 2
 '@BASEBOARD_FAB2_LIB.BASEBOARD_FAB2(SCH_1):PAGE139_I239@MSTR_DISCRETE.RES(CHIPS)':
 'B': CDS_PINID='B';
NODE_NAME     R1T33 2
 '@BASEBOARD_FAB2_LIB.BASEBOARD_FAB2(SCH_1):PAGE139_I240@MSTR_DISCRETE.RES(CHIPS)':
 'B': CDS_PINID='B';
NET_NAME
'P3V3_STBY_PLD_D'
 '@BASEBOARD_FAB2_LIB.BASEBOARD_FAB2(SCH_1):P3V3_STBY_PLD_D':
 C_SIGNAL='@baseboard_fab2_lib.baseboard_fab2(sch_1):p3v3_stby_pld_d';
NODE_NAME     J7G2 1
 '@BASEBOARD_FAB2_LIB.BASEBOARD_FAB2(SCH_1):PAGE189_I47@MSTR_CONN.CONN8_C77962004(CHIPS)':
 'IO1': CDS_PINID='IO1';
NODE_NAME     CR3U1 1
 '@BASEBOARD_FAB2_LIB.BASEBOARD_FAB2(SCH_1):PAGE189_I49@MSTR_DISCRETE.DIODE(CHIPS)':
 'C': CDS_PINID='C';
NET_NAME
'P3V3_SWITCH_G'
 '@BASEBOARD_FAB2_LIB.BASEBOARD_FAB2(SCH_1):P3V3_SWITCH_G':
 C_SIGNAL='@baseboard_fab2_lib.baseboard_fab2(sch_1):p3v3_switch_g';
NODE_NAME     EU2T1 7
 '@BASEBOARD_FAB2_LIB.BASEBOARD_FAB2(SCH_1):PAGE198_I1@MSTR_VREG.SLG55021(CHIPS)':
 'G': CDS_PINID='G';
NODE_NAME     Q8G1 4
 '@BASEBOARD_FAB2_LIB.BASEBOARD_FAB2(SCH_1):PAGE198_I85@MSTR_DISCRETE.MOSFET_N(CHIPS)':
 'GATE': CDS_PINID='GATE';
NET_NAME
'P3V3_USB2A_ALG'
 '@BASEBOARD_FAB2_LIB.BASEBOARD_FAB2(SCH_1):P3V3_USB2A_ALG':
 C_SIGNAL='@baseboard_fab2_lib.baseboard_fab2(sch_1):p3v3_usb2a_alg';
NODE_NAME     U25W4 C7
 '@BASEBOARD_FAB2_LIB.BASEBOARD_FAB2(SCH_1):PAGE148_I28@W_HDL.AST2520A1-GP-GP(CHIPS)':
 'USB2AV33': CDS_PINID='USB2AV33';
NODE_NAME     C25W70 1
 '@BASEBOARD_FAB2_LIB.BASEBOARD_FAB2(SCH_1):PAGE149_I5@MSTR_DISCRETE.CAP(CHIPS)':
 'A': CDS_PINID='A';
NODE_NAME     R25W120 2
 '@BASEBOARD_FAB2_LIB.BASEBOARD_FAB2(SCH_1):PAGE149_I91@MSTR_DISCRETE.RES(CHIPS)':
 'B': CDS_PINID='B';
NODE_NAME     C25W71 1
 '@BASEBOARD_FAB2_LIB.BASEBOARD_FAB2(SCH_1):PAGE149_I115@MSTR_DISCRETE.CAP(CHIPS)':
 'A': CDS_PINID='A';
NET_NAME
'P3V_BAT_SOURCE'
 '@BASEBOARD_FAB2_LIB.BASEBOARD_FAB2(SCH_1):P3V_BAT_SOURCE':
 C_SIGNAL='@baseboard_fab2_lib.baseboard_fab2(sch_1):p3v_bat_source';
NODE_NAME     R2U43 1
 '@BASEBOARD_FAB2_LIB.BASEBOARD_FAB2(SCH_1):PAGE196_I46@MSTR_DISCRETE.RES(CHIPS)':
 'A': CDS_PINID='A';
NODE_NAME     XBT8G1 1
 '@BASEBOARD_FAB2_LIB.BASEBOARD_FAB2(SCH_1):PAGE196_I51@MSTR_DISCRETE.VERT_BATT_3PIN(CHIPS)':
 'P1': CDS_PINID='P1';
NODE_NAME     XBT8G1 2
 '@BASEBOARD_FAB2_LIB.BASEBOARD_FAB2(SCH_1):PAGE196_I51@MSTR_DISCRETE.VERT_BATT_3PIN(CHIPS)':
 'P2': CDS_PINID='P2';
NET_NAME
'P3V_BAT_SOURCE_R'
 '@BASEBOARD_FAB2_LIB.BASEBOARD_FAB2(SCH_1):P3V_BAT_SOURCE_R':
 C_SIGNAL='@baseboard_fab2_lib.baseboard_fab2(sch_1):p3v_bat_source_r';
NODE_NAME     R1U50 2
 '@BASEBOARD_FAB2_LIB.BASEBOARD_FAB2(SCH_1):PAGE169_I126@MSTR_DISCRETE.RES(CHIPS)':
 'B': CDS_PINID='B';
NODE_NAME     Q9G1 3
 '@BASEBOARD_FAB2_LIB.BASEBOARD_FAB2(SCH_1):PAGE169_I157@MSTR_DISCRETE.FET_N_DUAL(CHIPS)':
 'DRAIN'<0>: CDS_PINID='DRAIN(0)';
NET_NAME
'P5V'
 '@BASEBOARD_FAB2_LIB.BASEBOARD_FAB2(SCH_1):P5V':
 C_SIGNAL='@baseboard_fab2_lib.baseboard_fab2(sch_1):p5v';
NODE_NAME     R1U29 1
 '@BASEBOARD_FAB2_LIB.BASEBOARD_FAB2(SCH_1):PAGE169_I141@MSTR_DISCRETE.RES(CHIPS)':
 'A': CDS_PINID='A';
NODE_NAME     R8D39 1
 '@BASEBOARD_FAB2_LIB.BASEBOARD_FAB2(SCH_1):PAGE196_I114@MSTR_DISCRETE.RES(CHIPS)':
 'A': CDS_PINID='A';
NODE_NAME     EU8B1 6
 '@BASEBOARD_FAB2_LIB.BASEBOARD_FAB2(SCH_1):PAGE198_I13@MSTR_VREG.SLG55021(CHIPS)':
 'S': CDS_PINID='S';
NODE_NAME     C8B6 1
 '@BASEBOARD_FAB2_LIB.BASEBOARD_FAB2(SCH_1):PAGE198_I40@MSTR_DISCRETE.CAP(CHIPS)':
 'A': CDS_PINID='A';
NODE_NAME     C8B7 1
 '@BASEBOARD_FAB2_LIB.BASEBOARD_FAB2(SCH_1):PAGE198_I41@DEV_DISCRETE.CAP_A(CHIPS)':
 'A': CDS_PINID='A';
NODE_NAME     Q8B1 1
 '@BASEBOARD_FAB2_LIB.BASEBOARD_FAB2(SCH_1):PAGE198_I87@MSTR_DISCRETE.MOSFET_N(CHIPS)':
 'SRC': CDS_PINID='SRC';
NODE_NAME     R1W11 1
 '@BASEBOARD_FAB2_LIB.BASEBOARD_FAB2(SCH_1):PAGE176_I133@MSTR_DISCRETE.RES(CHIPS)':
 'A': CDS_PINID='A';
NODE_NAME     D25W8 A
 '@BASEBOARD_FAB2_LIB.BASEBOARD_FAB2(SCH_1):PAGE255_I128@W_HDL.RB551V30-GP(CHIPS)':
 'ANODE': CDS_PINID='ANODE';
NODE_NAME     F8B1 2
 '@BASEBOARD_FAB2_LIB.BASEBOARD_FAB2(SCH_1):PAGE172_I71@W_HDL.FUSE-3A75V-GP(CHIPS)':
 '2': CDS_PINID='\2\';
NET_NAME
'P5V_HDD_SATA'
 '@BASEBOARD_FAB2_LIB.BASEBOARD_FAB2(SCH_1):P5V_HDD_SATA':
 C_SIGNAL='@baseboard_fab2_lib.baseboard_fab2(sch_1):p5v_hdd_sata';
NODE_NAME     C9B1 1
 '@BASEBOARD_FAB2_LIB.BASEBOARD_FAB2(SCH_1):PAGE172_I39@MSTR_DISCRETE.CAP(CHIPS)':
 'A': CDS_PINID='A';
NODE_NAME     J2W1 P1
 '@BASEBOARD_FAB2_LIB.BASEBOARD_FAB2(SCH_1):PAGE172_I67@W_HDL.SKT-SATA7P-6P-165-GP-U1(CHIPS)':
 'P1': CDS_PINID='P1';
NODE_NAME     J2W1 P2
 '@BASEBOARD_FAB2_LIB.BASEBOARD_FAB2(SCH_1):PAGE172_I67@W_HDL.SKT-SATA7P-6P-165-GP-U1(CHIPS)':
 'P2': CDS_PINID='P2';
NODE_NAME     J2W2 P1
 '@BASEBOARD_FAB2_LIB.BASEBOARD_FAB2(SCH_1):PAGE172_I68@W_HDL.SKT-SATA7P-6P-165-GP-U1(CHIPS)':
 'P1': CDS_PINID='P1';
NODE_NAME     J2W2 P2
 '@BASEBOARD_FAB2_LIB.BASEBOARD_FAB2(SCH_1):PAGE172_I68@W_HDL.SKT-SATA7P-6P-165-GP-U1(CHIPS)':
 'P2': CDS_PINID='P2';
NODE_NAME     F8B1 1
 '@BASEBOARD_FAB2_LIB.BASEBOARD_FAB2(SCH_1):PAGE172_I71@W_HDL.FUSE-3A75V-GP(CHIPS)':
 '1': CDS_PINID='\1\';
NET_NAME
'P5V_STBY'
 '@BASEBOARD_FAB2_LIB.BASEBOARD_FAB2(SCH_1):P5V_STBY':
 C_SIGNAL='@baseboard_fab2_lib.baseboard_fab2(sch_1):p5v_stby';
NODE_NAME     Q1L2 6
 '@BASEBOARD_FAB2_LIB.BASEBOARD_FAB2(SCH_1):PAGE155_I188@MSTR_DISCRETE.FET_N_DUAL(CHIPS)':
 'DRAIN'<0>: CDS_PINID='DRAIN(0)';
NODE_NAME     CR1E1 1
 '@BASEBOARD_FAB2_LIB.BASEBOARD_FAB2(SCH_1):PAGE161_I50@MSTR_DISCRETE.DIODE(CHIPS)':
 'C': CDS_PINID='C';
NODE_NAME     R1E12 1
 '@BASEBOARD_FAB2_LIB.BASEBOARD_FAB2(SCH_1):PAGE161_I51@MSTR_DISCRETE.RES(CHIPS)':
 'A': CDS_PINID='A';
NODE_NAME     CR1B1 1
 '@BASEBOARD_FAB2_LIB.BASEBOARD_FAB2(SCH_1):PAGE161_I64@MSTR_DISCRETE.DIODE(CHIPS)':
 'C': CDS_PINID='C';
NODE_NAME     R7F33 1
 '@BASEBOARD_FAB2_LIB.BASEBOARD_FAB2(SCH_1):PAGE161_I65@MSTR_DISCRETE.RES(CHIPS)':
 'A': CDS_PINID='A';
NODE_NAME     R1U47 1
 '@BASEBOARD_FAB2_LIB.BASEBOARD_FAB2(SCH_1):PAGE169_I115@MSTR_DISCRETE.RES(CHIPS)':
 'A': CDS_PINID='A';
NODE_NAME     R1L8 1
 '@BASEBOARD_FAB2_LIB.BASEBOARD_FAB2(SCH_1):PAGE175_I58@MSTR_DISCRETE.RES(CHIPS)':
 'A': CDS_PINID='A';
NODE_NAME     C1L4 1
 '@BASEBOARD_FAB2_LIB.BASEBOARD_FAB2(SCH_1):PAGE175_I64@DEV_DISCRETE.CAP_A(CHIPS)':
 'A': CDS_PINID='A';
NODE_NAME     R1L37 1
 '@BASEBOARD_FAB2_LIB.BASEBOARD_FAB2(SCH_1):PAGE177_I33@MSTR_DISCRETE.RES(CHIPS)':
 'A': CDS_PINID='A';
NODE_NAME     J9B3 3
 '@BASEBOARD_FAB2_LIB.BASEBOARD_FAB2(SCH_1):PAGE186_I336@MSTR_SCONN.SCONN120_A28699018(CHIPS)':
 'IO3': CDS_PINID='IO3';
NODE_NAME     J9B3 5
 '@BASEBOARD_FAB2_LIB.BASEBOARD_FAB2(SCH_1):PAGE186_I336@MSTR_SCONN.SCONN120_A28699018(CHIPS)':
 'IO5': CDS_PINID='IO5';
NODE_NAME     J9B3 7
 '@BASEBOARD_FAB2_LIB.BASEBOARD_FAB2(SCH_1):PAGE186_I336@MSTR_SCONN.SCONN120_A28699018(CHIPS)':
 'IO7': CDS_PINID='IO7';
NODE_NAME     C9B10 1
 '@BASEBOARD_FAB2_LIB.BASEBOARD_FAB2(SCH_1):PAGE186_I345@DEV_DISCRETE.CAP_A(CHIPS)':
 'A': CDS_PINID='A';
NODE_NAME     J4B2 A13
 '@BASEBOARD_FAB2_LIB.BASEBOARD_FAB2(SCH_1):PAGE193_I46@MSTR_SCONN.SCONN120_H61426002(CHIPS)':
 'IOA13': CDS_PINID='IOA13';
NODE_NAME     J4B2 B13
 '@BASEBOARD_FAB2_LIB.BASEBOARD_FAB2(SCH_1):PAGE193_I46@MSTR_SCONN.SCONN120_H61426002(CHIPS)':
 'IOB13': CDS_PINID='IOB13';
NODE_NAME     J4B2 C13
 '@BASEBOARD_FAB2_LIB.BASEBOARD_FAB2(SCH_1):PAGE193_I46@MSTR_SCONN.SCONN120_H61426002(CHIPS)':
 'IOC13': CDS_PINID='IOC13';
NODE_NAME     J6B1 A13
 '@BASEBOARD_FAB2_LIB.BASEBOARD_FAB2(SCH_1):PAGE194_I56@MSTR_SCONN.SCONN120_H61426002(CHIPS)':
 'IOA13': CDS_PINID='IOA13';
NODE_NAME     J6B1 B13
 '@BASEBOARD_FAB2_LIB.BASEBOARD_FAB2(SCH_1):PAGE194_I56@MSTR_SCONN.SCONN120_H61426002(CHIPS)':
 'IOB13': CDS_PINID='IOB13';
NODE_NAME     J6B1 C13
 '@BASEBOARD_FAB2_LIB.BASEBOARD_FAB2(SCH_1):PAGE194_I56@MSTR_SCONN.SCONN120_H61426002(CHIPS)':
 'IOC13': CDS_PINID='IOC13';
NODE_NAME     EU2T1 3
 '@BASEBOARD_FAB2_LIB.BASEBOARD_FAB2(SCH_1):PAGE198_I1@MSTR_VREG.SLG55021(CHIPS)':
 'SHDN_N': CDS_PINID='SHDN_N';
NODE_NAME     EU2T1 1
 '@BASEBOARD_FAB2_LIB.BASEBOARD_FAB2(SCH_1):PAGE198_I1@MSTR_VREG.SLG55021(CHIPS)':
 'VCC': CDS_PINID='VCC';
NODE_NAME     EU8B1 5
 '@BASEBOARD_FAB2_LIB.BASEBOARD_FAB2(SCH_1):PAGE198_I13@MSTR_VREG.SLG55021(CHIPS)':
 'D': CDS_PINID='D';
NODE_NAME     EU8B1 3
 '@BASEBOARD_FAB2_LIB.BASEBOARD_FAB2(SCH_1):PAGE198_I13@MSTR_VREG.SLG55021(CHIPS)':
 'SHDN_N': CDS_PINID='SHDN_N';
NODE_NAME     EU8B1 1
 '@BASEBOARD_FAB2_LIB.BASEBOARD_FAB2(SCH_1):PAGE198_I13@MSTR_VREG.SLG55021(CHIPS)':
 'VCC': CDS_PINID='VCC';
NODE_NAME     EU7E1 3
 '@BASEBOARD_FAB2_LIB.BASEBOARD_FAB2(SCH_1):PAGE198_I19@MSTR_VREG.SLG55021(CHIPS)':
 'SHDN_N': CDS_PINID='SHDN_N';
NODE_NAME     EU7E1 1
 '@BASEBOARD_FAB2_LIB.BASEBOARD_FAB2(SCH_1):PAGE198_I19@MSTR_VREG.SLG55021(CHIPS)':
 'VCC': CDS_PINID='VCC';
NODE_NAME     C8F17 1
 '@BASEBOARD_FAB2_LIB.BASEBOARD_FAB2(SCH_1):PAGE198_I24@DEV_DISCRETE.CAP_A(CHIPS)':
 'A': CDS_PINID='A';
NODE_NAME     C8B8 1
 '@BASEBOARD_FAB2_LIB.BASEBOARD_FAB2(SCH_1):PAGE198_I26@DEV_DISCRETE.CAP_A(CHIPS)':
 'A': CDS_PINID='A';
NODE_NAME     C8E19 1
 '@BASEBOARD_FAB2_LIB.BASEBOARD_FAB2(SCH_1):PAGE198_I28@DEV_DISCRETE.CAP_A(CHIPS)':
 'A': CDS_PINID='A';
NODE_NAME     C8B5 1
 '@BASEBOARD_FAB2_LIB.BASEBOARD_FAB2(SCH_1):PAGE198_I37@DEV_DISCRETE.CAP_A(CHIPS)':
 'A': CDS_PINID='A';
NODE_NAME     C8B12 1
 '@BASEBOARD_FAB2_LIB.BASEBOARD_FAB2(SCH_1):PAGE198_I38@MSTR_DISCRETE.CAP(CHIPS)':
 'A': CDS_PINID='A';
NODE_NAME     C9M6 1
 '@BASEBOARD_FAB2_LIB.BASEBOARD_FAB2(SCH_1):PAGE198_I67@DEV_DISCRETE.CAP_A(CHIPS)':
 'A': CDS_PINID='A';
NODE_NAME     EU9M1 3
 '@BASEBOARD_FAB2_LIB.BASEBOARD_FAB2(SCH_1):PAGE198_I69@MSTR_VREG.SLG55021(CHIPS)':
 'SHDN_N': CDS_PINID='SHDN_N';
NODE_NAME     EU9M1 1
 '@BASEBOARD_FAB2_LIB.BASEBOARD_FAB2(SCH_1):PAGE198_I69@MSTR_VREG.SLG55021(CHIPS)':
 'VCC': CDS_PINID='VCC';
NODE_NAME     Q8B1 5
 '@BASEBOARD_FAB2_LIB.BASEBOARD_FAB2(SCH_1):PAGE198_I87@MSTR_DISCRETE.MOSFET_N(CHIPS)':
 'DRN': CDS_PINID='DRN';
NODE_NAME     C4E5 1
 '@BASEBOARD_FAB2_LIB.BASEBOARD_FAB2(SCH_1):PAGE202_I18@MSTR_DISCRETE.CAP(CHIPS)':
 'A': CDS_PINID='A';
NODE_NAME     C4E27 1
 '@BASEBOARD_FAB2_LIB.BASEBOARD_FAB2(SCH_1):PAGE202_I24@MSTR_DISCRETE.CAP(CHIPS)':
 'A': CDS_PINID='A';
NODE_NAME     EU4E1 35
 '@BASEBOARD_FAB2_LIB.BASEBOARD_FAB2(SCH_1):PAGE202_I63@MSTR_DISCRETE.IR354XX(CHIPS)':
 'EN': CDS_PINID='EN';
NODE_NAME     EU4E1 4
 '@BASEBOARD_FAB2_LIB.BASEBOARD_FAB2(SCH_1):PAGE202_I63@MSTR_DISCRETE.IR354XX(CHIPS)':
 'VDRV': CDS_PINID='VDRV';
NODE_NAME     EU4D6 35
 '@BASEBOARD_FAB2_LIB.BASEBOARD_FAB2(SCH_1):PAGE202_I64@MSTR_DISCRETE.IR354XX(CHIPS)':
 'EN': CDS_PINID='EN';
NODE_NAME     EU4D6 4
 '@BASEBOARD_FAB2_LIB.BASEBOARD_FAB2(SCH_1):PAGE202_I64@MSTR_DISCRETE.IR354XX(CHIPS)':
 'VDRV': CDS_PINID='VDRV';
NODE_NAME     C4D13 1
 '@BASEBOARD_FAB2_LIB.BASEBOARD_FAB2(SCH_1):PAGE203_I40@MSTR_DISCRETE.CAP(CHIPS)':
 'A': CDS_PINID='A';
NODE_NAME     C4D5 1
 '@BASEBOARD_FAB2_LIB.BASEBOARD_FAB2(SCH_1):PAGE203_I48@MSTR_DISCRETE.CAP(CHIPS)':
 'A': CDS_PINID='A';
NODE_NAME     EU4D3 35
 '@BASEBOARD_FAB2_LIB.BASEBOARD_FAB2(SCH_1):PAGE203_I70@MSTR_DISCRETE.IR354XX(CHIPS)':
 'EN': CDS_PINID='EN';
NODE_NAME     EU4D3 4
 '@BASEBOARD_FAB2_LIB.BASEBOARD_FAB2(SCH_1):PAGE203_I70@MSTR_DISCRETE.IR354XX(CHIPS)':
 'VDRV': CDS_PINID='VDRV';
NODE_NAME     EU4D1 35
 '@BASEBOARD_FAB2_LIB.BASEBOARD_FAB2(SCH_1):PAGE203_I71@MSTR_DISCRETE.IR354XX(CHIPS)':
 'EN': CDS_PINID='EN';
NODE_NAME     EU4D1 4
 '@BASEBOARD_FAB2_LIB.BASEBOARD_FAB2(SCH_1):PAGE203_I71@MSTR_DISCRETE.IR354XX(CHIPS)':
 'VDRV': CDS_PINID='VDRV';
NODE_NAME     C4D47 1
 '@BASEBOARD_FAB2_LIB.BASEBOARD_FAB2(SCH_1):PAGE204_I18@MSTR_DISCRETE.CAP(CHIPS)':
 'A': CDS_PINID='A';
NODE_NAME     EU4C2 35
 '@BASEBOARD_FAB2_LIB.BASEBOARD_FAB2(SCH_1):PAGE204_I71@MSTR_DISCRETE.IR354XX(CHIPS)':
 'EN': CDS_PINID='EN';
NODE_NAME     EU4C2 4
 '@BASEBOARD_FAB2_LIB.BASEBOARD_FAB2(SCH_1):PAGE204_I71@MSTR_DISCRETE.IR354XX(CHIPS)':
 'VDRV': CDS_PINID='VDRV';
NODE_NAME     C4C5 1
 '@BASEBOARD_FAB2_LIB.BASEBOARD_FAB2(SCH_1):PAGE205_I16@MSTR_DISCRETE.CAP(CHIPS)':
 'A': CDS_PINID='A';
NODE_NAME     EU4C1 35
 '@BASEBOARD_FAB2_LIB.BASEBOARD_FAB2(SCH_1):PAGE205_I46@MSTR_DISCRETE.IR354XX(CHIPS)':
 'EN': CDS_PINID='EN';
NODE_NAME     EU4C1 4
 '@BASEBOARD_FAB2_LIB.BASEBOARD_FAB2(SCH_1):PAGE205_I46@MSTR_DISCRETE.IR354XX(CHIPS)':
 'VDRV': CDS_PINID='VDRV';
NODE_NAME     EU1E2 35
 '@BASEBOARD_FAB2_LIB.BASEBOARD_FAB2(SCH_1):PAGE207_I20@MSTR_DISCRETE.IR354XX(CHIPS)':
 'EN': CDS_PINID='EN';
NODE_NAME     EU1E2 4
 '@BASEBOARD_FAB2_LIB.BASEBOARD_FAB2(SCH_1):PAGE207_I20@MSTR_DISCRETE.IR354XX(CHIPS)':
 'VDRV': CDS_PINID='VDRV';
NODE_NAME     C1E7 1
 '@BASEBOARD_FAB2_LIB.BASEBOARD_FAB2(SCH_1):PAGE207_I28@MSTR_DISCRETE.CAP(CHIPS)':
 'A': CDS_PINID='A';
NODE_NAME     C1E25 1
 '@BASEBOARD_FAB2_LIB.BASEBOARD_FAB2(SCH_1):PAGE207_I36@MSTR_DISCRETE.CAP(CHIPS)':
 'A': CDS_PINID='A';
NODE_NAME     EU1D3 35
 '@BASEBOARD_FAB2_LIB.BASEBOARD_FAB2(SCH_1):PAGE208_I27@MSTR_DISCRETE.IR354XX(CHIPS)':
 'EN': CDS_PINID='EN';
NODE_NAME     EU1D3 4
 '@BASEBOARD_FAB2_LIB.BASEBOARD_FAB2(SCH_1):PAGE208_I27@MSTR_DISCRETE.IR354XX(CHIPS)':
 'VDRV': CDS_PINID='VDRV';
NODE_NAME     C1D16 1
 '@BASEBOARD_FAB2_LIB.BASEBOARD_FAB2(SCH_1):PAGE208_I38@MSTR_DISCRETE.CAP(CHIPS)':
 'A': CDS_PINID='A';
NODE_NAME     C1D6 1
 '@BASEBOARD_FAB2_LIB.BASEBOARD_FAB2(SCH_1):PAGE208_I46@MSTR_DISCRETE.CAP(CHIPS)':
 'A': CDS_PINID='A';
NODE_NAME     EU1D1 35
 '@BASEBOARD_FAB2_LIB.BASEBOARD_FAB2(SCH_1):PAGE208_I71@MSTR_DISCRETE.IR354XX(CHIPS)':
 'EN': CDS_PINID='EN';
NODE_NAME     EU1D1 4
 '@BASEBOARD_FAB2_LIB.BASEBOARD_FAB2(SCH_1):PAGE208_I71@MSTR_DISCRETE.IR354XX(CHIPS)':
 'VDRV': CDS_PINID='VDRV';
NODE_NAME     C1D33 1
 '@BASEBOARD_FAB2_LIB.BASEBOARD_FAB2(SCH_1):PAGE209_I22@MSTR_DISCRETE.CAP(CHIPS)':
 'A': CDS_PINID='A';
NODE_NAME     EU1C3 35
 '@BASEBOARD_FAB2_LIB.BASEBOARD_FAB2(SCH_1):PAGE209_I56@MSTR_DISCRETE.IR354XX(CHIPS)':
 'EN': CDS_PINID='EN';
NODE_NAME     EU1C3 4
 '@BASEBOARD_FAB2_LIB.BASEBOARD_FAB2(SCH_1):PAGE209_I56@MSTR_DISCRETE.IR354XX(CHIPS)':
 'VDRV': CDS_PINID='VDRV';
NODE_NAME     C1C4 1
 '@BASEBOARD_FAB2_LIB.BASEBOARD_FAB2(SCH_1):PAGE210_I22@MSTR_DISCRETE.CAP(CHIPS)':
 'A': CDS_PINID='A';
NODE_NAME     EU1C1 35
 '@BASEBOARD_FAB2_LIB.BASEBOARD_FAB2(SCH_1):PAGE210_I51@MSTR_DISCRETE.IR354XX(CHIPS)':
 'EN': CDS_PINID='EN';
NODE_NAME     EU1C1 4
 '@BASEBOARD_FAB2_LIB.BASEBOARD_FAB2(SCH_1):PAGE210_I51@MSTR_DISCRETE.IR354XX(CHIPS)':
 'VDRV': CDS_PINID='VDRV';
NODE_NAME     C7C18 1
 '@BASEBOARD_FAB2_LIB.BASEBOARD_FAB2(SCH_1):PAGE212_I33@MSTR_DISCRETE.CAP(CHIPS)':
 'A': CDS_PINID='A';
NODE_NAME     EU7C1 35
 '@BASEBOARD_FAB2_LIB.BASEBOARD_FAB2(SCH_1):PAGE212_I101@MSTR_DISCRETE.IR354XX(CHIPS)':
 'EN': CDS_PINID='EN';
NODE_NAME     EU7C1 4
 '@BASEBOARD_FAB2_LIB.BASEBOARD_FAB2(SCH_1):PAGE212_I101@MSTR_DISCRETE.IR354XX(CHIPS)':
 'VDRV': CDS_PINID='VDRV';
NODE_NAME     C4E23 1
 '@BASEBOARD_FAB2_LIB.BASEBOARD_FAB2(SCH_1):PAGE214_I73@MSTR_DISCRETE.CAP(CHIPS)':
 'A': CDS_PINID='A';
NODE_NAME     EU4E2 35
 '@BASEBOARD_FAB2_LIB.BASEBOARD_FAB2(SCH_1):PAGE214_I126@MSTR_DISCRETE.IR354XX(CHIPS)':
 'EN': CDS_PINID='EN';
NODE_NAME     EU4E2 4
 '@BASEBOARD_FAB2_LIB.BASEBOARD_FAB2(SCH_1):PAGE214_I126@MSTR_DISCRETE.IR354XX(CHIPS)':
 'VDRV': CDS_PINID='VDRV';
NODE_NAME     C7G34 1
 '@BASEBOARD_FAB2_LIB.BASEBOARD_FAB2(SCH_1):PAGE216_I54@MSTR_DISCRETE.CAP(CHIPS)':
 'A': CDS_PINID='A';
NODE_NAME     C7G41 1
 '@BASEBOARD_FAB2_LIB.BASEBOARD_FAB2(SCH_1):PAGE216_I72@MSTR_DISCRETE.CAP(CHIPS)':
 'A': CDS_PINID='A';
NODE_NAME     EU7G2 35
 '@BASEBOARD_FAB2_LIB.BASEBOARD_FAB2(SCH_1):PAGE216_I102@MSTR_DISCRETE.IR354XX(CHIPS)':
 'EN': CDS_PINID='EN';
NODE_NAME     EU7G2 4
 '@BASEBOARD_FAB2_LIB.BASEBOARD_FAB2(SCH_1):PAGE216_I102@MSTR_DISCRETE.IR354XX(CHIPS)':
 'VDRV': CDS_PINID='VDRV';
NODE_NAME     EU7G3 35
 '@BASEBOARD_FAB2_LIB.BASEBOARD_FAB2(SCH_1):PAGE216_I103@MSTR_DISCRETE.IR354XX(CHIPS)':
 'EN': CDS_PINID='EN';
NODE_NAME     EU7G3 4
 '@BASEBOARD_FAB2_LIB.BASEBOARD_FAB2(SCH_1):PAGE216_I103@MSTR_DISCRETE.IR354XX(CHIPS)':
 'VDRV': CDS_PINID='VDRV';
NODE_NAME     C7A17 1
 '@BASEBOARD_FAB2_LIB.BASEBOARD_FAB2(SCH_1):PAGE219_I54@MSTR_DISCRETE.CAP(CHIPS)':
 'A': CDS_PINID='A';
NODE_NAME     C7A25 1
 '@BASEBOARD_FAB2_LIB.BASEBOARD_FAB2(SCH_1):PAGE219_I72@MSTR_DISCRETE.CAP(CHIPS)':
 'A': CDS_PINID='A';
NODE_NAME     EU7A1 35
 '@BASEBOARD_FAB2_LIB.BASEBOARD_FAB2(SCH_1):PAGE219_I106@MSTR_DISCRETE.IR354XX(CHIPS)':
 'EN': CDS_PINID='EN';
NODE_NAME     EU7A1 4
 '@BASEBOARD_FAB2_LIB.BASEBOARD_FAB2(SCH_1):PAGE219_I106@MSTR_DISCRETE.IR354XX(CHIPS)':
 'VDRV': CDS_PINID='VDRV';
NODE_NAME     EU7A4 35
 '@BASEBOARD_FAB2_LIB.BASEBOARD_FAB2(SCH_1):PAGE219_I107@MSTR_DISCRETE.IR354XX(CHIPS)':
 'EN': CDS_PINID='EN';
NODE_NAME     EU7A4 4
 '@BASEBOARD_FAB2_LIB.BASEBOARD_FAB2(SCH_1):PAGE219_I107@MSTR_DISCRETE.IR354XX(CHIPS)':
 'VDRV': CDS_PINID='VDRV';
NODE_NAME     C1G5 1
 '@BASEBOARD_FAB2_LIB.BASEBOARD_FAB2(SCH_1):PAGE224_I54@MSTR_DISCRETE.CAP(CHIPS)':
 'A': CDS_PINID='A';
NODE_NAME     C1G29 1
 '@BASEBOARD_FAB2_LIB.BASEBOARD_FAB2(SCH_1):PAGE224_I72@MSTR_DISCRETE.CAP(CHIPS)':
 'A': CDS_PINID='A';
NODE_NAME     EU1G1 35
 '@BASEBOARD_FAB2_LIB.BASEBOARD_FAB2(SCH_1):PAGE224_I110@MSTR_DISCRETE.IR354XX(CHIPS)':
 'EN': CDS_PINID='EN';
NODE_NAME     EU1G1 4
 '@BASEBOARD_FAB2_LIB.BASEBOARD_FAB2(SCH_1):PAGE224_I110@MSTR_DISCRETE.IR354XX(CHIPS)':
 'VDRV': CDS_PINID='VDRV';
NODE_NAME     EU1F1 35
 '@BASEBOARD_FAB2_LIB.BASEBOARD_FAB2(SCH_1):PAGE224_I111@MSTR_DISCRETE.IR354XX(CHIPS)':
 'EN': CDS_PINID='EN';
NODE_NAME     EU1F1 4
 '@BASEBOARD_FAB2_LIB.BASEBOARD_FAB2(SCH_1):PAGE224_I111@MSTR_DISCRETE.IR354XX(CHIPS)':
 'VDRV': CDS_PINID='VDRV';
NODE_NAME     C1B21 1
 '@BASEBOARD_FAB2_LIB.BASEBOARD_FAB2(SCH_1):PAGE227_I54@MSTR_DISCRETE.CAP(CHIPS)':
 'A': CDS_PINID='A';
NODE_NAME     C1A13 1
 '@BASEBOARD_FAB2_LIB.BASEBOARD_FAB2(SCH_1):PAGE227_I72@MSTR_DISCRETE.CAP(CHIPS)':
 'A': CDS_PINID='A';
NODE_NAME     EU1A2 35
 '@BASEBOARD_FAB2_LIB.BASEBOARD_FAB2(SCH_1):PAGE227_I101@MSTR_DISCRETE.IR354XX(CHIPS)':
 'EN': CDS_PINID='EN';
NODE_NAME     EU1A2 4
 '@BASEBOARD_FAB2_LIB.BASEBOARD_FAB2(SCH_1):PAGE227_I101@MSTR_DISCRETE.IR354XX(CHIPS)':
 'VDRV': CDS_PINID='VDRV';
NODE_NAME     EU1A1 35
 '@BASEBOARD_FAB2_LIB.BASEBOARD_FAB2(SCH_1):PAGE227_I102@MSTR_DISCRETE.IR354XX(CHIPS)':
 'EN': CDS_PINID='EN';
NODE_NAME     EU1A1 4
 '@BASEBOARD_FAB2_LIB.BASEBOARD_FAB2(SCH_1):PAGE227_I102@MSTR_DISCRETE.IR354XX(CHIPS)':
 'VDRV': CDS_PINID='VDRV';
NODE_NAME     C7A8 1
 '@BASEBOARD_FAB2_LIB.BASEBOARD_FAB2(SCH_1):PAGE236_I16@MSTR_DISCRETE.CAP(CHIPS)':
 'A': CDS_PINID='A';
NODE_NAME     C7A41 1
 '@BASEBOARD_FAB2_LIB.BASEBOARD_FAB2(SCH_1):PAGE236_I39@MSTR_DISCRETE.CAP(CHIPS)':
 'A': CDS_PINID='A';
NODE_NAME     EU7A3 35
 '@BASEBOARD_FAB2_LIB.BASEBOARD_FAB2(SCH_1):PAGE236_I116@MSTR_DISCRETE.IR354XX(CHIPS)':
 'EN': CDS_PINID='EN';
NODE_NAME     EU7A3 4
 '@BASEBOARD_FAB2_LIB.BASEBOARD_FAB2(SCH_1):PAGE236_I116@MSTR_DISCRETE.IR354XX(CHIPS)':
 'VDRV': CDS_PINID='VDRV';
NODE_NAME     EU7A2 35
 '@BASEBOARD_FAB2_LIB.BASEBOARD_FAB2(SCH_1):PAGE236_I117@MSTR_DISCRETE.IR354XX(CHIPS)':
 'EN': CDS_PINID='EN';
NODE_NAME     EU7A2 4
 '@BASEBOARD_FAB2_LIB.BASEBOARD_FAB2(SCH_1):PAGE236_I117@MSTR_DISCRETE.IR354XX(CHIPS)':
 'VDRV': CDS_PINID='VDRV';
NODE_NAME     EU8F1 5
 '@BASEBOARD_FAB2_LIB.BASEBOARD_FAB2(SCH_1):PAGE240_I125@MSTR_VREG.RT8240(CHIPS)':
 'VCC': CDS_PINID='VCC';
NODE_NAME     R8E18 1
 '@BASEBOARD_FAB2_LIB.BASEBOARD_FAB2(SCH_1):PAGE241_I9@MSTR_DISCRETE.RES(CHIPS)':
 'A': CDS_PINID='A';
NODE_NAME     R7E12 1
 '@BASEBOARD_FAB2_LIB.BASEBOARD_FAB2(SCH_1):PAGE241_I11@MSTR_DISCRETE.RES(CHIPS)':
 'A': CDS_PINID='A';
NODE_NAME     R8E37 2
 '@BASEBOARD_FAB2_LIB.BASEBOARD_FAB2(SCH_1):PAGE241_I78@MSTR_DISCRETE.RES(CHIPS)':
 'B': CDS_PINID='B';
NODE_NAME     L8E1 2
 '@BASEBOARD_FAB2_LIB.BASEBOARD_FAB2(SCH_1):PAGE241_I90@MSTR_DISCRETE.INDUCTOR(CHIPS)':
 'INB': CDS_PINID='INB';
NODE_NAME     Q9W4 5
 '@BASEBOARD_FAB2_LIB.BASEBOARD_FAB2(SCH_1):PAGE249_I15@W_HDL.LMV331IDCKRG4-GP(CHIPS)':
 'VCC': CDS_PINID='VCC';
NODE_NAME     R1W10 1
 '@BASEBOARD_FAB2_LIB.BASEBOARD_FAB2(SCH_1):PAGE176_I132@MSTR_DISCRETE.RES(CHIPS)':
 'A': CDS_PINID='A';
NODE_NAME     CR10W2 1
 '@BASEBOARD_FAB2_LIB.BASEBOARD_FAB2(SCH_1):PAGE251_I10@MSTR_DISCRETE.DIODE(CHIPS)':
 'C': CDS_PINID='C';
NODE_NAME     R10W3 1
 '@BASEBOARD_FAB2_LIB.BASEBOARD_FAB2(SCH_1):PAGE251_I11@MSTR_DISCRETE.RES(CHIPS)':
 'A': CDS_PINID='A';
NODE_NAME     R6P19 2
 '@BASEBOARD_FAB2_LIB.BASEBOARD_FAB2(SCH_1):PAGE203_I128@MSTR_DISCRETE.RES(CHIPS)':
 'B': CDS_PINID='B';
NODE_NAME     R6P10 2
 '@BASEBOARD_FAB2_LIB.BASEBOARD_FAB2(SCH_1):PAGE203_I129@MSTR_DISCRETE.RES(CHIPS)':
 'B': CDS_PINID='B';
NODE_NAME     R6R2 2
 '@BASEBOARD_FAB2_LIB.BASEBOARD_FAB2(SCH_1):PAGE202_I107@MSTR_DISCRETE.RES(CHIPS)':
 'B': CDS_PINID='B';
NODE_NAME     R6R6 2
 '@BASEBOARD_FAB2_LIB.BASEBOARD_FAB2(SCH_1):PAGE202_I108@MSTR_DISCRETE.RES(CHIPS)':
 'B': CDS_PINID='B';
NODE_NAME     R6N3 2
 '@BASEBOARD_FAB2_LIB.BASEBOARD_FAB2(SCH_1):PAGE205_I81@MSTR_DISCRETE.RES(CHIPS)':
 'B': CDS_PINID='B';
NODE_NAME     R6P47 2
 '@BASEBOARD_FAB2_LIB.BASEBOARD_FAB2(SCH_1):PAGE204_I103@MSTR_DISCRETE.RES(CHIPS)':
 'B': CDS_PINID='B';
NODE_NAME     R9R11 2
 '@BASEBOARD_FAB2_LIB.BASEBOARD_FAB2(SCH_1):PAGE207_I105@MSTR_DISCRETE.RES(CHIPS)':
 'B': CDS_PINID='B';
NODE_NAME     R9R2 2
 '@BASEBOARD_FAB2_LIB.BASEBOARD_FAB2(SCH_1):PAGE207_I106@MSTR_DISCRETE.RES(CHIPS)':
 'B': CDS_PINID='B';
NODE_NAME     R9P22 2
 '@BASEBOARD_FAB2_LIB.BASEBOARD_FAB2(SCH_1):PAGE208_I114@MSTR_DISCRETE.RES(CHIPS)':
 'B': CDS_PINID='B';
NODE_NAME     R9P8 2
 '@BASEBOARD_FAB2_LIB.BASEBOARD_FAB2(SCH_1):PAGE208_I115@MSTR_DISCRETE.RES(CHIPS)':
 'B': CDS_PINID='B';
NODE_NAME     R9P32 2
 '@BASEBOARD_FAB2_LIB.BASEBOARD_FAB2(SCH_1):PAGE209_I79@MSTR_DISCRETE.RES(CHIPS)':
 'B': CDS_PINID='B';
NODE_NAME     R9N3 2
 '@BASEBOARD_FAB2_LIB.BASEBOARD_FAB2(SCH_1):PAGE210_I71@MSTR_DISCRETE.RES(CHIPS)':
 'B': CDS_PINID='B';
NODE_NAME     R3N7 2
 '@BASEBOARD_FAB2_LIB.BASEBOARD_FAB2(SCH_1):PAGE212_I140@MSTR_DISCRETE.RES(CHIPS)':
 'B': CDS_PINID='B';
NODE_NAME     R6R5 2
 '@BASEBOARD_FAB2_LIB.BASEBOARD_FAB2(SCH_1):PAGE214_I173@MSTR_DISCRETE.RES(CHIPS)':
 'B': CDS_PINID='B';
NODE_NAME     R3U6 2
 '@BASEBOARD_FAB2_LIB.BASEBOARD_FAB2(SCH_1):PAGE216_I145@MSTR_DISCRETE.RES(CHIPS)':
 'B': CDS_PINID='B';
NODE_NAME     R3U9 2
 '@BASEBOARD_FAB2_LIB.BASEBOARD_FAB2(SCH_1):PAGE216_I146@MSTR_DISCRETE.RES(CHIPS)':
 'B': CDS_PINID='B';
NODE_NAME     R3L6 2
 '@BASEBOARD_FAB2_LIB.BASEBOARD_FAB2(SCH_1):PAGE219_I147@MSTR_DISCRETE.RES(CHIPS)':
 'B': CDS_PINID='B';
NODE_NAME     R3L8 2
 '@BASEBOARD_FAB2_LIB.BASEBOARD_FAB2(SCH_1):PAGE219_I148@MSTR_DISCRETE.RES(CHIPS)':
 'B': CDS_PINID='B';
NODE_NAME     R9U1 2
 '@BASEBOARD_FAB2_LIB.BASEBOARD_FAB2(SCH_1):PAGE224_I150@MSTR_DISCRETE.RES(CHIPS)':
 'B': CDS_PINID='B';
NODE_NAME     R9U12 2
 '@BASEBOARD_FAB2_LIB.BASEBOARD_FAB2(SCH_1):PAGE224_I151@MSTR_DISCRETE.RES(CHIPS)':
 'B': CDS_PINID='B';
NODE_NAME     R3L1 2
 '@BASEBOARD_FAB2_LIB.BASEBOARD_FAB2(SCH_1):PAGE236_I175@MSTR_DISCRETE.RES(CHIPS)':
 'B': CDS_PINID='B';
NODE_NAME     R3L4 2
 '@BASEBOARD_FAB2_LIB.BASEBOARD_FAB2(SCH_1):PAGE236_I177@MSTR_DISCRETE.RES(CHIPS)':
 'B': CDS_PINID='B';
NODE_NAME     C8E4 1
 '@BASEBOARD_FAB2_LIB.BASEBOARD_FAB2(SCH_1):PAGE241_I100@W_HDL.ST220U10VDM-LGP(CHIPS)':
 '1': CDS_PINID='\1\';
NODE_NAME     C2R11 1
 '@BASEBOARD_FAB2_LIB.BASEBOARD_FAB2(SCH_1):PAGE240_I191@W_HDL.SC4D7U16V3KX-GP(CHIPS)':
 '1': CDS_PINID='\1\';
NODE_NAME     C9B9 1
 '@BASEBOARD_FAB2_LIB.BASEBOARD_FAB2(SCH_1):PAGE186_I357@W_HDL.SC1U10V2KX-4-GP(CHIPS)':
 '1': CDS_PINID='\1\';
NODE_NAME     C1C18 1
 '@BASEBOARD_FAB2_LIB.BASEBOARD_FAB2(SCH_1):PAGE209_I89@W_HDL.SC1U10V2KX-4-GP(CHIPS)':
 '1': CDS_PINID='\1\';
NODE_NAME     C1A11 1
 '@BASEBOARD_FAB2_LIB.BASEBOARD_FAB2(SCH_1):PAGE227_I147@W_HDL.SC1U10V2KX-4-GP(CHIPS)':
 '1': CDS_PINID='\1\';
NODE_NAME     C1A2 1
 '@BASEBOARD_FAB2_LIB.BASEBOARD_FAB2(SCH_1):PAGE227_I148@W_HDL.SC1U10V2KX-4-GP(CHIPS)':
 '1': CDS_PINID='\1\';
NODE_NAME     C1C3 1
 '@BASEBOARD_FAB2_LIB.BASEBOARD_FAB2(SCH_1):PAGE210_I73@W_HDL.SC1U10V2KX-4-GP(CHIPS)':
 '1': CDS_PINID='\1\';
NODE_NAME     C1D15 1
 '@BASEBOARD_FAB2_LIB.BASEBOARD_FAB2(SCH_1):PAGE208_I118@W_HDL.SC1U10V2KX-4-GP(CHIPS)':
 '1': CDS_PINID='\1\';
NODE_NAME     C1D5 1
 '@BASEBOARD_FAB2_LIB.BASEBOARD_FAB2(SCH_1):PAGE208_I119@W_HDL.SC1U10V2KX-4-GP(CHIPS)':
 '1': CDS_PINID='\1\';
NODE_NAME     C1E23 1
 '@BASEBOARD_FAB2_LIB.BASEBOARD_FAB2(SCH_1):PAGE207_I109@W_HDL.SC1U10V2KX-4-GP(CHIPS)':
 '1': CDS_PINID='\1\';
NODE_NAME     C1E6 1
 '@BASEBOARD_FAB2_LIB.BASEBOARD_FAB2(SCH_1):PAGE207_I110@W_HDL.SC1U10V2KX-4-GP(CHIPS)':
 '1': CDS_PINID='\1\';
NODE_NAME     C1F21 1
 '@BASEBOARD_FAB2_LIB.BASEBOARD_FAB2(SCH_1):PAGE224_I154@W_HDL.SC1U10V2KX-4-GP(CHIPS)':
 '1': CDS_PINID='\1\';
NODE_NAME     C1G4 1
 '@BASEBOARD_FAB2_LIB.BASEBOARD_FAB2(SCH_1):PAGE224_I155@W_HDL.SC1U10V2KX-4-GP(CHIPS)':
 '1': CDS_PINID='\1\';
NODE_NAME     C3L1 1
 '@BASEBOARD_FAB2_LIB.BASEBOARD_FAB2(SCH_1):PAGE236_I180@W_HDL.SC1U10V2KX-4-GP(CHIPS)':
 '1': CDS_PINID='\1\';
NODE_NAME     C3L29 1
 '@BASEBOARD_FAB2_LIB.BASEBOARD_FAB2(SCH_1):PAGE236_I181@W_HDL.SC1U10V2KX-4-GP(CHIPS)':
 '1': CDS_PINID='\1\';
NODE_NAME     C4C4 1
 '@BASEBOARD_FAB2_LIB.BASEBOARD_FAB2(SCH_1):PAGE205_I83@W_HDL.SC1U10V2KX-4-GP(CHIPS)':
 '1': CDS_PINID='\1\';
NODE_NAME     C4C14 1
 '@BASEBOARD_FAB2_LIB.BASEBOARD_FAB2(SCH_1):PAGE204_I113@W_HDL.SC1U10V2KX-4-GP(CHIPS)':
 '1': CDS_PINID='\1\';
NODE_NAME     C4D14 1
 '@BASEBOARD_FAB2_LIB.BASEBOARD_FAB2(SCH_1):PAGE203_I132@W_HDL.SC1U10V2KX-4-GP(CHIPS)':
 '1': CDS_PINID='\1\';
NODE_NAME     C4D6 1
 '@BASEBOARD_FAB2_LIB.BASEBOARD_FAB2(SCH_1):PAGE203_I133@W_HDL.SC1U10V2KX-4-GP(CHIPS)':
 '1': CDS_PINID='\1\';
NODE_NAME     C4E25 1
 '@BASEBOARD_FAB2_LIB.BASEBOARD_FAB2(SCH_1):PAGE202_I111@W_HDL.SC1U10V2KX-4-GP(CHIPS)':
 '1': CDS_PINID='\1\';
NODE_NAME     C4E6 1
 '@BASEBOARD_FAB2_LIB.BASEBOARD_FAB2(SCH_1):PAGE202_I112@W_HDL.SC1U10V2KX-4-GP(CHIPS)':
 '1': CDS_PINID='\1\';
NODE_NAME     C4E28 1
 '@BASEBOARD_FAB2_LIB.BASEBOARD_FAB2(SCH_1):PAGE214_I175@W_HDL.SC1U10V2KX-4-GP(CHIPS)':
 '1': CDS_PINID='\1\';
NODE_NAME     C7A18 1
 '@BASEBOARD_FAB2_LIB.BASEBOARD_FAB2(SCH_1):PAGE219_I151@W_HDL.SC1U10V2KX-4-GP(CHIPS)':
 '1': CDS_PINID='\1\';
NODE_NAME     C7A26 1
 '@BASEBOARD_FAB2_LIB.BASEBOARD_FAB2(SCH_1):PAGE219_I152@W_HDL.SC1U10V2KX-4-GP(CHIPS)':
 '1': CDS_PINID='\1\';
NODE_NAME     C7C20 1
 '@BASEBOARD_FAB2_LIB.BASEBOARD_FAB2(SCH_1):PAGE212_I143@W_HDL.SC1U10V2KX-4-GP(CHIPS)':
 '1': CDS_PINID='\1\';
NODE_NAME     C7G35 1
 '@BASEBOARD_FAB2_LIB.BASEBOARD_FAB2(SCH_1):PAGE216_I149@W_HDL.SC1U10V2KX-4-GP(CHIPS)':
 '1': CDS_PINID='\1\';
NODE_NAME     C7G42 1
 '@BASEBOARD_FAB2_LIB.BASEBOARD_FAB2(SCH_1):PAGE216_I150@W_HDL.SC1U10V2KX-4-GP(CHIPS)':
 '1': CDS_PINID='\1\';
NODE_NAME     C8W2 1
 '@BASEBOARD_FAB2_LIB.BASEBOARD_FAB2(SCH_1):PAGE249_I37@DEV_DISCRETE.CAP_A(CHIPS)':
 'A': CDS_PINID='A';
NODE_NAME     C8E7 1
 '@BASEBOARD_FAB2_LIB.BASEBOARD_FAB2(SCH_1):PAGE241_I103@W_HDL.SC22U16V5MX-4-GP(CHIPS)':
 '1': CDS_PINID='\1\';
NODE_NAME     C8E9 1
 '@BASEBOARD_FAB2_LIB.BASEBOARD_FAB2(SCH_1):PAGE241_I104@W_HDL.SC22U16V5MX-4-GP(CHIPS)':
 '1': CDS_PINID='\1\';
NODE_NAME     R9A5 1
 '@BASEBOARD_FAB2_LIB.BASEBOARD_FAB2(SCH_1):PAGE155_I198@MSTR_DISCRETE.RES(CHIPS)':
 'A': CDS_PINID='A';
NODE_NAME     EU1D4 35
 '@BASEBOARD_FAB2_LIB.BASEBOARD_FAB2(SCH_1):PAGE207_I113@MSTR_DISCRETE.IR354XX(CHIPS)':
 'EN': CDS_PINID='EN';
NODE_NAME     EU1D4 4
 '@BASEBOARD_FAB2_LIB.BASEBOARD_FAB2(SCH_1):PAGE207_I113@MSTR_DISCRETE.IR354XX(CHIPS)':
 'VDRV': CDS_PINID='VDRV';
NODE_NAME     R9L9 2
 '@BASEBOARD_FAB2_LIB.BASEBOARD_FAB2(SCH_1):PAGE227_I154@MSTR_DISCRETE.RES(CHIPS)':
 'B': CDS_PINID='B';
NODE_NAME     R9L4 2
 '@BASEBOARD_FAB2_LIB.BASEBOARD_FAB2(SCH_1):PAGE227_I155@MSTR_DISCRETE.RES(CHIPS)':
 'B': CDS_PINID='B';
NODE_NAME     F30W1 1
 '@BASEBOARD_FAB2_LIB.BASEBOARD_FAB2(SCH_1):PAGE253_I44@W_HDL.POLYSW-1D1A6V-2-GP-U(CHIPS)':
 '1': CDS_PINID='\1\';
NET_NAME
'P5V_STBY_DBG'
 '@BASEBOARD_FAB2_LIB.BASEBOARD_FAB2(SCH_1):P5V_STBY_DBG':
 C_SIGNAL='@baseboard_fab2_lib.baseboard_fab2(sch_1):p5v_stby_dbg';
NODE_NAME     F1L1 1
 '@BASEBOARD_FAB2_LIB.BASEBOARD_FAB2(SCH_1):PAGE155_I129@MSTR_DISCRETE.FUSE(CHIPS)':
 'A'<0>: CDS_PINID='A(0)';
NODE_NAME     Q1L2 1
 '@BASEBOARD_FAB2_LIB.BASEBOARD_FAB2(SCH_1):PAGE155_I188@MSTR_DISCRETE.FET_N_DUAL(CHIPS)':
 'SOURCE'<0>: CDS_PINID='SOURCE(0)';
NET_NAME
'P5V_STBY_DGB_FS'
 '@BASEBOARD_FAB2_LIB.BASEBOARD_FAB2(SCH_1):P5V_STBY_DGB_FS':
 C_SIGNAL='@baseboard_fab2_lib.baseboard_fab2(sch_1):p5v_stby_dgb_fs';
NODE_NAME     C9A1 1
 '@BASEBOARD_FAB2_LIB.BASEBOARD_FAB2(SCH_1):PAGE155_I127@DEV_DISCRETE.CAP_A(CHIPS)':
 'A': CDS_PINID='A';
NODE_NAME     F1L1 2
 '@BASEBOARD_FAB2_LIB.BASEBOARD_FAB2(SCH_1):PAGE155_I129@MSTR_DISCRETE.FUSE(CHIPS)':
 'B'<0>: CDS_PINID='B(0)';
NODE_NAME     J9A2 14
 '@BASEBOARD_FAB2_LIB.BASEBOARD_FAB2(SCH_1):PAGE155_I171@MSTR_CONN.CONN14_H54902001(CHIPS)':
 'IO14': CDS_PINID='IO14';
NET_NAME
'P5V_STBY_USBC'
 '@BASEBOARD_FAB2_LIB.BASEBOARD_FAB2(SCH_1):P5V_STBY_USBC':
 C_SIGNAL='@baseboard_fab2_lib.baseboard_fab2(sch_1):p5v_stby_usbc';
NODE_NAME     J30W1 A4
 '@BASEBOARD_FAB2_LIB.BASEBOARD_FAB2(SCH_1):PAGE253_I26@W_HDL.SKT-USB32-8-GP(CHIPS)':
 'VBUS'<0>: CDS_PINID='VBUS(0)';
NODE_NAME     J30W1 A9
 '@BASEBOARD_FAB2_LIB.BASEBOARD_FAB2(SCH_1):PAGE253_I26@W_HDL.SKT-USB32-8-GP(CHIPS)':
 'VBUS'<1>: CDS_PINID='VBUS(1)';
NODE_NAME     J30W1 B4
 '@BASEBOARD_FAB2_LIB.BASEBOARD_FAB2(SCH_1):PAGE253_I26@W_HDL.SKT-USB32-8-GP(CHIPS)':
 'VBUS'<2>: CDS_PINID='VBUS(2)';
NODE_NAME     J30W1 B9
 '@BASEBOARD_FAB2_LIB.BASEBOARD_FAB2(SCH_1):PAGE253_I26@W_HDL.SKT-USB32-8-GP(CHIPS)':
 'VBUS'<3>: CDS_PINID='VBUS(3)';
NODE_NAME     C30W3 1
 '@BASEBOARD_FAB2_LIB.BASEBOARD_FAB2(SCH_1):PAGE253_I35@W_HDL.SC22U16V5MX-4-GP(CHIPS)':
 '1': CDS_PINID='\1\';
NODE_NAME     C30W4 1
 '@BASEBOARD_FAB2_LIB.BASEBOARD_FAB2(SCH_1):PAGE253_I36@W_HDL.SC22U16V5MX-4-GP(CHIPS)':
 '1': CDS_PINID='\1\';
NODE_NAME     C30W6 1
 '@BASEBOARD_FAB2_LIB.BASEBOARD_FAB2(SCH_1):PAGE253_I37@W_HDL.SC22U16V5MX-4-GP(CHIPS)':
 '1': CDS_PINID='\1\';
NODE_NAME     C30W5 1
 '@BASEBOARD_FAB2_LIB.BASEBOARD_FAB2(SCH_1):PAGE253_I38@W_HDL.SC22U16V5MX-4-GP(CHIPS)':
 '1': CDS_PINID='\1\';
NODE_NAME     C30W9 1
 '@BASEBOARD_FAB2_LIB.BASEBOARD_FAB2(SCH_1):PAGE253_I40@W_HDL.SC22U16V5MX-4-GP(CHIPS)':
 '1': CDS_PINID='\1\';
NODE_NAME     C30W8 1
 '@BASEBOARD_FAB2_LIB.BASEBOARD_FAB2(SCH_1):PAGE253_I41@W_HDL.SC22U16V5MX-4-GP(CHIPS)':
 '1': CDS_PINID='\1\';
NODE_NAME     C30W7 1
 '@BASEBOARD_FAB2_LIB.BASEBOARD_FAB2(SCH_1):PAGE253_I42@W_HDL.SC22U16V5MX-4-GP(CHIPS)':
 '1': CDS_PINID='\1\';
NODE_NAME     F30W1 2
 '@BASEBOARD_FAB2_LIB.BASEBOARD_FAB2(SCH_1):PAGE253_I44@W_HDL.POLYSW-1D1A6V-2-GP-U(CHIPS)':
 '2': CDS_PINID='\2\';
NET_NAME
'P5V_SWITCH_G'
 '@BASEBOARD_FAB2_LIB.BASEBOARD_FAB2(SCH_1):P5V_SWITCH_G':
 C_SIGNAL='@baseboard_fab2_lib.baseboard_fab2(sch_1):p5v_switch_g';
NODE_NAME     EU8B1 7
 '@BASEBOARD_FAB2_LIB.BASEBOARD_FAB2(SCH_1):PAGE198_I13@MSTR_VREG.SLG55021(CHIPS)':
 'G': CDS_PINID='G';
NODE_NAME     Q8B1 4
 '@BASEBOARD_FAB2_LIB.BASEBOARD_FAB2(SCH_1):PAGE198_I87@MSTR_DISCRETE.MOSFET_N(CHIPS)':
 'GATE': CDS_PINID='GATE';
NET_NAME
'P5V_TPS2061'
 '@BASEBOARD_FAB2_LIB.BASEBOARD_FAB2(SCH_1):P5V_TPS2061':
 C_SIGNAL='@baseboard_fab2_lib.baseboard_fab2(sch_1):p5v_tps2061';
NODE_NAME     U1M3 5
 '@BASEBOARD_FAB2_LIB.BASEBOARD_FAB2(SCH_1):PAGE176_I100@MSTR_VREG.TPS2061(CHIPS)':
 'IN': CDS_PINID='\in\';
NODE_NAME     C1M38 1
 '@BASEBOARD_FAB2_LIB.BASEBOARD_FAB2(SCH_1):PAGE176_I108@DEV_DISCRETE.CAP_A(CHIPS)':
 'A': CDS_PINID='A';
NODE_NAME     R1W10 2
 '@BASEBOARD_FAB2_LIB.BASEBOARD_FAB2(SCH_1):PAGE176_I132@MSTR_DISCRETE.RES(CHIPS)':
 'B': CDS_PINID='B';
NODE_NAME     R1W11 2
 '@BASEBOARD_FAB2_LIB.BASEBOARD_FAB2(SCH_1):PAGE176_I133@MSTR_DISCRETE.RES(CHIPS)':
 'B': CDS_PINID='B';
NET_NAME
'P5V_USB'
 '@BASEBOARD_FAB2_LIB.BASEBOARD_FAB2(SCH_1):P5V_USB':
 C_SIGNAL='@baseboard_fab2_lib.baseboard_fab2(sch_1):p5v_usb';
NODE_NAME     J9B1 1
 '@BASEBOARD_FAB2_LIB.BASEBOARD_FAB2(SCH_1):PAGE176_I69@MSTR_CONN.CONN9_H51826001(CHIPS)':
 'VBUS': CDS_PINID='VBUS';
NODE_NAME     U1M3 1
 '@BASEBOARD_FAB2_LIB.BASEBOARD_FAB2(SCH_1):PAGE176_I100@MSTR_VREG.TPS2061(CHIPS)':
 'OUT': CDS_PINID='\out\';
NODE_NAME     C9B8 1
 '@BASEBOARD_FAB2_LIB.BASEBOARD_FAB2(SCH_1):PAGE176_I113@MSTR_DISCRETE.CAPP(CHIPS)':
 'A': CDS_PINID='A';
NET_NAME
'P5V_VGA'
 '@BASEBOARD_FAB2_LIB.BASEBOARD_FAB2(SCH_1):P5V_VGA':
 C_SIGNAL='@baseboard_fab2_lib.baseboard_fab2(sch_1):p5v_vga';
NODE_NAME     C25P83 1
 '@BASEBOARD_FAB2_LIB.BASEBOARD_FAB2(SCH_1):PAGE255_I74@DEV_DISCRETE.CAP_A(CHIPS)':
 'A': CDS_PINID='A';
NODE_NAME     F25W1 1
 '@BASEBOARD_FAB2_LIB.BASEBOARD_FAB2(SCH_1):PAGE255_I89@W_HDL.POLYSW-D5A6V-2-GP-U(CHIPS)':
 '1': CDS_PINID='\1\';
NODE_NAME     J25W1 13
 '@BASEBOARD_FAB2_LIB.BASEBOARD_FAB2(SCH_1):PAGE255_I136@W_HDL.SMC-CON13-GP(CHIPS)':
 '13': CDS_PINID='\13\';
NET_NAME
'P5V_VGA_D'
 '@BASEBOARD_FAB2_LIB.BASEBOARD_FAB2(SCH_1):P5V_VGA_D':
 C_SIGNAL='@baseboard_fab2_lib.baseboard_fab2(sch_1):p5v_vga_d';
NODE_NAME     R25W132 1
 '@BASEBOARD_FAB2_LIB.BASEBOARD_FAB2(SCH_1):PAGE255_I31@MSTR_DISCRETE.RES(CHIPS)':
 'A': CDS_PINID='A';
NODE_NAME     R25W135 1
 '@BASEBOARD_FAB2_LIB.BASEBOARD_FAB2(SCH_1):PAGE255_I44@MSTR_DISCRETE.RES(CHIPS)':
 'A': CDS_PINID='A';
NODE_NAME     F25W1 2
 '@BASEBOARD_FAB2_LIB.BASEBOARD_FAB2(SCH_1):PAGE255_I89@W_HDL.POLYSW-D5A6V-2-GP-U(CHIPS)':
 '2': CDS_PINID='\2\';
NODE_NAME     U25W7 5
 '@BASEBOARD_FAB2_LIB.BASEBOARD_FAB2(SCH_1):PAGE255_I111@W_HDL.U74AHCT1G125G-AL5-R-GP-U(CHIPS)':
 'VCC': CDS_PINID='VCC';
NODE_NAME     U25W8 5
 '@BASEBOARD_FAB2_LIB.BASEBOARD_FAB2(SCH_1):PAGE255_I112@W_HDL.U74AHCT1G125G-AL5-R-GP-U(CHIPS)':
 'VCC': CDS_PINID='VCC';
NODE_NAME     C25W90 1
 '@BASEBOARD_FAB2_LIB.BASEBOARD_FAB2(SCH_1):PAGE255_I118@DEV_DISCRETE.CAP_A(CHIPS)':
 'A': CDS_PINID='A';
NODE_NAME     D25W8 K
 '@BASEBOARD_FAB2_LIB.BASEBOARD_FAB2(SCH_1):PAGE255_I128@W_HDL.RB551V30-GP(CHIPS)':
 'CATHODE': CDS_PINID='CATHODE';
NODE_NAME     C25P80 1
 '@BASEBOARD_FAB2_LIB.BASEBOARD_FAB2(SCH_1):PAGE255_I134@DEV_DISCRETE.CAP_A(CHIPS)':
 'A': CDS_PINID='A';
NET_NAME
'PCA9554_A0'
 '@BASEBOARD_FAB2_LIB.BASEBOARD_FAB2(SCH_1):PCA9554_A0':
 C_SIGNAL='@baseboard_fab2_lib.baseboard_fab2(sch_1):pca9554_a0';
NODE_NAME     R6W47 1
 '@BASEBOARD_FAB2_LIB.BASEBOARD_FAB2(SCH_1):PAGE164_I76@MSTR_DISCRETE.RES(CHIPS)':
 'A': CDS_PINID='A';
NODE_NAME     R6W44 2
 '@BASEBOARD_FAB2_LIB.BASEBOARD_FAB2(SCH_1):PAGE164_I78@MSTR_DISCRETE.RES(CHIPS)':
 'B': CDS_PINID='B';
NODE_NAME     U6W11 1
 '@BASEBOARD_FAB2_LIB.BASEBOARD_FAB2(SCH_1):PAGE164_I97@W_HDL.PCA9554PWR-GP(CHIPS)':
 'A0': CDS_PINID='A0';
NET_NAME
'PCA9554_A1'
 '@BASEBOARD_FAB2_LIB.BASEBOARD_FAB2(SCH_1):PCA9554_A1':
 C_SIGNAL='@baseboard_fab2_lib.baseboard_fab2(sch_1):pca9554_a1';
NODE_NAME     R6W46 1
 '@BASEBOARD_FAB2_LIB.BASEBOARD_FAB2(SCH_1):PAGE164_I93@MSTR_DISCRETE.RES(CHIPS)':
 'A': CDS_PINID='A';
NODE_NAME     R6W43 2
 '@BASEBOARD_FAB2_LIB.BASEBOARD_FAB2(SCH_1):PAGE164_I96@MSTR_DISCRETE.RES(CHIPS)':
 'B': CDS_PINID='B';
NODE_NAME     U6W11 2
 '@BASEBOARD_FAB2_LIB.BASEBOARD_FAB2(SCH_1):PAGE164_I97@W_HDL.PCA9554PWR-GP(CHIPS)':
 'A1': CDS_PINID='A1';
NET_NAME
'PCA9554_A2'
 '@BASEBOARD_FAB2_LIB.BASEBOARD_FAB2(SCH_1):PCA9554_A2':
 C_SIGNAL='@baseboard_fab2_lib.baseboard_fab2(sch_1):pca9554_a2';
NODE_NAME     R6W45 1
 '@BASEBOARD_FAB2_LIB.BASEBOARD_FAB2(SCH_1):PAGE164_I94@MSTR_DISCRETE.RES(CHIPS)':
 'A': CDS_PINID='A';
NODE_NAME     R6W42 2
 '@BASEBOARD_FAB2_LIB.BASEBOARD_FAB2(SCH_1):PAGE164_I95@MSTR_DISCRETE.RES(CHIPS)':
 'B': CDS_PINID='B';
NODE_NAME     U6W11 3
 '@BASEBOARD_FAB2_LIB.BASEBOARD_FAB2(SCH_1):PAGE164_I97@W_HDL.PCA9554PWR-GP(CHIPS)':
 'A2': CDS_PINID='A2';
NET_NAME
'PCA9554_INT_N'
 '@BASEBOARD_FAB2_LIB.BASEBOARD_FAB2(SCH_1):PCA9554_INT_N':
 C_SIGNAL='@baseboard_fab2_lib.baseboard_fab2(sch_1):pca9554_int_n';
NODE_NAME     R6W41 2
 '@BASEBOARD_FAB2_LIB.BASEBOARD_FAB2(SCH_1):PAGE164_I87@MSTR_DISCRETE.RES(CHIPS)':
 'B': CDS_PINID='B';
NODE_NAME     U6W11 13
 '@BASEBOARD_FAB2_LIB.BASEBOARD_FAB2(SCH_1):PAGE164_I97@W_HDL.PCA9554PWR-GP(CHIPS)':
 'INT#': CDS_PINID='\int#\';
NET_NAME
'PCA9555_A0'
 '@BASEBOARD_FAB2_LIB.BASEBOARD_FAB2(SCH_1):PCA9555_A0':
 C_SIGNAL='@baseboard_fab2_lib.baseboard_fab2(sch_1):pca9555_a0';
NODE_NAME     U6W1 21
 '@BASEBOARD_FAB2_LIB.BASEBOARD_FAB2(SCH_1):PAGE247_I120@W_HDL.TCA9555PWR-GP(CHIPS)':
 'A0': CDS_PINID='A0';
NODE_NAME     R6W6 2
 '@BASEBOARD_FAB2_LIB.BASEBOARD_FAB2(SCH_1):PAGE247_I161@MSTR_DISCRETE.RES(CHIPS)':
 'B': CDS_PINID='B';
NODE_NAME     R6W9 1
 '@BASEBOARD_FAB2_LIB.BASEBOARD_FAB2(SCH_1):PAGE247_I162@MSTR_DISCRETE.RES(CHIPS)':
 'A': CDS_PINID='A';
NET_NAME
'PCA9555_A1'
 '@BASEBOARD_FAB2_LIB.BASEBOARD_FAB2(SCH_1):PCA9555_A1':
 C_SIGNAL='@baseboard_fab2_lib.baseboard_fab2(sch_1):pca9555_a1';
NODE_NAME     U6W1 2
 '@BASEBOARD_FAB2_LIB.BASEBOARD_FAB2(SCH_1):PAGE247_I120@W_HDL.TCA9555PWR-GP(CHIPS)':
 'A1': CDS_PINID='A1';
NODE_NAME     R6W5 2
 '@BASEBOARD_FAB2_LIB.BASEBOARD_FAB2(SCH_1):PAGE247_I160@MSTR_DISCRETE.RES(CHIPS)':
 'B': CDS_PINID='B';
NODE_NAME     R6W8 1
 '@BASEBOARD_FAB2_LIB.BASEBOARD_FAB2(SCH_1):PAGE247_I163@MSTR_DISCRETE.RES(CHIPS)':
 'A': CDS_PINID='A';
NET_NAME
'PCA9555_A2'
 '@BASEBOARD_FAB2_LIB.BASEBOARD_FAB2(SCH_1):PCA9555_A2':
 C_SIGNAL='@baseboard_fab2_lib.baseboard_fab2(sch_1):pca9555_a2';
NODE_NAME     U6W1 3
 '@BASEBOARD_FAB2_LIB.BASEBOARD_FAB2(SCH_1):PAGE247_I120@W_HDL.TCA9555PWR-GP(CHIPS)':
 'A2': CDS_PINID='A2';
NODE_NAME     R6W4 2
 '@BASEBOARD_FAB2_LIB.BASEBOARD_FAB2(SCH_1):PAGE247_I159@MSTR_DISCRETE.RES(CHIPS)':
 'B': CDS_PINID='B';
NODE_NAME     R6W7 1
 '@BASEBOARD_FAB2_LIB.BASEBOARD_FAB2(SCH_1):PAGE247_I164@MSTR_DISCRETE.RES(CHIPS)':
 'A': CDS_PINID='A';
NET_NAME
'PCA9555_INT_N'
 '@BASEBOARD_FAB2_LIB.BASEBOARD_FAB2(SCH_1):PCA9555_INT_N':
 C_SIGNAL='@baseboard_fab2_lib.baseboard_fab2(sch_1):pca9555_int_n';
NODE_NAME     R6W10 2
 '@BASEBOARD_FAB2_LIB.BASEBOARD_FAB2(SCH_1):PAGE247_I1@MSTR_DISCRETE.RES(CHIPS)':
 'B': CDS_PINID='B';
NODE_NAME     U6W1 1
 '@BASEBOARD_FAB2_LIB.BASEBOARD_FAB2(SCH_1):PAGE247_I120@W_HDL.TCA9555PWR-GP(CHIPS)':
 'INT#': CDS_PINID='\int#\';
NET_NAME
'PD_ADCREXT'
 '@BASEBOARD_FAB2_LIB.BASEBOARD_FAB2(SCH_1):PD_ADCREXT':
 C_SIGNAL='@baseboard_fab2_lib.baseboard_fab2(sch_1):pd_adcrext';
NODE_NAME     U25W4 J1
 '@BASEBOARD_FAB2_LIB.BASEBOARD_FAB2(SCH_1):PAGE147_I106@W_HDL.AST2520A1-GP-GP(CHIPS)':
 'ADCREXT': CDS_PINID='ADCREXT';
NODE_NAME     R25W57 1
 '@BASEBOARD_FAB2_LIB.BASEBOARD_FAB2(SCH_1):PAGE147_I151@MSTR_DISCRETE.RES(CHIPS)':
 'A': CDS_PINID='A';
NET_NAME
'PD_CKMNG_OE'
 '@BASEBOARD_FAB2_LIB.BASEBOARD_FAB2(SCH_1):PD_CKMNG_OE':
 C_SIGNAL='@baseboard_fab2_lib.baseboard_fab2(sch_1):pd_ckmng_oe';
NODE_NAME     EU8F2 5
 '@BASEBOARD_FAB2_LIB.BASEBOARD_FAB2(SCH_1):PAGE101_I34@MSTR_CLOCK.ICS9FGP204(CHIPS)':
 'OE_96': CDS_PINID='OE_96';
NODE_NAME     EU8F2 6
 '@BASEBOARD_FAB2_LIB.BASEBOARD_FAB2(SCH_1):PAGE101_I34@MSTR_CLOCK.ICS9FGP204(CHIPS)':
 'OE_CPU': CDS_PINID='OE_CPU';
NODE_NAME     R2T25 1
 '@BASEBOARD_FAB2_LIB.BASEBOARD_FAB2(SCH_1):PAGE101_I48@MSTR_DISCRETE.RES(CHIPS)':
 'A': CDS_PINID='A';
NET_NAME
'PD_CPU0_BIST_ENABLE'
 '@BASEBOARD_FAB2_LIB.BASEBOARD_FAB2(SCH_1):PD_CPU0_BIST_ENABLE':
 C_SIGNAL='@baseboard_fab2_lib.baseboard_fab2(sch_1):pd_cpu0_bist_enable';
NODE_NAME     U5D1 BA20
 '@BASEBOARD_FAB2_LIB.BASEBOARD_FAB2(SCH_1):PAGE21_I259@CHPSET_LIB.SKX_EXT_B(CHIPS)':
 'BIST_ENABLE': CDS_PINID='BIST_ENABLE';
NODE_NAME     R4P1 2
 '@BASEBOARD_FAB2_LIB.BASEBOARD_FAB2(SCH_1):PAGE90_I98@MSTR_DISCRETE.RES(CHIPS)':
 'B': CDS_PINID='B';
NET_NAME
'PD_CPU0_DMIMODE_OVERRIDE'
 '@BASEBOARD_FAB2_LIB.BASEBOARD_FAB2(SCH_1):PD_CPU0_DMIMODE_OVERRIDE':
 C_SIGNAL='@baseboard_fab2_lib.baseboard_fab2(sch_1):pd_cpu0_dmimode_override';
NODE_NAME     U5D1 AW12
 '@BASEBOARD_FAB2_LIB.BASEBOARD_FAB2(SCH_1):PAGE22_I204@CHPSET_LIB.SKX_EXT_B(CHIPS)':
 'DMIMODE_OVERRIDE': CDS_PINID='DMIMODE_OVERRIDE';
NODE_NAME     R4P6 2
 '@BASEBOARD_FAB2_LIB.BASEBOARD_FAB2(SCH_1):PAGE90_I68@MSTR_DISCRETE.RES(CHIPS)':
 'B': CDS_PINID='B';
NET_NAME
'PD_CPU0_EAR_N'
 '@BASEBOARD_FAB2_LIB.BASEBOARD_FAB2(SCH_1):PD_CPU0_EAR_N':
 C_SIGNAL='@baseboard_fab2_lib.baseboard_fab2(sch_1):pd_cpu0_ear_n';
NODE_NAME     U5D1 AJ14
 '@BASEBOARD_FAB2_LIB.BASEBOARD_FAB2(SCH_1):PAGE21_I259@CHPSET_LIB.SKX_EXT_B(CHIPS)':
 'EAR_N': CDS_PINID='EAR_N';
NODE_NAME     R6D14 2
 '@BASEBOARD_FAB2_LIB.BASEBOARD_FAB2(SCH_1):PAGE90_I52@MSTR_DISCRETE.RES(CHIPS)':
 'B': CDS_PINID='B';
NET_NAME
'PD_CPU0_KSFC_DIS'
 '@BASEBOARD_FAB2_LIB.BASEBOARD_FAB2(SCH_1):PD_CPU0_KSFC_DIS':
 C_SIGNAL='@baseboard_fab2_lib.baseboard_fab2(sch_1):pd_cpu0_ksfc_dis';
NODE_NAME     U5D1 AW14
 '@BASEBOARD_FAB2_LIB.BASEBOARD_FAB2(SCH_1):PAGE21_I259@CHPSET_LIB.SKX_EXT_B(CHIPS)':
 'TEST_15': CDS_PINID='TEST_15';
NODE_NAME     R4P7 2
 '@BASEBOARD_FAB2_LIB.BASEBOARD_FAB2(SCH_1):PAGE90_I72@MSTR_DISCRETE.RES(CHIPS)':
 'B': CDS_PINID='B';
NET_NAME
'PD_CPU0_MCP01_DMON'
 '@BASEBOARD_FAB2_LIB.BASEBOARD_FAB2(SCH_1):PD_CPU0_MCP01_DMON':
 C_SIGNAL='@baseboard_fab2_lib.baseboard_fab2(sch_1):pd_cpu0_mcp01_dmon';
NODE_NAME     U5D1 CN28
 '@BASEBOARD_FAB2_LIB.BASEBOARD_FAB2(SCH_1):PAGE39_I127@CHPSET_LIB.SKX_EXT_B(CHIPS)':
 'RSVD'<75>: CDS_PINID='RSVD(75)';
NODE_NAME     R4P5 2
 '@BASEBOARD_FAB2_LIB.BASEBOARD_FAB2(SCH_1):PAGE97_I80@MSTR_DISCRETE.RES(CHIPS)':
 'B': CDS_PINID='B';
NET_NAME
'PD_CPU0_RSVD_TEST_1'
 '@BASEBOARD_FAB2_LIB.BASEBOARD_FAB2(SCH_1):PD_CPU0_RSVD_TEST_1':
 C_SIGNAL='@baseboard_fab2_lib.baseboard_fab2(sch_1):pd_cpu0_rsvd_test_1';
NODE_NAME     R5R1 1
 '@BASEBOARD_FAB2_LIB.BASEBOARD_FAB2(SCH_1):PAGE22_I188@MSTR_DISCRETE.RES(CHIPS)':
 'A': CDS_PINID='A';
NODE_NAME     U5D1 AF45
 '@BASEBOARD_FAB2_LIB.BASEBOARD_FAB2(SCH_1):PAGE22_I204@CHPSET_LIB.SKX_EXT_B(CHIPS)':
 'TEST_1': CDS_PINID='TEST_1';
NET_NAME
'PD_CPU0_RSVD_TEST_2'
 '@BASEBOARD_FAB2_LIB.BASEBOARD_FAB2(SCH_1):PD_CPU0_RSVD_TEST_2':
 C_SIGNAL='@baseboard_fab2_lib.baseboard_fab2(sch_1):pd_cpu0_rsvd_test_2';
NODE_NAME     R5P4 1
 '@BASEBOARD_FAB2_LIB.BASEBOARD_FAB2(SCH_1):PAGE22_I190@MSTR_DISCRETE.RES(CHIPS)':
 'A': CDS_PINID='A';
NODE_NAME     U5D1 AG46
 '@BASEBOARD_FAB2_LIB.BASEBOARD_FAB2(SCH_1):PAGE22_I204@CHPSET_LIB.SKX_EXT_B(CHIPS)':
 'TEST_2': CDS_PINID='TEST_2';
NET_NAME
'PD_CPU0_TEST12'
 '@BASEBOARD_FAB2_LIB.BASEBOARD_FAB2(SCH_1):PD_CPU0_TEST12':
 C_SIGNAL='@baseboard_fab2_lib.baseboard_fab2(sch_1):pd_cpu0_test12';
NODE_NAME     U5D1 AY19
 '@BASEBOARD_FAB2_LIB.BASEBOARD_FAB2(SCH_1):PAGE21_I259@CHPSET_LIB.SKX_EXT_B(CHIPS)':
 'TEST_12': CDS_PINID='TEST_12';
NODE_NAME     R6D5 1
 '@BASEBOARD_FAB2_LIB.BASEBOARD_FAB2(SCH_1):PAGE90_I81@MSTR_DISCRETE.RES(CHIPS)':
 'A': CDS_PINID='A';
NET_NAME
'PD_CPU0_TEST13'
 '@BASEBOARD_FAB2_LIB.BASEBOARD_FAB2(SCH_1):PD_CPU0_TEST13':
 C_SIGNAL='@baseboard_fab2_lib.baseboard_fab2(sch_1):pd_cpu0_test13';
NODE_NAME     U5D1 DB51
 '@BASEBOARD_FAB2_LIB.BASEBOARD_FAB2(SCH_1):PAGE21_I259@CHPSET_LIB.SKX_EXT_B(CHIPS)':
 'TEST_13': CDS_PINID='TEST_13';
NODE_NAME     R5P3 1
 '@BASEBOARD_FAB2_LIB.BASEBOARD_FAB2(SCH_1):PAGE90_I80@MSTR_DISCRETE.RES(CHIPS)':
 'A': CDS_PINID='A';
NET_NAME
'PD_CPU0_TEST14'
 '@BASEBOARD_FAB2_LIB.BASEBOARD_FAB2(SCH_1):PD_CPU0_TEST14':
 C_SIGNAL='@baseboard_fab2_lib.baseboard_fab2(sch_1):pd_cpu0_test14';
NODE_NAME     U5D1 DC50
 '@BASEBOARD_FAB2_LIB.BASEBOARD_FAB2(SCH_1):PAGE21_I259@CHPSET_LIB.SKX_EXT_B(CHIPS)':
 'TEST_14': CDS_PINID='TEST_14';
NODE_NAME     R5P2 1
 '@BASEBOARD_FAB2_LIB.BASEBOARD_FAB2(SCH_1):PAGE90_I79@MSTR_DISCRETE.RES(CHIPS)':
 'A': CDS_PINID='A';
NET_NAME
'PD_CPU0_TXT_PLTEN'
 '@BASEBOARD_FAB2_LIB.BASEBOARD_FAB2(SCH_1):PD_CPU0_TXT_PLTEN':
 C_SIGNAL='@baseboard_fab2_lib.baseboard_fab2(sch_1):pd_cpu0_txt_plten';
NODE_NAME     U5D1 AV15
 '@BASEBOARD_FAB2_LIB.BASEBOARD_FAB2(SCH_1):PAGE21_I259@CHPSET_LIB.SKX_EXT_B(CHIPS)':
 'TXT_PLTEN': CDS_PINID='TXT_PLTEN';
NODE_NAME     R6D6 2
 '@BASEBOARD_FAB2_LIB.BASEBOARD_FAB2(SCH_1):PAGE90_I101@MSTR_DISCRETE.RES(CHIPS)':
 'B': CDS_PINID='B';
NET_NAME
'PD_CPU1_BIST_ENABLE'
 '@BASEBOARD_FAB2_LIB.BASEBOARD_FAB2(SCH_1):PD_CPU1_BIST_ENABLE':
 C_SIGNAL='@baseboard_fab2_lib.baseboard_fab2(sch_1):pd_cpu1_bist_enable';
NODE_NAME     U2D1 BA20
 '@BASEBOARD_FAB2_LIB.BASEBOARD_FAB2(SCH_1):PAGE55_I172@CHPSET_LIB.SKX_EXT_B(CHIPS)':
 'BIST_ENABLE': CDS_PINID='BIST_ENABLE';
NODE_NAME     R3D13 2
 '@BASEBOARD_FAB2_LIB.BASEBOARD_FAB2(SCH_1):PAGE90_I99@MSTR_DISCRETE.RES(CHIPS)':
 'B': CDS_PINID='B';
NET_NAME
'PD_CPU1_DMIMODE_OVERRIDE'
 '@BASEBOARD_FAB2_LIB.BASEBOARD_FAB2(SCH_1):PD_CPU1_DMIMODE_OVERRIDE':
 C_SIGNAL='@baseboard_fab2_lib.baseboard_fab2(sch_1):pd_cpu1_dmimode_override';
NODE_NAME     U2D1 AW12
 '@BASEBOARD_FAB2_LIB.BASEBOARD_FAB2(SCH_1):PAGE56_I169@CHPSET_LIB.SKX_EXT_B(CHIPS)':
 'DMIMODE_OVERRIDE': CDS_PINID='DMIMODE_OVERRIDE';
NODE_NAME     R7P14 2
 '@BASEBOARD_FAB2_LIB.BASEBOARD_FAB2(SCH_1):PAGE90_I100@MSTR_DISCRETE.RES(CHIPS)':
 'B': CDS_PINID='B';
NET_NAME
'PD_CPU1_EAR_N'
 '@BASEBOARD_FAB2_LIB.BASEBOARD_FAB2(SCH_1):PD_CPU1_EAR_N':
 C_SIGNAL='@baseboard_fab2_lib.baseboard_fab2(sch_1):pd_cpu1_ear_n';
NODE_NAME     U2D1 AJ14
 '@BASEBOARD_FAB2_LIB.BASEBOARD_FAB2(SCH_1):PAGE55_I172@CHPSET_LIB.SKX_EXT_B(CHIPS)':
 'EAR_N': CDS_PINID='EAR_N';
NODE_NAME     R3D25 2
 '@BASEBOARD_FAB2_LIB.BASEBOARD_FAB2(SCH_1):PAGE90_I66@MSTR_DISCRETE.RES(CHIPS)':
 'B': CDS_PINID='B';
NET_NAME
'PD_CPU1_KSFC_DIS'
 '@BASEBOARD_FAB2_LIB.BASEBOARD_FAB2(SCH_1):PD_CPU1_KSFC_DIS':
 C_SIGNAL='@baseboard_fab2_lib.baseboard_fab2(sch_1):pd_cpu1_ksfc_dis';
NODE_NAME     U2D1 AW14
 '@BASEBOARD_FAB2_LIB.BASEBOARD_FAB2(SCH_1):PAGE55_I172@CHPSET_LIB.SKX_EXT_B(CHIPS)':
 'TEST_15': CDS_PINID='TEST_15';
NODE_NAME     R7P15 2
 '@BASEBOARD_FAB2_LIB.BASEBOARD_FAB2(SCH_1):PAGE90_I74@MSTR_DISCRETE.RES(CHIPS)':
 'B': CDS_PINID='B';
NET_NAME
'PD_CPU1_MCP01_DMON'
 '@BASEBOARD_FAB2_LIB.BASEBOARD_FAB2(SCH_1):PD_CPU1_MCP01_DMON':
 C_SIGNAL='@baseboard_fab2_lib.baseboard_fab2(sch_1):pd_cpu1_mcp01_dmon';
NODE_NAME     U2D1 CN28
 '@BASEBOARD_FAB2_LIB.BASEBOARD_FAB2(SCH_1):PAGE73_I107@CHPSET_LIB.SKX_EXT_B(CHIPS)':
 'RSVD'<75>: CDS_PINID='RSVD(75)';
NODE_NAME     R7P13 2
 '@BASEBOARD_FAB2_LIB.BASEBOARD_FAB2(SCH_1):PAGE97_I81@MSTR_DISCRETE.RES(CHIPS)':
 'B': CDS_PINID='B';
NET_NAME
'PD_CPU1_RSVD_TEST_1'
 '@BASEBOARD_FAB2_LIB.BASEBOARD_FAB2(SCH_1):PD_CPU1_RSVD_TEST_1':
 C_SIGNAL='@baseboard_fab2_lib.baseboard_fab2(sch_1):pd_cpu1_rsvd_test_1';
NODE_NAME     U2D1 AF45
 '@BASEBOARD_FAB2_LIB.BASEBOARD_FAB2(SCH_1):PAGE56_I169@CHPSET_LIB.SKX_EXT_B(CHIPS)':
 'TEST_1': CDS_PINID='TEST_1';
NODE_NAME     R8R1 1
 '@BASEBOARD_FAB2_LIB.BASEBOARD_FAB2(SCH_1):PAGE56_I174@MSTR_DISCRETE.RES(CHIPS)':
 'A': CDS_PINID='A';
NET_NAME
'PD_CPU1_RSVD_TEST_2'
 '@BASEBOARD_FAB2_LIB.BASEBOARD_FAB2(SCH_1):PD_CPU1_RSVD_TEST_2':
 C_SIGNAL='@baseboard_fab2_lib.baseboard_fab2(sch_1):pd_cpu1_rsvd_test_2';
NODE_NAME     U2D1 AG46
 '@BASEBOARD_FAB2_LIB.BASEBOARD_FAB2(SCH_1):PAGE56_I169@CHPSET_LIB.SKX_EXT_B(CHIPS)':
 'TEST_2': CDS_PINID='TEST_2';
NODE_NAME     R8P3 1
 '@BASEBOARD_FAB2_LIB.BASEBOARD_FAB2(SCH_1):PAGE56_I173@MSTR_DISCRETE.RES(CHIPS)':
 'A': CDS_PINID='A';
NET_NAME
'PD_CPU1_TEST12'
 '@BASEBOARD_FAB2_LIB.BASEBOARD_FAB2(SCH_1):PD_CPU1_TEST12':
 C_SIGNAL='@baseboard_fab2_lib.baseboard_fab2(sch_1):pd_cpu1_test12';
NODE_NAME     U2D1 AY19
 '@BASEBOARD_FAB2_LIB.BASEBOARD_FAB2(SCH_1):PAGE55_I172@CHPSET_LIB.SKX_EXT_B(CHIPS)':
 'TEST_12': CDS_PINID='TEST_12';
NODE_NAME     R3D9 1
 '@BASEBOARD_FAB2_LIB.BASEBOARD_FAB2(SCH_1):PAGE90_I88@MSTR_DISCRETE.RES(CHIPS)':
 'A': CDS_PINID='A';
NET_NAME
'PD_CPU1_TEST13'
 '@BASEBOARD_FAB2_LIB.BASEBOARD_FAB2(SCH_1):PD_CPU1_TEST13':
 C_SIGNAL='@baseboard_fab2_lib.baseboard_fab2(sch_1):pd_cpu1_test13';
NODE_NAME     U2D1 DB51
 '@BASEBOARD_FAB2_LIB.BASEBOARD_FAB2(SCH_1):PAGE55_I172@CHPSET_LIB.SKX_EXT_B(CHIPS)':
 'TEST_13': CDS_PINID='TEST_13';
NODE_NAME     R8P2 1
 '@BASEBOARD_FAB2_LIB.BASEBOARD_FAB2(SCH_1):PAGE90_I86@MSTR_DISCRETE.RES(CHIPS)':
 'A': CDS_PINID='A';
NET_NAME
'PD_CPU1_TEST14'
 '@BASEBOARD_FAB2_LIB.BASEBOARD_FAB2(SCH_1):PD_CPU1_TEST14':
 C_SIGNAL='@baseboard_fab2_lib.baseboard_fab2(sch_1):pd_cpu1_test14';
NODE_NAME     U2D1 DC50
 '@BASEBOARD_FAB2_LIB.BASEBOARD_FAB2(SCH_1):PAGE55_I172@CHPSET_LIB.SKX_EXT_B(CHIPS)':
 'TEST_14': CDS_PINID='TEST_14';
NODE_NAME     R8P1 1
 '@BASEBOARD_FAB2_LIB.BASEBOARD_FAB2(SCH_1):PAGE90_I85@MSTR_DISCRETE.RES(CHIPS)':
 'A': CDS_PINID='A';
NET_NAME
'PD_CPU1_TXT_PLTEN'
 '@BASEBOARD_FAB2_LIB.BASEBOARD_FAB2(SCH_1):PD_CPU1_TXT_PLTEN':
 C_SIGNAL='@baseboard_fab2_lib.baseboard_fab2(sch_1):pd_cpu1_txt_plten';
NODE_NAME     U2D1 AV15
 '@BASEBOARD_FAB2_LIB.BASEBOARD_FAB2(SCH_1):PAGE55_I172@CHPSET_LIB.SKX_EXT_B(CHIPS)':
 'TXT_PLTEN': CDS_PINID='TXT_PLTEN';
NODE_NAME     R3D12 2
 '@BASEBOARD_FAB2_LIB.BASEBOARD_FAB2(SCH_1):PAGE90_I102@MSTR_DISCRETE.RES(CHIPS)':
 'B': CDS_PINID='B';
NET_NAME
'PD_DIR_2'
 '@BASEBOARD_FAB2_LIB.BASEBOARD_FAB2(SCH_1):PD_DIR_2':
 C_SIGNAL='@baseboard_fab2_lib.baseboard_fab2(sch_1):pd_dir_2';
NODE_NAME     U9G1 1
 '@BASEBOARD_FAB2_LIB.BASEBOARD_FAB2(SCH_1):PAGE152_I1@MSTR_DIGITAL.GTL2014(CHIPS)':
 'DIR': CDS_PINID='DIR';
NODE_NAME     R1U30 1
 '@BASEBOARD_FAB2_LIB.BASEBOARD_FAB2(SCH_1):PAGE152_I2@MSTR_DISCRETE.RES(CHIPS)':
 'A': CDS_PINID='A';
NET_NAME
'PD_FRU_WP'
 '@BASEBOARD_FAB2_LIB.BASEBOARD_FAB2(SCH_1):PD_FRU_WP':
 C_SIGNAL='@baseboard_fab2_lib.baseboard_fab2(sch_1):pd_fru_wp';
NODE_NAME     U8D4 7
 '@BASEBOARD_FAB2_LIB.BASEBOARD_FAB2(SCH_1):PAGE167_I49@MSTR_MEMORY.AT24C64(CHIPS)':
 'WP': CDS_PINID='WP';
NODE_NAME     R8D27 1
 '@BASEBOARD_FAB2_LIB.BASEBOARD_FAB2(SCH_1):PAGE167_I50@MSTR_DISCRETE.RES(CHIPS)':
 'A': CDS_PINID='A';
NET_NAME
'PD_GTL2014_1_VREF'
 '@BASEBOARD_FAB2_LIB.BASEBOARD_FAB2(SCH_1):PD_GTL2014_1_VREF':
 C_SIGNAL='@baseboard_fab2_lib.baseboard_fab2(sch_1):pd_gtl2014_1_vref';
NODE_NAME     U3P1 4
 '@BASEBOARD_FAB2_LIB.BASEBOARD_FAB2(SCH_1):PAGE96_I42@MSTR_DIGITAL.GTL2014(CHIPS)':
 'VREF': CDS_PINID='VREF';
NODE_NAME     R3P32 2
 '@BASEBOARD_FAB2_LIB.BASEBOARD_FAB2(SCH_1):PAGE96_I71@MSTR_DISCRETE.RES(CHIPS)':
 'B': CDS_PINID='B';
NET_NAME
'PD_GTL2014_2_VREF'
 '@BASEBOARD_FAB2_LIB.BASEBOARD_FAB2(SCH_1):PD_GTL2014_2_VREF':
 C_SIGNAL='@baseboard_fab2_lib.baseboard_fab2(sch_1):pd_gtl2014_2_vref';
NODE_NAME     U4C2 4
 '@BASEBOARD_FAB2_LIB.BASEBOARD_FAB2(SCH_1):PAGE96_I46@MSTR_DIGITAL.GTL2014(CHIPS)':
 'VREF': CDS_PINID='VREF';
NODE_NAME     R4C9 2
 '@BASEBOARD_FAB2_LIB.BASEBOARD_FAB2(SCH_1):PAGE96_I69@MSTR_DISCRETE.RES(CHIPS)':
 'B': CDS_PINID='B';
NET_NAME
'PD_GTL2014_3_VREF'
 '@BASEBOARD_FAB2_LIB.BASEBOARD_FAB2(SCH_1):PD_GTL2014_3_VREF':
 C_SIGNAL='@baseboard_fab2_lib.baseboard_fab2(sch_1):pd_gtl2014_3_vref';
NODE_NAME     R25W159 2
 '@BASEBOARD_FAB2_LIB.BASEBOARD_FAB2(SCH_1):PAGE269_I24@MSTR_DISCRETE.RES(CHIPS)':
 'B': CDS_PINID='B';
NODE_NAME     U25W10 4
 '@BASEBOARD_FAB2_LIB.BASEBOARD_FAB2(SCH_1):PAGE269_I49@MSTR_DIGITAL.GTL2014(CHIPS)':
 'VREF': CDS_PINID='VREF';
NET_NAME
'PD_GTL2014_6_B0'
 '@BASEBOARD_FAB2_LIB.BASEBOARD_FAB2(SCH_1):PD_GTL2014_6_B0':
 C_SIGNAL='@baseboard_fab2_lib.baseboard_fab2(sch_1):pd_gtl2014_6_b0';
NODE_NAME     R25W175 1
 '@BASEBOARD_FAB2_LIB.BASEBOARD_FAB2(SCH_1):PAGE268_I17@MSTR_DISCRETE.RES(CHIPS)':
 'A': CDS_PINID='A';
NODE_NAME     U25W11 2
 '@BASEBOARD_FAB2_LIB.BASEBOARD_FAB2(SCH_1):PAGE268_I33@MSTR_DIGITAL.GTL2014(CHIPS)':
 'B0': CDS_PINID='B0';
NET_NAME
'PD_GTL2014_6_B2'
 '@BASEBOARD_FAB2_LIB.BASEBOARD_FAB2(SCH_1):PD_GTL2014_6_B2':
 C_SIGNAL='@baseboard_fab2_lib.baseboard_fab2(sch_1):pd_gtl2014_6_b2';
NODE_NAME     R25W176 1
 '@BASEBOARD_FAB2_LIB.BASEBOARD_FAB2(SCH_1):PAGE268_I14@MSTR_DISCRETE.RES(CHIPS)':
 'A': CDS_PINID='A';
NODE_NAME     U25W11 5
 '@BASEBOARD_FAB2_LIB.BASEBOARD_FAB2(SCH_1):PAGE268_I33@MSTR_DIGITAL.GTL2014(CHIPS)':
 'B2': CDS_PINID='B2';
NET_NAME
'PD_GTL2014_DIR_6'
 '@BASEBOARD_FAB2_LIB.BASEBOARD_FAB2(SCH_1):PD_GTL2014_DIR_6':
 C_SIGNAL='@baseboard_fab2_lib.baseboard_fab2(sch_1):pd_gtl2014_dir_6';
NODE_NAME     R25W166 1
 '@BASEBOARD_FAB2_LIB.BASEBOARD_FAB2(SCH_1):PAGE268_I26@MSTR_DISCRETE.RES(CHIPS)':
 'A': CDS_PINID='A';
NODE_NAME     U25W11 1
 '@BASEBOARD_FAB2_LIB.BASEBOARD_FAB2(SCH_1):PAGE268_I33@MSTR_DIGITAL.GTL2014(CHIPS)':
 'DIR': CDS_PINID='DIR';
NET_NAME
'PD_GTL2104_4_DIR'
 '@BASEBOARD_FAB2_LIB.BASEBOARD_FAB2(SCH_1):PD_GTL2104_4_DIR':
 C_SIGNAL='@baseboard_fab2_lib.baseboard_fab2(sch_1):pd_gtl2104_4_dir';
NODE_NAME     U2T4 1
 '@BASEBOARD_FAB2_LIB.BASEBOARD_FAB2(SCH_1):PAGE93_I30@MSTR_DIGITAL.GTL2014(CHIPS)':
 'DIR': CDS_PINID='DIR';
NODE_NAME     R2T50 1
 '@BASEBOARD_FAB2_LIB.BASEBOARD_FAB2(SCH_1):PAGE93_I127@MSTR_DISCRETE.RES(CHIPS)':
 'A': CDS_PINID='A';
NET_NAME
'PD_GTL2104_DIR_0'
 '@BASEBOARD_FAB2_LIB.BASEBOARD_FAB2(SCH_1):PD_GTL2104_DIR_0':
 C_SIGNAL='@baseboard_fab2_lib.baseboard_fab2(sch_1):pd_gtl2104_dir_0';
NODE_NAME     U7D2 1
 '@BASEBOARD_FAB2_LIB.BASEBOARD_FAB2(SCH_1):PAGE92_I32@MSTR_DIGITAL.GTL2014(CHIPS)':
 'DIR': CDS_PINID='DIR';
NODE_NAME     R7D26 1
 '@BASEBOARD_FAB2_LIB.BASEBOARD_FAB2(SCH_1):PAGE92_I54@MSTR_DISCRETE.RES(CHIPS)':
 'A': CDS_PINID='A';
NET_NAME
'PD_GTL2104_DIR_1'
 '@BASEBOARD_FAB2_LIB.BASEBOARD_FAB2(SCH_1):PD_GTL2104_DIR_1':
 C_SIGNAL='@baseboard_fab2_lib.baseboard_fab2(sch_1):pd_gtl2104_dir_1';
NODE_NAME     U3P2 1
 '@BASEBOARD_FAB2_LIB.BASEBOARD_FAB2(SCH_1):PAGE92_I1@MSTR_DIGITAL.GTL2014(CHIPS)':
 'DIR': CDS_PINID='DIR';
NODE_NAME     R3R1 1
 '@BASEBOARD_FAB2_LIB.BASEBOARD_FAB2(SCH_1):PAGE92_I46@MSTR_DISCRETE.RES(CHIPS)':
 'A': CDS_PINID='A';
NET_NAME
'PD_HSC_RETRY_N'
 '@BASEBOARD_FAB2_LIB.BASEBOARD_FAB2(SCH_1):PD_HSC_RETRY_N':
 C_SIGNAL='@baseboard_fab2_lib.baseboard_fab2(sch_1):pd_hsc_retry_n';
NODE_NAME     EU1D2 17
 '@BASEBOARD_FAB2_LIB.BASEBOARD_FAB2(SCH_1):PAGE199_I10@MSTR_CONTROLLER.ADM1278(CHIPS)':
 'RETRY_N': CDS_PINID='RETRY_N';
NODE_NAME     R1D28 1
 '@BASEBOARD_FAB2_LIB.BASEBOARD_FAB2(SCH_1):PAGE199_I26@MSTR_DISCRETE.RES(CHIPS)':
 'A': CDS_PINID='A';
NET_NAME
'PD_ID_EEPROM_WP'
 '@BASEBOARD_FAB2_LIB.BASEBOARD_FAB2(SCH_1):PD_ID_EEPROM_WP':
 C_SIGNAL='@baseboard_fab2_lib.baseboard_fab2(sch_1):pd_id_eeprom_wp';
NODE_NAME     U6W3 7
 '@BASEBOARD_FAB2_LIB.BASEBOARD_FAB2(SCH_1):PAGE247_I89@MSTR_MEMORY.AT24C64(CHIPS)':
 'WP': CDS_PINID='WP';
NODE_NAME     R6W23 1
 '@BASEBOARD_FAB2_LIB.BASEBOARD_FAB2(SCH_1):PAGE247_I92@MSTR_DISCRETE.RES(CHIPS)':
 'A': CDS_PINID='A';
NET_NAME
'PD_IE_DEBUG_MODE'
 '@BASEBOARD_FAB2_LIB.BASEBOARD_FAB2(SCH_1):PD_IE_DEBUG_MODE':
 C_SIGNAL='@baseboard_fab2_lib.baseboard_fab2(sch_1):pd_ie_debug_mode';
NODE_NAME     R1U64 1
 '@BASEBOARD_FAB2_LIB.BASEBOARD_FAB2(SCH_1):PAGE137_I69@MSTR_DISCRETE.RES(CHIPS)':
 'A': CDS_PINID='A';
NODE_NAME     J9G1 11
 '@BASEBOARD_FAB2_LIB.BASEBOARD_FAB2(SCH_1):PAGE137_I128@MSTR_CONN.CONN12_C73564003(CHIPS)':
 'IO11': CDS_PINID='IO11';
NET_NAME
'PD_ME_RCVR_N'
 '@BASEBOARD_FAB2_LIB.BASEBOARD_FAB2(SCH_1):PD_ME_RCVR_N':
 C_SIGNAL='@baseboard_fab2_lib.baseboard_fab2(sch_1):pd_me_rcvr_n';
NODE_NAME     R7G28 1
 '@BASEBOARD_FAB2_LIB.BASEBOARD_FAB2(SCH_1):PAGE136_I102@MSTR_DISCRETE.RES(CHIPS)':
 'A': CDS_PINID='A';
NODE_NAME     J7G3 5
 '@BASEBOARD_FAB2_LIB.BASEBOARD_FAB2(SCH_1):PAGE136_I174@MSTR_CONN.CONN12_C73564003(CHIPS)':
 'IO5': CDS_PINID='IO5';
NET_NAME
'PD_PASSWORD_CLEAR'
 '@BASEBOARD_FAB2_LIB.BASEBOARD_FAB2(SCH_1):PD_PASSWORD_CLEAR':
 C_SIGNAL='@baseboard_fab2_lib.baseboard_fab2(sch_1):pd_password_clear';
NODE_NAME     R7G29 1
 '@BASEBOARD_FAB2_LIB.BASEBOARD_FAB2(SCH_1):PAGE136_I148@MSTR_DISCRETE.RES(CHIPS)':
 'A': CDS_PINID='A';
NODE_NAME     J7G3 11
 '@BASEBOARD_FAB2_LIB.BASEBOARD_FAB2(SCH_1):PAGE136_I174@MSTR_CONN.CONN12_C73564003(CHIPS)':
 'IO11': CDS_PINID='IO11';
NET_NAME
'PD_PEREXT'
 '@BASEBOARD_FAB2_LIB.BASEBOARD_FAB2(SCH_1):PD_PEREXT':
 C_SIGNAL='@baseboard_fab2_lib.baseboard_fab2(sch_1):pd_perext';
NODE_NAME     U25W4 K20
 '@BASEBOARD_FAB2_LIB.BASEBOARD_FAB2(SCH_1):PAGE145_I117@W_HDL.AST2520A1-GP-GP(CHIPS)':
 'PEREXT': CDS_PINID='PEREXT';
NODE_NAME     R25W67 1
 '@BASEBOARD_FAB2_LIB.BASEBOARD_FAB2(SCH_1):PAGE145_I118@W_HDL.200R2F-L1-GP(CHIPS)':
 '1': CDS_PINID='\1\';
NET_NAME
'PD_PIROM_CPU0_ADDR0'
 '@BASEBOARD_FAB2_LIB.BASEBOARD_FAB2(SCH_1):PD_PIROM_CPU0_ADDR0':
 C_SIGNAL='@baseboard_fab2_lib.baseboard_fab2(sch_1):pd_pirom_cpu0_addr0';
NODE_NAME     U5D1 CU58
 '@BASEBOARD_FAB2_LIB.BASEBOARD_FAB2(SCH_1):PAGE21_I259@CHPSET_LIB.SKX_EXT_B(CHIPS)':
 'PIROM_ADDR'<0>: CDS_PINID='PIROM_ADDR(0)';
NODE_NAME     R6N14 2
 '@BASEBOARD_FAB2_LIB.BASEBOARD_FAB2(SCH_1):PAGE156_I302@MSTR_DISCRETE.RES(CHIPS)':
 'B': CDS_PINID='B';
NET_NAME
'PD_PIROM_CPU0_ADDR1'
 '@BASEBOARD_FAB2_LIB.BASEBOARD_FAB2(SCH_1):PD_PIROM_CPU0_ADDR1':
 C_SIGNAL='@baseboard_fab2_lib.baseboard_fab2(sch_1):pd_pirom_cpu0_addr1';
NODE_NAME     U5D1 CV57
 '@BASEBOARD_FAB2_LIB.BASEBOARD_FAB2(SCH_1):PAGE21_I259@CHPSET_LIB.SKX_EXT_B(CHIPS)':
 'PIROM_ADDR'<1>: CDS_PINID='PIROM_ADDR(1)';
NODE_NAME     R6N13 2
 '@BASEBOARD_FAB2_LIB.BASEBOARD_FAB2(SCH_1):PAGE156_I303@MSTR_DISCRETE.RES(CHIPS)':
 'B': CDS_PINID='B';
NET_NAME
'PD_PIROM_CPU0_ADDR2'
 '@BASEBOARD_FAB2_LIB.BASEBOARD_FAB2(SCH_1):PD_PIROM_CPU0_ADDR2':
 C_SIGNAL='@baseboard_fab2_lib.baseboard_fab2(sch_1):pd_pirom_cpu0_addr2';
NODE_NAME     U5D1 CW56
 '@BASEBOARD_FAB2_LIB.BASEBOARD_FAB2(SCH_1):PAGE21_I259@CHPSET_LIB.SKX_EXT_B(CHIPS)':
 'PIROM_ADDR'<2>: CDS_PINID='PIROM_ADDR(2)';
NODE_NAME     R6N15 2
 '@BASEBOARD_FAB2_LIB.BASEBOARD_FAB2(SCH_1):PAGE156_I304@MSTR_DISCRETE.RES(CHIPS)':
 'B': CDS_PINID='B';
NET_NAME
'PD_PIROM_CPU1_ADDR1'
 '@BASEBOARD_FAB2_LIB.BASEBOARD_FAB2(SCH_1):PD_PIROM_CPU1_ADDR1':
 C_SIGNAL='@baseboard_fab2_lib.baseboard_fab2(sch_1):pd_pirom_cpu1_addr1';
NODE_NAME     U2D1 CV57
 '@BASEBOARD_FAB2_LIB.BASEBOARD_FAB2(SCH_1):PAGE55_I172@CHPSET_LIB.SKX_EXT_B(CHIPS)':
 'PIROM_ADDR'<1>: CDS_PINID='PIROM_ADDR(1)';
NODE_NAME     R1C33 2
 '@BASEBOARD_FAB2_LIB.BASEBOARD_FAB2(SCH_1):PAGE156_I313@MSTR_DISCRETE.RES(CHIPS)':
 'B': CDS_PINID='B';
NET_NAME
'PD_PIROM_CPU1_ADDR2'
 '@BASEBOARD_FAB2_LIB.BASEBOARD_FAB2(SCH_1):PD_PIROM_CPU1_ADDR2':
 C_SIGNAL='@baseboard_fab2_lib.baseboard_fab2(sch_1):pd_pirom_cpu1_addr2';
NODE_NAME     U2D1 CW56
 '@BASEBOARD_FAB2_LIB.BASEBOARD_FAB2(SCH_1):PAGE55_I172@CHPSET_LIB.SKX_EXT_B(CHIPS)':
 'PIROM_ADDR'<2>: CDS_PINID='PIROM_ADDR(2)';
NODE_NAME     R1C32 2
 '@BASEBOARD_FAB2_LIB.BASEBOARD_FAB2(SCH_1):PAGE156_I312@MSTR_DISCRETE.RES(CHIPS)':
 'B': CDS_PINID='B';
NET_NAME
'PD_RST_RTCRST_N'
 '@BASEBOARD_FAB2_LIB.BASEBOARD_FAB2(SCH_1):PD_RST_RTCRST_N':
 C_SIGNAL='@baseboard_fab2_lib.baseboard_fab2(sch_1):pd_rst_rtcrst_n';
NODE_NAME     R1U63 1
 '@BASEBOARD_FAB2_LIB.BASEBOARD_FAB2(SCH_1):PAGE137_I15@MSTR_DISCRETE.RES(CHIPS)':
 'A': CDS_PINID='A';
NODE_NAME     J9G1 6
 '@BASEBOARD_FAB2_LIB.BASEBOARD_FAB2(SCH_1):PAGE137_I128@MSTR_CONN.CONN12_C73564003(CHIPS)':
 'IO6': CDS_PINID='IO6';
NET_NAME
'PD_SATA0_CONTROLLER_TYPE_R'
 '@BASEBOARD_FAB2_LIB.BASEBOARD_FAB2(SCH_1):PD_SATA0_CONTROLLER_TYPE_R':
 C_SIGNAL='@baseboard_fab2_lib.baseboard_fab2(sch_1):pd_sata0_controller_type_r';
NODE_NAME     J8A1 1D2
 '@BASEBOARD_FAB2_LIB.BASEBOARD_FAB2(SCH_1):PAGE173_I163@MSTR_CONN.CONN72_G97614002_A(CHIPS)':
 'SIDEBANDA_6': CDS_PINID='SIDEBANDA_6';
NODE_NAME     R2L18 1
 '@BASEBOARD_FAB2_LIB.BASEBOARD_FAB2(SCH_1):PAGE173_I266@MSTR_DISCRETE.RES(CHIPS)':
 'A': CDS_PINID='A';
NET_NAME
'PD_SATA1_CONTROLLER_TYPE_R'
 '@BASEBOARD_FAB2_LIB.BASEBOARD_FAB2(SCH_1):PD_SATA1_CONTROLLER_TYPE_R':
 C_SIGNAL='@baseboard_fab2_lib.baseboard_fab2(sch_1):pd_sata1_controller_type_r';
NODE_NAME     J8A1 2D2
 '@BASEBOARD_FAB2_LIB.BASEBOARD_FAB2(SCH_1):PAGE173_I163@MSTR_CONN.CONN72_G97614002_A(CHIPS)':
 'SIDEBANDB_6': CDS_PINID='SIDEBANDB_6';
NODE_NAME     R2L22 1
 '@BASEBOARD_FAB2_LIB.BASEBOARD_FAB2(SCH_1):PAGE173_I264@MSTR_DISCRETE.RES(CHIPS)':
 'A': CDS_PINID='A';
NET_NAME
'PD_SMB_M2_EN'
 '@BASEBOARD_FAB2_LIB.BASEBOARD_FAB2(SCH_1):PD_SMB_M2_EN':
 C_SIGNAL='@baseboard_fab2_lib.baseboard_fab2(sch_1):pd_smb_m2_en';
NODE_NAME     U32W1 5
 '@BASEBOARD_FAB2_LIB.BASEBOARD_FAB2(SCH_1):PAGE185_I191@W_HDL.TCA9517DGKR-GP(CHIPS)':
 'EN': CDS_PINID='EN';
NODE_NAME     R32W9 1
 '@BASEBOARD_FAB2_LIB.BASEBOARD_FAB2(SCH_1):PAGE185_I200@MSTR_DISCRETE.RES(CHIPS)':
 'A': CDS_PINID='A';
NODE_NAME     U32W2 5
 '@BASEBOARD_FAB2_LIB.BASEBOARD_FAB2(SCH_1):PAGE185_I204@W_HDL.TCA9517DGKR-GP(CHIPS)':
 'EN': CDS_PINID='EN';
NET_NAME
'PD_SPI_BMC_BT_CS0_N'
 '@BASEBOARD_FAB2_LIB.BASEBOARD_FAB2(SCH_1):PD_SPI_BMC_BT_CS0_N':
 C_SIGNAL='@baseboard_fab2_lib.baseboard_fab2(sch_1):pd_spi_bmc_bt_cs0_n';
NODE_NAME     J9G1 12
 '@BASEBOARD_FAB2_LIB.BASEBOARD_FAB2(SCH_1):PAGE137_I128@MSTR_CONN.CONN12_C73564003(CHIPS)':
 'IO12': CDS_PINID='IO12';
NODE_NAME     R25W94 2
 '@BASEBOARD_FAB2_LIB.BASEBOARD_FAB2(SCH_1):PAGE137_I140@MSTR_DISCRETE.RES(CHIPS)':
 'B': CDS_PINID='B';
NET_NAME
'PD_SPRV_RSET'
 '@BASEBOARD_FAB2_LIB.BASEBOARD_FAB2(SCH_1):PD_SPRV_RSET':
 C_SIGNAL='@baseboard_fab2_lib.baseboard_fab2(sch_1):pd_sprv_rset';
NODE_NAME     EU9E1 48
 '@BASEBOARD_FAB2_LIB.BASEBOARD_FAB2(SCH_1):PAGE139_I72@MSTR_INTEL.SPRINGVILLE(CHIPS)':
 'RSET': CDS_PINID='RSET';
NODE_NAME     R9E23 1
 '@BASEBOARD_FAB2_LIB.BASEBOARD_FAB2(SCH_1):PAGE139_I174@MSTR_DISCRETE.RES(CHIPS)':
 'A': CDS_PINID='A';
NET_NAME
'PD_SP_ENTEST'
 '@BASEBOARD_FAB2_LIB.BASEBOARD_FAB2(SCH_1):PD_SP_ENTEST':
 C_SIGNAL='@baseboard_fab2_lib.baseboard_fab2(sch_1):pd_sp_entest';
NODE_NAME     R1U7 2
 '@BASEBOARD_FAB2_LIB.BASEBOARD_FAB2(SCH_1):PAGE146_I78@MSTR_DISCRETE.RES(CHIPS)':
 'B': CDS_PINID='B';
NODE_NAME     U25W4 K3
 '@BASEBOARD_FAB2_LIB.BASEBOARD_FAB2(SCH_1):PAGE146_I105@W_HDL.AST2520A1-GP-GP(CHIPS)':
 'ENTEST': CDS_PINID='ENTEST';
NET_NAME
'PD_TMP421_1_A0'
 '@BASEBOARD_FAB2_LIB.BASEBOARD_FAB2(SCH_1):PD_TMP421_1_A0':
 C_SIGNAL='@baseboard_fab2_lib.baseboard_fab2(sch_1):pd_tmp421_1_a0';
NODE_NAME     U9B4 4
 '@BASEBOARD_FAB2_LIB.BASEBOARD_FAB2(SCH_1):PAGE167_I1@MSTR_ANALOG.TMP421(CHIPS)':
 'A'<0>: CDS_PINID='A(0)';
NODE_NAME     R9B8 1
 '@BASEBOARD_FAB2_LIB.BASEBOARD_FAB2(SCH_1):PAGE167_I10@MSTR_DISCRETE.RES(CHIPS)':
 'A': CDS_PINID='A';
NET_NAME
'PD_TMP421_2_A1'
 '@BASEBOARD_FAB2_LIB.BASEBOARD_FAB2(SCH_1):PD_TMP421_2_A1':
 C_SIGNAL='@baseboard_fab2_lib.baseboard_fab2(sch_1):pd_tmp421_2_a1';
NODE_NAME     U1E1 3
 '@BASEBOARD_FAB2_LIB.BASEBOARD_FAB2(SCH_1):PAGE167_I30@MSTR_ANALOG.TMP421(CHIPS)':
 'A'<1>: CDS_PINID='A(1)';
NODE_NAME     R1E10 2
 '@BASEBOARD_FAB2_LIB.BASEBOARD_FAB2(SCH_1):PAGE167_I38@MSTR_DISCRETE.RES(CHIPS)':
 'B': CDS_PINID='B';
NET_NAME
'PD_UV_HIGH_SET'
 '@BASEBOARD_FAB2_LIB.BASEBOARD_FAB2(SCH_1):PD_UV_HIGH_SET':
 C_SIGNAL='@baseboard_fab2_lib.baseboard_fab2(sch_1):pd_uv_high_set';
NODE_NAME     J9G1 5
 '@BASEBOARD_FAB2_LIB.BASEBOARD_FAB2(SCH_1):PAGE137_I128@MSTR_CONN.CONN12_C73564003(CHIPS)':
 'IO5': CDS_PINID='IO5';
NODE_NAME     R6W2 1
 '@BASEBOARD_FAB2_LIB.BASEBOARD_FAB2(SCH_1):PAGE137_I144@MSTR_DISCRETE.RES(CHIPS)':
 'A': CDS_PINID='A';
NET_NAME
'PECI_BMC'
 '@BASEBOARD_FAB2_LIB.BASEBOARD_FAB2(SCH_1):PECI_BMC':
 C_SIGNAL='@baseboard_fab2_lib.baseboard_fab2(sch_1):peci_bmc';
NODE_NAME     R7C17 2
 '@BASEBOARD_FAB2_LIB.BASEBOARD_FAB2(SCH_1):PAGE166_I28@MSTR_DISCRETE.RES(CHIPS)':
 'B': CDS_PINID='B';
NODE_NAME     R9F33 1
 '@BASEBOARD_FAB2_LIB.BASEBOARD_FAB2(SCH_1):PAGE145_I20@MSTR_DISCRETE.RES(CHIPS)':
 'A': CDS_PINID='A';
NODE_NAME     R9F20 1
 '@BASEBOARD_FAB2_LIB.BASEBOARD_FAB2(SCH_1):PAGE145_I22@MSTR_DISCRETE.RES(CHIPS)':
 'A': CDS_PINID='A';
NODE_NAME     U7W1 1
 '@BASEBOARD_FAB2_LIB.BASEBOARD_FAB2(SCH_1):PAGE166_I34@W_HDL.PI5A3157BC6E-GP(CHIPS)':
 'B1': CDS_PINID='B1';
NET_NAME
'PECI_BMC_R'
 '@BASEBOARD_FAB2_LIB.BASEBOARD_FAB2(SCH_1):PECI_BMC_R':
 C_SIGNAL='@baseboard_fab2_lib.baseboard_fab2(sch_1):peci_bmc_r';
NODE_NAME     R9F33 2
 '@BASEBOARD_FAB2_LIB.BASEBOARD_FAB2(SCH_1):PAGE145_I20@MSTR_DISCRETE.RES(CHIPS)':
 'B': CDS_PINID='B';
NODE_NAME     U25W4 AB18
 '@BASEBOARD_FAB2_LIB.BASEBOARD_FAB2(SCH_1):PAGE145_I117@W_HDL.AST2520A1-GP-GP(CHIPS)':
 'PECI': CDS_PINID='PECI';
NET_NAME
'PECI_CPU_G'
 '@BASEBOARD_FAB2_LIB.BASEBOARD_FAB2(SCH_1):PECI_CPU_G':
 C_SIGNAL='@baseboard_fab2_lib.baseboard_fab2(sch_1):peci_cpu_g';
NODE_NAME     U5D1 AU12
 '@BASEBOARD_FAB2_LIB.BASEBOARD_FAB2(SCH_1):PAGE21_I259@CHPSET_LIB.SKX_EXT_B(CHIPS)':
 'PECI': CDS_PINID='PECI';
NODE_NAME     U2D1 AU12
 '@BASEBOARD_FAB2_LIB.BASEBOARD_FAB2(SCH_1):PAGE55_I172@CHPSET_LIB.SKX_EXT_B(CHIPS)':
 'PECI': CDS_PINID='PECI';
NODE_NAME     U7W1 4
 '@BASEBOARD_FAB2_LIB.BASEBOARD_FAB2(SCH_1):PAGE166_I34@W_HDL.PI5A3157BC6E-GP(CHIPS)':
 'A': CDS_PINID='A';
NODE_NAME     R7W2 1
 '@BASEBOARD_FAB2_LIB.BASEBOARD_FAB2(SCH_1):PAGE166_I42@MSTR_DISCRETE.RES(CHIPS)':
 'A': CDS_PINID='A';
NET_NAME
'PECI_PCH'
 '@BASEBOARD_FAB2_LIB.BASEBOARD_FAB2(SCH_1):PECI_PCH':
 C_SIGNAL='@baseboard_fab2_lib.baseboard_fab2(sch_1):peci_pch';
NODE_NAME     U7C1 U9
 '@BASEBOARD_FAB2_LIB.BASEBOARD_FAB2(SCH_1):PAGE118_I73@MSTR_U_PROC.LBG_CORE_QAT_EXT_D(CHIPS)':
 'PECI': CDS_PINID='PECI';
NODE_NAME     R7D15 1
 '@BASEBOARD_FAB2_LIB.BASEBOARD_FAB2(SCH_1):PAGE166_I32@MSTR_DISCRETE.RES(CHIPS)':
 'A': CDS_PINID='A';
NODE_NAME     U7W1 3
 '@BASEBOARD_FAB2_LIB.BASEBOARD_FAB2(SCH_1):PAGE166_I34@W_HDL.PI5A3157BC6E-GP(CHIPS)':
 'B0': CDS_PINID='B0';
NET_NAME
'PECI_SEL'
 '@BASEBOARD_FAB2_LIB.BASEBOARD_FAB2(SCH_1):PECI_SEL':
 C_SIGNAL='@baseboard_fab2_lib.baseboard_fab2(sch_1):peci_sel';
NODE_NAME     U25W4 U22
 '@BASEBOARD_FAB2_LIB.BASEBOARD_FAB2(SCH_1):PAGE146_I104@W_HDL.AST2520A1-GP-GP(CHIPS)':
 'GPIOAA4_VPOR6_NORD4_SALT11': CDS_PINID='GPIOAA4_VPOR6_NORD4_SALT11';
NODE_NAME     U7W1 6
 '@BASEBOARD_FAB2_LIB.BASEBOARD_FAB2(SCH_1):PAGE166_I34@W_HDL.PI5A3157BC6E-GP(CHIPS)':
 'S': CDS_PINID='S';
NODE_NAME     R7W3 2
 '@BASEBOARD_FAB2_LIB.BASEBOARD_FAB2(SCH_1):PAGE166_I46@MSTR_DISCRETE.RES(CHIPS)':
 'B': CDS_PINID='B';
NET_NAME
'PE_PCH_SPRV_RX_C_DN'
 '@BASEBOARD_FAB2_LIB.BASEBOARD_FAB2(SCH_1):PE_PCH_SPRV_RX_C_DN':
 C_SIGNAL='@baseboard_fab2_lib.baseboard_fab2(sch_1):pe_pch_sprv_rx_c_dn';
NODE_NAME     U7C1 AM69
 '@BASEBOARD_FAB2_LIB.BASEBOARD_FAB2(SCH_1):PAGE116_I220@MSTR_U_PROC.LBG_CORE_QAT_EXT_D(CHIPS)':
 'PCIE5_GBE_RXN': CDS_PINID='PCIE5_GBE_RXN';
NODE_NAME     C9E5 2
 '@BASEBOARD_FAB2_LIB.BASEBOARD_FAB2(SCH_1):PAGE139_I87@DEV_DISCRETE.CAP_A(CHIPS)':
 'B': CDS_PINID='B';
NET_NAME
'PE_PCH_SPRV_RX_C_DP'
 '@BASEBOARD_FAB2_LIB.BASEBOARD_FAB2(SCH_1):PE_PCH_SPRV_RX_C_DP':
 C_SIGNAL='@baseboard_fab2_lib.baseboard_fab2(sch_1):pe_pch_sprv_rx_c_dp';
NODE_NAME     U7C1 AM71
 '@BASEBOARD_FAB2_LIB.BASEBOARD_FAB2(SCH_1):PAGE116_I220@MSTR_U_PROC.LBG_CORE_QAT_EXT_D(CHIPS)':
 'PCIE5_GBE_RXP': CDS_PINID='PCIE5_GBE_RXP';
NODE_NAME     C9E4 2
 '@BASEBOARD_FAB2_LIB.BASEBOARD_FAB2(SCH_1):PAGE139_I88@DEV_DISCRETE.CAP_A(CHIPS)':
 'B': CDS_PINID='B';
NET_NAME
'PE_PCH_SPRV_RX_DN'
 '@BASEBOARD_FAB2_LIB.BASEBOARD_FAB2(SCH_1):PE_PCH_SPRV_RX_DN':
 C_SIGNAL='@baseboard_fab2_lib.baseboard_fab2(sch_1):pe_pch_sprv_rx_dn';
NODE_NAME     EU9E1 20
 '@BASEBOARD_FAB2_LIB.BASEBOARD_FAB2(SCH_1):PAGE139_I72@MSTR_INTEL.SPRINGVILLE(CHIPS)':
 'PE_TN': CDS_PINID='PE_TN';
NODE_NAME     C9E5 1
 '@BASEBOARD_FAB2_LIB.BASEBOARD_FAB2(SCH_1):PAGE139_I87@DEV_DISCRETE.CAP_A(CHIPS)':
 'A': CDS_PINID='A';
NET_NAME
'PE_PCH_SPRV_RX_DP'
 '@BASEBOARD_FAB2_LIB.BASEBOARD_FAB2(SCH_1):PE_PCH_SPRV_RX_DP':
 C_SIGNAL='@baseboard_fab2_lib.baseboard_fab2(sch_1):pe_pch_sprv_rx_dp';
NODE_NAME     EU9E1 21
 '@BASEBOARD_FAB2_LIB.BASEBOARD_FAB2(SCH_1):PAGE139_I72@MSTR_INTEL.SPRINGVILLE(CHIPS)':
 'PE_TP': CDS_PINID='PE_TP';
NODE_NAME     C9E4 1
 '@BASEBOARD_FAB2_LIB.BASEBOARD_FAB2(SCH_1):PAGE139_I88@DEV_DISCRETE.CAP_A(CHIPS)':
 'A': CDS_PINID='A';
NET_NAME
'PE_PCH_SPRV_TX_C_DN'
 '@BASEBOARD_FAB2_LIB.BASEBOARD_FAB2(SCH_1):PE_PCH_SPRV_TX_C_DN':
 C_SIGNAL='@baseboard_fab2_lib.baseboard_fab2(sch_1):pe_pch_sprv_tx_c_dn';
NODE_NAME     EU9E1 23
 '@BASEBOARD_FAB2_LIB.BASEBOARD_FAB2(SCH_1):PAGE139_I72@MSTR_INTEL.SPRINGVILLE(CHIPS)':
 'PE_RN': CDS_PINID='PE_RN';
NODE_NAME     C2M24 2
 '@BASEBOARD_FAB2_LIB.BASEBOARD_FAB2(SCH_1):PAGE139_I90@DEV_DISCRETE.CAP_A(CHIPS)':
 'B': CDS_PINID='B';
NET_NAME
'PE_PCH_SPRV_TX_C_DP'
 '@BASEBOARD_FAB2_LIB.BASEBOARD_FAB2(SCH_1):PE_PCH_SPRV_TX_C_DP':
 C_SIGNAL='@baseboard_fab2_lib.baseboard_fab2(sch_1):pe_pch_sprv_tx_c_dp';
NODE_NAME     EU9E1 24
 '@BASEBOARD_FAB2_LIB.BASEBOARD_FAB2(SCH_1):PAGE139_I72@MSTR_INTEL.SPRINGVILLE(CHIPS)':
 'PE_RP': CDS_PINID='PE_RP';
NODE_NAME     C2M23 2
 '@BASEBOARD_FAB2_LIB.BASEBOARD_FAB2(SCH_1):PAGE139_I89@DEV_DISCRETE.CAP_A(CHIPS)':
 'B': CDS_PINID='B';
NET_NAME
'PE_PCH_SPRV_TX_DN'
 '@BASEBOARD_FAB2_LIB.BASEBOARD_FAB2(SCH_1):PE_PCH_SPRV_TX_DN':
 C_SIGNAL='@baseboard_fab2_lib.baseboard_fab2(sch_1):pe_pch_sprv_tx_dn';
NODE_NAME     U7C1 BH65
 '@BASEBOARD_FAB2_LIB.BASEBOARD_FAB2(SCH_1):PAGE116_I220@MSTR_U_PROC.LBG_CORE_QAT_EXT_D(CHIPS)':
 'PCIE5_GBE_TXN': CDS_PINID='PCIE5_GBE_TXN';
NODE_NAME     C2M24 1
 '@BASEBOARD_FAB2_LIB.BASEBOARD_FAB2(SCH_1):PAGE139_I90@DEV_DISCRETE.CAP_A(CHIPS)':
 'A': CDS_PINID='A';
NET_NAME
'PE_PCH_SPRV_TX_DP'
 '@BASEBOARD_FAB2_LIB.BASEBOARD_FAB2(SCH_1):PE_PCH_SPRV_TX_DP':
 C_SIGNAL='@baseboard_fab2_lib.baseboard_fab2(sch_1):pe_pch_sprv_tx_dp';
NODE_NAME     U7C1 BJ63
 '@BASEBOARD_FAB2_LIB.BASEBOARD_FAB2(SCH_1):PAGE116_I220@MSTR_U_PROC.LBG_CORE_QAT_EXT_D(CHIPS)':
 'PCIE5_GBE_TXP': CDS_PINID='PCIE5_GBE_TXP';
NODE_NAME     C2M23 1
 '@BASEBOARD_FAB2_LIB.BASEBOARD_FAB2(SCH_1):PAGE139_I89@DEV_DISCRETE.CAP_A(CHIPS)':
 'A': CDS_PINID='A';
NET_NAME
'PUMP_PWM_OUT'
 '@BASEBOARD_FAB2_LIB.BASEBOARD_FAB2(SCH_1):PUMP_PWM_OUT':
 C_SIGNAL='@baseboard_fab2_lib.baseboard_fab2(sch_1):pump_pwm_out';
NODE_NAME     U25W4 Y3
 '@BASEBOARD_FAB2_LIB.BASEBOARD_FAB2(SCH_1):PAGE147_I106@W_HDL.AST2520A1-GP-GP(CHIPS)':
 'GPION6_PWM6_VPIG6': CDS_PINID='GPION6_PWM6_VPIG6';
NODE_NAME     U10W1 2
 '@BASEBOARD_FAB2_LIB.BASEBOARD_FAB2(SCH_1):PAGE251_I19@MSTR_TTL.TTL1G07_A(CHIPS)':
 'A': CDS_PINID='A';
NET_NAME
'PUMP_PWM_OUT_BUF'
 '@BASEBOARD_FAB2_LIB.BASEBOARD_FAB2(SCH_1):PUMP_PWM_OUT_BUF':
 C_SIGNAL='@baseboard_fab2_lib.baseboard_fab2(sch_1):pump_pwm_out_buf';
NODE_NAME     R10W4 1
 '@BASEBOARD_FAB2_LIB.BASEBOARD_FAB2(SCH_1):PAGE251_I14@MSTR_DISCRETE.RES(CHIPS)':
 'A': CDS_PINID='A';
NODE_NAME     U10W1 4
 '@BASEBOARD_FAB2_LIB.BASEBOARD_FAB2(SCH_1):PAGE251_I19@MSTR_TTL.TTL1G07_A(CHIPS)':
 'Y': CDS_PINID='Y';
NET_NAME
'PUMP_PWM_OUT_R'
 '@BASEBOARD_FAB2_LIB.BASEBOARD_FAB2(SCH_1):PUMP_PWM_OUT_R':
 C_SIGNAL='@baseboard_fab2_lib.baseboard_fab2(sch_1):pump_pwm_out_r';
NODE_NAME     CR10W2 2
 '@BASEBOARD_FAB2_LIB.BASEBOARD_FAB2(SCH_1):PAGE251_I10@MSTR_DISCRETE.DIODE(CHIPS)':
 'A': CDS_PINID='A';
NODE_NAME     R10W3 2
 '@BASEBOARD_FAB2_LIB.BASEBOARD_FAB2(SCH_1):PAGE251_I11@MSTR_DISCRETE.RES(CHIPS)':
 'B': CDS_PINID='B';
NODE_NAME     R10W4 2
 '@BASEBOARD_FAB2_LIB.BASEBOARD_FAB2(SCH_1):PAGE251_I14@MSTR_DISCRETE.RES(CHIPS)':
 'B': CDS_PINID='B';
NODE_NAME     J1B2 4
 '@BASEBOARD_FAB2_LIB.BASEBOARD_FAB2(SCH_1):PAGE251_I25@MSTR_CONN.CONN6_C74770005(CHIPS)':
 'IO4': CDS_PINID='IO4';
NET_NAME
'PUMP_TACH0'
 '@BASEBOARD_FAB2_LIB.BASEBOARD_FAB2(SCH_1):PUMP_TACH0':
 C_SIGNAL='@baseboard_fab2_lib.baseboard_fab2(sch_1):pump_tach0';
NODE_NAME     U25W4 AB3
 '@BASEBOARD_FAB2_LIB.BASEBOARD_FAB2(SCH_1):PAGE147_I106@W_HDL.AST2520A1-GP-GP(CHIPS)':
 'GPIOO4_TACH4_VPIR2': CDS_PINID='GPIOO4_TACH4_VPIR2';
NODE_NAME     R1T24 1
 '@BASEBOARD_FAB2_LIB.BASEBOARD_FAB2(SCH_1):PAGE147_I129@MSTR_DISCRETE.RES(CHIPS)':
 'A': CDS_PINID='A';
NODE_NAME     R10W1 1
 '@BASEBOARD_FAB2_LIB.BASEBOARD_FAB2(SCH_1):PAGE251_I13@MSTR_DISCRETE.RES(CHIPS)':
 'A': CDS_PINID='A';
NODE_NAME     R10W2 2
 '@BASEBOARD_FAB2_LIB.BASEBOARD_FAB2(SCH_1):PAGE251_I15@MSTR_DISCRETE.RES(CHIPS)':
 'B': CDS_PINID='B';
NODE_NAME     C10W3 1
 '@BASEBOARD_FAB2_LIB.BASEBOARD_FAB2(SCH_1):PAGE251_I16@DEV_DISCRETE.CAP_A(CHIPS)':
 'A': CDS_PINID='A';
NODE_NAME     R25W157 1
 '@BASEBOARD_FAB2_LIB.BASEBOARD_FAB2(SCH_1):PAGE147_I164@MSTR_DISCRETE.RES(CHIPS)':
 'A': CDS_PINID='A';
NET_NAME
'PUMP_TACH1'
 '@BASEBOARD_FAB2_LIB.BASEBOARD_FAB2(SCH_1):PUMP_TACH1':
 C_SIGNAL='@baseboard_fab2_lib.baseboard_fab2(sch_1):pump_tach1';
NODE_NAME     U25W4 Y4
 '@BASEBOARD_FAB2_LIB.BASEBOARD_FAB2(SCH_1):PAGE147_I106@W_HDL.AST2520A1-GP-GP(CHIPS)':
 'GPIOO5_TACH5_VPIR3': CDS_PINID='GPIOO5_TACH5_VPIR3';
NODE_NAME     R25W142 1
 '@BASEBOARD_FAB2_LIB.BASEBOARD_FAB2(SCH_1):PAGE147_I156@MSTR_DISCRETE.RES(CHIPS)':
 'A': CDS_PINID='A';
NODE_NAME     R10W6 1
 '@BASEBOARD_FAB2_LIB.BASEBOARD_FAB2(SCH_1):PAGE251_I27@MSTR_DISCRETE.RES(CHIPS)':
 'A': CDS_PINID='A';
NODE_NAME     C10W5 1
 '@BASEBOARD_FAB2_LIB.BASEBOARD_FAB2(SCH_1):PAGE251_I29@DEV_DISCRETE.CAP_A(CHIPS)':
 'A': CDS_PINID='A';
NODE_NAME     R10W7 2
 '@BASEBOARD_FAB2_LIB.BASEBOARD_FAB2(SCH_1):PAGE251_I31@MSTR_DISCRETE.RES(CHIPS)':
 'B': CDS_PINID='B';
NET_NAME
'PUMP_TACH1_D'
 '@BASEBOARD_FAB2_LIB.BASEBOARD_FAB2(SCH_1):PUMP_TACH1_D':
 C_SIGNAL='@baseboard_fab2_lib.baseboard_fab2(sch_1):pump_tach1_d';
NODE_NAME     J1B2 5
 '@BASEBOARD_FAB2_LIB.BASEBOARD_FAB2(SCH_1):PAGE251_I25@MSTR_CONN.CONN6_C74770005(CHIPS)':
 'IO5': CDS_PINID='IO5';
NODE_NAME     CR10W3 1
 '@BASEBOARD_FAB2_LIB.BASEBOARD_FAB2(SCH_1):PAGE251_I26@MSTR_DISCRETE.DIODE(CHIPS)':
 'C': CDS_PINID='C';
NET_NAME
'PUMP_TACH1_R'
 '@BASEBOARD_FAB2_LIB.BASEBOARD_FAB2(SCH_1):PUMP_TACH1_R':
 C_SIGNAL='@baseboard_fab2_lib.baseboard_fab2(sch_1):pump_tach1_r';
NODE_NAME     CR10W3 2
 '@BASEBOARD_FAB2_LIB.BASEBOARD_FAB2(SCH_1):PAGE251_I26@MSTR_DISCRETE.DIODE(CHIPS)':
 'A': CDS_PINID='A';
NODE_NAME     R10W6 2
 '@BASEBOARD_FAB2_LIB.BASEBOARD_FAB2(SCH_1):PAGE251_I27@MSTR_DISCRETE.RES(CHIPS)':
 'B': CDS_PINID='B';
NET_NAME
'PUMP_TACH_D'
 '@BASEBOARD_FAB2_LIB.BASEBOARD_FAB2(SCH_1):PUMP_TACH_D':
 C_SIGNAL='@baseboard_fab2_lib.baseboard_fab2(sch_1):pump_tach_d';
NODE_NAME     CR10W1 1
 '@BASEBOARD_FAB2_LIB.BASEBOARD_FAB2(SCH_1):PAGE251_I12@MSTR_DISCRETE.DIODE(CHIPS)':
 'C': CDS_PINID='C';
NODE_NAME     J1B2 3
 '@BASEBOARD_FAB2_LIB.BASEBOARD_FAB2(SCH_1):PAGE251_I25@MSTR_CONN.CONN6_C74770005(CHIPS)':
 'IO3': CDS_PINID='IO3';
NET_NAME
'PUMP_TACH_R'
 '@BASEBOARD_FAB2_LIB.BASEBOARD_FAB2(SCH_1):PUMP_TACH_R':
 C_SIGNAL='@baseboard_fab2_lib.baseboard_fab2(sch_1):pump_tach_r';
NODE_NAME     CR10W1 2
 '@BASEBOARD_FAB2_LIB.BASEBOARD_FAB2(SCH_1):PAGE251_I12@MSTR_DISCRETE.DIODE(CHIPS)':
 'A': CDS_PINID='A';
NODE_NAME     R10W1 2
 '@BASEBOARD_FAB2_LIB.BASEBOARD_FAB2(SCH_1):PAGE251_I13@MSTR_DISCRETE.RES(CHIPS)':
 'B': CDS_PINID='B';
NET_NAME
'PU_10GBE_LOM_PCI_DISABLE_N'
 '@BASEBOARD_FAB2_LIB.BASEBOARD_FAB2(SCH_1):PU_10GBE_LOM_PCI_DISABLE_N':
 C_SIGNAL='@baseboard_fab2_lib.baseboard_fab2(sch_1):pu_10gbe_lom_pci_disable_n';
NODE_NAME     U7C1 BW22
 '@BASEBOARD_FAB2_LIB.BASEBOARD_FAB2(SCH_1):PAGE120_I147@MSTR_U_PROC.LBG_CORE_QAT_EXT_D(CHIPS)':
 'GPP_I8_PCI_DIS_N': CDS_PINID='GPP_I8_PCI_DIS_N';
NODE_NAME     R2N9 2
 '@BASEBOARD_FAB2_LIB.BASEBOARD_FAB2(SCH_1):PAGE133_I267@MSTR_DISCRETE.RES(CHIPS)':
 'B': CDS_PINID='B';
NET_NAME
'PU_24M_OSC_OE'
 '@BASEBOARD_FAB2_LIB.BASEBOARD_FAB2(SCH_1):PU_24M_OSC_OE':
 C_SIGNAL='@baseboard_fab2_lib.baseboard_fab2(sch_1):pu_24m_osc_oe';
NODE_NAME     Y9F2 1
 '@BASEBOARD_FAB2_LIB.BASEBOARD_FAB2(SCH_1):PAGE145_I8@MSTR_DISCRETE.OSC_C(CHIPS)':
 'ENABLE_CONTROL': CDS_PINID='ENABLE_CONTROL';
NODE_NAME     R9F61 2
 '@BASEBOARD_FAB2_LIB.BASEBOARD_FAB2(SCH_1):PAGE145_I14@MSTR_DISCRETE.RES(CHIPS)':
 'B': CDS_PINID='B';
NET_NAME
'PU_33P_33M_SMBADR'
 '@BASEBOARD_FAB2_LIB.BASEBOARD_FAB2(SCH_1):PU_33P_33M_SMBADR':
 C_SIGNAL='@baseboard_fab2_lib.baseboard_fab2(sch_1):pu_33p_33m_smbadr';
NODE_NAME     EU8F2 22
 '@BASEBOARD_FAB2_LIB.BASEBOARD_FAB2(SCH_1):PAGE101_I34@MSTR_CLOCK.ICS9FGP204(CHIPS)':
 '33MHZ_SMBADR': CDS_PINID='\33mhz_smbadr\';
NODE_NAME     R1W25 1
 '@BASEBOARD_FAB2_LIB.BASEBOARD_FAB2(SCH_1):PAGE101_I140@MSTR_DISCRETE.RES(CHIPS)':
 'A': CDS_PINID='A';
NET_NAME
'PU_ADR_TIMER_HOLD_OFF_N'
 '@BASEBOARD_FAB2_LIB.BASEBOARD_FAB2(SCH_1):PU_ADR_TIMER_HOLD_OFF_N':
 C_SIGNAL='@baseboard_fab2_lib.baseboard_fab2(sch_1):pu_adr_timer_hold_off_n';
NODE_NAME     U7C1 BB3
 '@BASEBOARD_FAB2_LIB.BASEBOARD_FAB2(SCH_1):PAGE120_I147@MSTR_U_PROC.LBG_CORE_QAT_EXT_D(CHIPS)':
 'GPP_H15_SML3ALERT_N_IE_N': CDS_PINID='GPP_H15_SML3ALERT_N_IE_N';
NODE_NAME     R8D5 1
 '@BASEBOARD_FAB2_LIB.BASEBOARD_FAB2(SCH_1):PAGE125_I50@MSTR_DISCRETE.RES(CHIPS)':
 'A': CDS_PINID='A';
NODE_NAME     R8D13 2
 '@BASEBOARD_FAB2_LIB.BASEBOARD_FAB2(SCH_1):PAGE125_I87@MSTR_DISCRETE.RES(CHIPS)':
 'B': CDS_PINID='B';
NET_NAME
'PU_AT24C64_A2'
 '@BASEBOARD_FAB2_LIB.BASEBOARD_FAB2(SCH_1):PU_AT24C64_A2':
 C_SIGNAL='@baseboard_fab2_lib.baseboard_fab2(sch_1):pu_at24c64_a2';
NODE_NAME     U8D4 3
 '@BASEBOARD_FAB2_LIB.BASEBOARD_FAB2(SCH_1):PAGE167_I49@MSTR_MEMORY.AT24C64(CHIPS)':
 'A2': CDS_PINID='A2';
NODE_NAME     R8D28 2
 '@BASEBOARD_FAB2_LIB.BASEBOARD_FAB2(SCH_1):PAGE167_I70@MSTR_DISCRETE.RES(CHIPS)':
 'B': CDS_PINID='B';
NET_NAME
'PU_BIOS_RECOVER_BOOT'
 '@BASEBOARD_FAB2_LIB.BASEBOARD_FAB2(SCH_1):PU_BIOS_RECOVER_BOOT':
 C_SIGNAL='@baseboard_fab2_lib.baseboard_fab2(sch_1):pu_bios_recover_boot';
NODE_NAME     R7G31 2
 '@BASEBOARD_FAB2_LIB.BASEBOARD_FAB2(SCH_1):PAGE136_I139@MSTR_DISCRETE.RES(CHIPS)':
 'B': CDS_PINID='B';
NODE_NAME     J7G3 12
 '@BASEBOARD_FAB2_LIB.BASEBOARD_FAB2(SCH_1):PAGE136_I174@MSTR_CONN.CONN12_C73564003(CHIPS)':
 'IO12': CDS_PINID='IO12';
NET_NAME
'PU_BIOS_SPI_HOLD0_N'
 '@BASEBOARD_FAB2_LIB.BASEBOARD_FAB2(SCH_1):PU_BIOS_SPI_HOLD0_N':
 C_SIGNAL='@baseboard_fab2_lib.baseboard_fab2(sch_1):pu_bios_spi_hold0_n';
NODE_NAME     R7F3 2
 '@BASEBOARD_FAB2_LIB.BASEBOARD_FAB2(SCH_1):PAGE153_I109@MSTR_DISCRETE.RES(CHIPS)':
 'B': CDS_PINID='B';
NODE_NAME     R7F32 2
 '@BASEBOARD_FAB2_LIB.BASEBOARD_FAB2(SCH_1):PAGE153_I140@MSTR_DISCRETE.RES(CHIPS)':
 'B': CDS_PINID='B';
NODE_NAME     U7F1 1
 '@BASEBOARD_FAB2_LIB.BASEBOARD_FAB2(SCH_1):PAGE153_I146@MSTR_MEMORY.W25Q256(CHIPS)':
 'HOLD_N_IO'<3>: CDS_PINID='HOLD_N_IO(3)';
NET_NAME
'PU_BIOS_SPI_HOLD1_N'
 '@BASEBOARD_FAB2_LIB.BASEBOARD_FAB2(SCH_1):PU_BIOS_SPI_HOLD1_N':
 C_SIGNAL='@baseboard_fab2_lib.baseboard_fab2(sch_1):pu_bios_spi_hold1_n';
NODE_NAME     R3T1 2
 '@BASEBOARD_FAB2_LIB.BASEBOARD_FAB2(SCH_1):PAGE153_I157@MSTR_DISCRETE.RES(CHIPS)':
 'B': CDS_PINID='B';
NODE_NAME     R3T4 2
 '@BASEBOARD_FAB2_LIB.BASEBOARD_FAB2(SCH_1):PAGE153_I174@MSTR_DISCRETE.RES(CHIPS)':
 'B': CDS_PINID='B';
NODE_NAME     U3T1 1
 '@BASEBOARD_FAB2_LIB.BASEBOARD_FAB2(SCH_1):PAGE153_I185@W_HDL.W25Q256FVFIG-GP(CHIPS)':
 'HOLD#/IO3': CDS_PINID='\hold#/io3\';
NET_NAME
'PU_BIOS_SPI_WP0_N'
 '@BASEBOARD_FAB2_LIB.BASEBOARD_FAB2(SCH_1):PU_BIOS_SPI_WP0_N':
 C_SIGNAL='@baseboard_fab2_lib.baseboard_fab2(sch_1):pu_bios_spi_wp0_n';
NODE_NAME     R7F37 2
 '@BASEBOARD_FAB2_LIB.BASEBOARD_FAB2(SCH_1):PAGE153_I108@MSTR_DISCRETE.RES(CHIPS)':
 'B': CDS_PINID='B';
NODE_NAME     U7F1 9
 '@BASEBOARD_FAB2_LIB.BASEBOARD_FAB2(SCH_1):PAGE153_I146@MSTR_MEMORY.W25Q256(CHIPS)':
 'WP_N_IO'<2>: CDS_PINID='WP_N_IO(2)';
NODE_NAME     R7F28 2
 '@BASEBOARD_FAB2_LIB.BASEBOARD_FAB2(SCH_1):PAGE153_I168@MSTR_DISCRETE.RES(CHIPS)':
 'B': CDS_PINID='B';
NODE_NAME     R7F30 1
 '@BASEBOARD_FAB2_LIB.BASEBOARD_FAB2(SCH_1):PAGE153_I170@MSTR_DISCRETE.RES(CHIPS)':
 'A': CDS_PINID='A';
NET_NAME
'PU_BIOS_SPI_WP1_N'
 '@BASEBOARD_FAB2_LIB.BASEBOARD_FAB2(SCH_1):PU_BIOS_SPI_WP1_N':
 C_SIGNAL='@baseboard_fab2_lib.baseboard_fab2(sch_1):pu_bios_spi_wp1_n';
NODE_NAME     R3U1 2
 '@BASEBOARD_FAB2_LIB.BASEBOARD_FAB2(SCH_1):PAGE153_I156@MSTR_DISCRETE.RES(CHIPS)':
 'B': CDS_PINID='B';
NODE_NAME     R3T12 2
 '@BASEBOARD_FAB2_LIB.BASEBOARD_FAB2(SCH_1):PAGE153_I178@MSTR_DISCRETE.RES(CHIPS)':
 'B': CDS_PINID='B';
NODE_NAME     R3T9 1
 '@BASEBOARD_FAB2_LIB.BASEBOARD_FAB2(SCH_1):PAGE153_I179@MSTR_DISCRETE.RES(CHIPS)':
 'A': CDS_PINID='A';
NODE_NAME     U3T1 9
 '@BASEBOARD_FAB2_LIB.BASEBOARD_FAB2(SCH_1):PAGE153_I185@W_HDL.W25Q256FVFIG-GP(CHIPS)':
 'WP#/IO2': CDS_PINID='\wp#/io2\';
NET_NAME
'PU_BIOS_USB_RECOVERY'
 '@BASEBOARD_FAB2_LIB.BASEBOARD_FAB2(SCH_1):PU_BIOS_USB_RECOVERY':
 C_SIGNAL='@baseboard_fab2_lib.baseboard_fab2(sch_1):pu_bios_usb_recovery';
NODE_NAME     R7G27 2
 '@BASEBOARD_FAB2_LIB.BASEBOARD_FAB2(SCH_1):PAGE136_I155@MSTR_DISCRETE.RES(CHIPS)':
 'B': CDS_PINID='B';
NODE_NAME     J7G3 6
 '@BASEBOARD_FAB2_LIB.BASEBOARD_FAB2(SCH_1):PAGE136_I174@MSTR_CONN.CONN12_C73564003(CHIPS)':
 'IO6': CDS_PINID='IO6';
NET_NAME
'PU_CPLD1_PT20D_PROGRAMN'
 '@BASEBOARD_FAB2_LIB.BASEBOARD_FAB2(SCH_1):PU_CPLD1_PT20D_PROGRAMN':
 C_SIGNAL='@baseboard_fab2_lib.baseboard_fab2(sch_1):pu_cpld1_pt20d_programn';
NODE_NAME     U8D7 B10
 '@BASEBOARD_FAB2_LIB.BASEBOARD_FAB2(SCH_1):PAGE191_I59@MSTR_MEMORY.LCMXO2_A(CHIPS)':
 'PT20D_PROGRAMN': CDS_PINID='PT20D_PROGRAMN';
NODE_NAME     R4W1 2
 '@BASEBOARD_FAB2_LIB.BASEBOARD_FAB2(SCH_1):PAGE191_I195@MSTR_DISCRETE.RES(CHIPS)':
 'B': CDS_PINID='B';
NET_NAME
'PU_CPU0_FRMAGENT'
 '@BASEBOARD_FAB2_LIB.BASEBOARD_FAB2(SCH_1):PU_CPU0_FRMAGENT':
 C_SIGNAL='@baseboard_fab2_lib.baseboard_fab2(sch_1):pu_cpu0_frmagent';
NODE_NAME     U5D1 AV17
 '@BASEBOARD_FAB2_LIB.BASEBOARD_FAB2(SCH_1):PAGE21_I259@CHPSET_LIB.SKX_EXT_B(CHIPS)':
 'FRMAGENT': CDS_PINID='FRMAGENT';
NODE_NAME     R5D3 2
 '@BASEBOARD_FAB2_LIB.BASEBOARD_FAB2(SCH_1):PAGE90_I29@MSTR_DISCRETE.RES(CHIPS)':
 'B': CDS_PINID='B';
NET_NAME
'PU_CPU0_LEGACY_SKT'
 '@BASEBOARD_FAB2_LIB.BASEBOARD_FAB2(SCH_1):PU_CPU0_LEGACY_SKT':
 C_SIGNAL='@baseboard_fab2_lib.baseboard_fab2(sch_1):pu_cpu0_legacy_skt';
NODE_NAME     U5D1 AE20
 '@BASEBOARD_FAB2_LIB.BASEBOARD_FAB2(SCH_1):PAGE21_I259@CHPSET_LIB.SKX_EXT_B(CHIPS)':
 'LEGACY_SKT': CDS_PINID='LEGACY_SKT';
NODE_NAME     R4P14 2
 '@BASEBOARD_FAB2_LIB.BASEBOARD_FAB2(SCH_1):PAGE90_I53@MSTR_DISCRETE.RES(CHIPS)':
 'B': CDS_PINID='B';
NET_NAME
'PU_CPU0_SAFE_MODE_BOOT'
 '@BASEBOARD_FAB2_LIB.BASEBOARD_FAB2(SCH_1):PU_CPU0_SAFE_MODE_BOOT':
 C_SIGNAL='@baseboard_fab2_lib.baseboard_fab2(sch_1):pu_cpu0_safe_mode_boot';
NODE_NAME     U5D1 AR18
 '@BASEBOARD_FAB2_LIB.BASEBOARD_FAB2(SCH_1):PAGE21_I259@CHPSET_LIB.SKX_EXT_B(CHIPS)':
 'SAFE_MODE_BOOT': CDS_PINID='SAFE_MODE_BOOT';
NODE_NAME     R6D13 2
 '@BASEBOARD_FAB2_LIB.BASEBOARD_FAB2(SCH_1):PAGE90_I33@MSTR_DISCRETE.RES(CHIPS)':
 'B': CDS_PINID='B';
NET_NAME
'PU_CPU0_SOCKET_ID_0'
 '@BASEBOARD_FAB2_LIB.BASEBOARD_FAB2(SCH_1):PU_CPU0_SOCKET_ID_0':
 C_SIGNAL='@baseboard_fab2_lib.baseboard_fab2(sch_1):pu_cpu0_socket_id_0';
NODE_NAME     U5D1 AU22
 '@BASEBOARD_FAB2_LIB.BASEBOARD_FAB2(SCH_1):PAGE21_I259@CHPSET_LIB.SKX_EXT_B(CHIPS)':
 'SOCKET_ID'<0>: CDS_PINID='SOCKET_ID(0)';
NODE_NAME     R6D15 2
 '@BASEBOARD_FAB2_LIB.BASEBOARD_FAB2(SCH_1):PAGE90_I48@MSTR_DISCRETE.RES(CHIPS)':
 'B': CDS_PINID='B';
NET_NAME
'PU_CPU0_SOCKET_ID_1'
 '@BASEBOARD_FAB2_LIB.BASEBOARD_FAB2(SCH_1):PU_CPU0_SOCKET_ID_1':
 C_SIGNAL='@baseboard_fab2_lib.baseboard_fab2(sch_1):pu_cpu0_socket_id_1';
NODE_NAME     U5D1 AU16
 '@BASEBOARD_FAB2_LIB.BASEBOARD_FAB2(SCH_1):PAGE21_I259@CHPSET_LIB.SKX_EXT_B(CHIPS)':
 'SOCKET_ID'<1>: CDS_PINID='SOCKET_ID(1)';
NODE_NAME     R6D10 2
 '@BASEBOARD_FAB2_LIB.BASEBOARD_FAB2(SCH_1):PAGE90_I49@MSTR_DISCRETE.RES(CHIPS)':
 'B': CDS_PINID='B';
NET_NAME
'PU_CPU0_TSC_SYNC'
 '@BASEBOARD_FAB2_LIB.BASEBOARD_FAB2(SCH_1):PU_CPU0_TSC_SYNC':
 C_SIGNAL='@baseboard_fab2_lib.baseboard_fab2(sch_1):pu_cpu0_tsc_sync';
NODE_NAME     U5D1 AM11
 '@BASEBOARD_FAB2_LIB.BASEBOARD_FAB2(SCH_1):PAGE21_I259@CHPSET_LIB.SKX_EXT_B(CHIPS)':
 'TSC_SYNC': CDS_PINID='TSC_SYNC';
NODE_NAME     R4P21 2
 '@BASEBOARD_FAB2_LIB.BASEBOARD_FAB2(SCH_1):PAGE97_I72@MSTR_DISCRETE.RES(CHIPS)':
 'B': CDS_PINID='B';
NET_NAME
'PU_CPU0_TXT_AGENT'
 '@BASEBOARD_FAB2_LIB.BASEBOARD_FAB2(SCH_1):PU_CPU0_TXT_AGENT':
 C_SIGNAL='@baseboard_fab2_lib.baseboard_fab2(sch_1):pu_cpu0_txt_agent';
NODE_NAME     U5D1 AW18
 '@BASEBOARD_FAB2_LIB.BASEBOARD_FAB2(SCH_1):PAGE21_I259@CHPSET_LIB.SKX_EXT_B(CHIPS)':
 'TXT_AGENT': CDS_PINID='TXT_AGENT';
NODE_NAME     R5D4 2
 '@BASEBOARD_FAB2_LIB.BASEBOARD_FAB2(SCH_1):PAGE90_I96@MSTR_DISCRETE.RES(CHIPS)':
 'B': CDS_PINID='B';
NET_NAME
'PU_CPU1_FRMAGENT'
 '@BASEBOARD_FAB2_LIB.BASEBOARD_FAB2(SCH_1):PU_CPU1_FRMAGENT':
 C_SIGNAL='@baseboard_fab2_lib.baseboard_fab2(sch_1):pu_cpu1_frmagent';
NODE_NAME     U2D1 AV17
 '@BASEBOARD_FAB2_LIB.BASEBOARD_FAB2(SCH_1):PAGE55_I172@CHPSET_LIB.SKX_EXT_B(CHIPS)':
 'FRMAGENT': CDS_PINID='FRMAGENT';
NODE_NAME     R3D22 2
 '@BASEBOARD_FAB2_LIB.BASEBOARD_FAB2(SCH_1):PAGE90_I17@MSTR_DISCRETE.RES(CHIPS)':
 'B': CDS_PINID='B';
NET_NAME
'PU_CPU1_LEGACY_SKT'
 '@BASEBOARD_FAB2_LIB.BASEBOARD_FAB2(SCH_1):PU_CPU1_LEGACY_SKT':
 C_SIGNAL='@baseboard_fab2_lib.baseboard_fab2(sch_1):pu_cpu1_legacy_skt';
NODE_NAME     U2D1 AE20
 '@BASEBOARD_FAB2_LIB.BASEBOARD_FAB2(SCH_1):PAGE55_I172@CHPSET_LIB.SKX_EXT_B(CHIPS)':
 'LEGACY_SKT': CDS_PINID='LEGACY_SKT';
NODE_NAME     R7P22 2
 '@BASEBOARD_FAB2_LIB.BASEBOARD_FAB2(SCH_1):PAGE90_I76@MSTR_DISCRETE.RES(CHIPS)':
 'B': CDS_PINID='B';
NET_NAME
'PU_CPU1_SAFE_MODE_BOOT'
 '@BASEBOARD_FAB2_LIB.BASEBOARD_FAB2(SCH_1):PU_CPU1_SAFE_MODE_BOOT':
 C_SIGNAL='@baseboard_fab2_lib.baseboard_fab2(sch_1):pu_cpu1_safe_mode_boot';
NODE_NAME     U2D1 AR18
 '@BASEBOARD_FAB2_LIB.BASEBOARD_FAB2(SCH_1):PAGE55_I172@CHPSET_LIB.SKX_EXT_B(CHIPS)':
 'SAFE_MODE_BOOT': CDS_PINID='SAFE_MODE_BOOT';
NODE_NAME     R3D26 2
 '@BASEBOARD_FAB2_LIB.BASEBOARD_FAB2(SCH_1):PAGE90_I28@MSTR_DISCRETE.RES(CHIPS)':
 'B': CDS_PINID='B';
NET_NAME
'PU_CPU1_SOCKET_ID_0'
 '@BASEBOARD_FAB2_LIB.BASEBOARD_FAB2(SCH_1):PU_CPU1_SOCKET_ID_0':
 C_SIGNAL='@baseboard_fab2_lib.baseboard_fab2(sch_1):pu_cpu1_socket_id_0';
NODE_NAME     U2D1 AU22
 '@BASEBOARD_FAB2_LIB.BASEBOARD_FAB2(SCH_1):PAGE55_I172@CHPSET_LIB.SKX_EXT_B(CHIPS)':
 'SOCKET_ID'<0>: CDS_PINID='SOCKET_ID(0)';
NODE_NAME     R3D24 2
 '@BASEBOARD_FAB2_LIB.BASEBOARD_FAB2(SCH_1):PAGE90_I59@MSTR_DISCRETE.RES(CHIPS)':
 'B': CDS_PINID='B';
NET_NAME
'PU_CPU1_SOCKET_ID_1'
 '@BASEBOARD_FAB2_LIB.BASEBOARD_FAB2(SCH_1):PU_CPU1_SOCKET_ID_1':
 C_SIGNAL='@baseboard_fab2_lib.baseboard_fab2(sch_1):pu_cpu1_socket_id_1';
NODE_NAME     U2D1 AU16
 '@BASEBOARD_FAB2_LIB.BASEBOARD_FAB2(SCH_1):PAGE55_I172@CHPSET_LIB.SKX_EXT_B(CHIPS)':
 'SOCKET_ID'<1>: CDS_PINID='SOCKET_ID(1)';
NODE_NAME     R3D17 2
 '@BASEBOARD_FAB2_LIB.BASEBOARD_FAB2(SCH_1):PAGE90_I60@MSTR_DISCRETE.RES(CHIPS)':
 'B': CDS_PINID='B';
NET_NAME
'PU_CPU1_TSC_SYNC'
 '@BASEBOARD_FAB2_LIB.BASEBOARD_FAB2(SCH_1):PU_CPU1_TSC_SYNC':
 C_SIGNAL='@baseboard_fab2_lib.baseboard_fab2(sch_1):pu_cpu1_tsc_sync';
NODE_NAME     U2D1 AM11
 '@BASEBOARD_FAB2_LIB.BASEBOARD_FAB2(SCH_1):PAGE55_I172@CHPSET_LIB.SKX_EXT_B(CHIPS)':
 'TSC_SYNC': CDS_PINID='TSC_SYNC';
NODE_NAME     R4C10 2
 '@BASEBOARD_FAB2_LIB.BASEBOARD_FAB2(SCH_1):PAGE97_I76@MSTR_DISCRETE.RES(CHIPS)':
 'B': CDS_PINID='B';
NET_NAME
'PU_CPU1_TXT_AGENT'
 '@BASEBOARD_FAB2_LIB.BASEBOARD_FAB2(SCH_1):PU_CPU1_TXT_AGENT':
 C_SIGNAL='@baseboard_fab2_lib.baseboard_fab2(sch_1):pu_cpu1_txt_agent';
NODE_NAME     U2D1 AW18
 '@BASEBOARD_FAB2_LIB.BASEBOARD_FAB2(SCH_1):PAGE55_I172@CHPSET_LIB.SKX_EXT_B(CHIPS)':
 'TXT_AGENT': CDS_PINID='TXT_AGENT';
NODE_NAME     R3D23 2
 '@BASEBOARD_FAB2_LIB.BASEBOARD_FAB2(SCH_1):PAGE90_I25@MSTR_DISCRETE.RES(CHIPS)':
 'B': CDS_PINID='B';
NET_NAME
'PU_DATAIN1_SATA_0_R'
 '@BASEBOARD_FAB2_LIB.BASEBOARD_FAB2(SCH_1):PU_DATAIN1_SATA_0_R':
 C_SIGNAL='@baseboard_fab2_lib.baseboard_fab2(sch_1):pu_datain1_sata_0_r';
NODE_NAME     J8A1 1D1
 '@BASEBOARD_FAB2_LIB.BASEBOARD_FAB2(SCH_1):PAGE173_I163@MSTR_CONN.CONN72_G97614002_A(CHIPS)':
 'SIDEBANDA_5': CDS_PINID='SIDEBANDA_5';
NODE_NAME     R2L21 2
 '@BASEBOARD_FAB2_LIB.BASEBOARD_FAB2(SCH_1):PAGE173_I263@MSTR_DISCRETE.RES(CHIPS)':
 'B': CDS_PINID='B';
NET_NAME
'PU_DATAIN1_SATA_1_R'
 '@BASEBOARD_FAB2_LIB.BASEBOARD_FAB2(SCH_1):PU_DATAIN1_SATA_1_R':
 C_SIGNAL='@baseboard_fab2_lib.baseboard_fab2(sch_1):pu_datain1_sata_1_r';
NODE_NAME     J8A1 2D1
 '@BASEBOARD_FAB2_LIB.BASEBOARD_FAB2(SCH_1):PAGE173_I163@MSTR_CONN.CONN72_G97614002_A(CHIPS)':
 'SIDEBANDB_5': CDS_PINID='SIDEBANDB_5';
NODE_NAME     R2L23 2
 '@BASEBOARD_FAB2_LIB.BASEBOARD_FAB2(SCH_1):PAGE173_I261@MSTR_DISCRETE.RES(CHIPS)':
 'B': CDS_PINID='B';
NET_NAME
'PU_DEV_OFF_N'
 '@BASEBOARD_FAB2_LIB.BASEBOARD_FAB2(SCH_1):PU_DEV_OFF_N':
 C_SIGNAL='@baseboard_fab2_lib.baseboard_fab2(sch_1):pu_dev_off_n';
NODE_NAME     EU9E1 28
 '@BASEBOARD_FAB2_LIB.BASEBOARD_FAB2(SCH_1):PAGE139_I72@MSTR_INTEL.SPRINGVILLE(CHIPS)':
 'DEV_OFF_N': CDS_PINID='DEV_OFF_N';
NODE_NAME     R9W36 2
 '@BASEBOARD_FAB2_LIB.BASEBOARD_FAB2(SCH_1):PAGE139_I252@MSTR_DISCRETE.RES(CHIPS)':
 'B': CDS_PINID='B';
NET_NAME
'PU_FAB2_MARKER_CPLD'
 '@BASEBOARD_FAB2_LIB.BASEBOARD_FAB2(SCH_1):PU_FAB2_MARKER_CPLD':
 C_SIGNAL='@baseboard_fab2_lib.baseboard_fab2(sch_1):pu_fab2_marker_cpld';
NODE_NAME     U8D7 K16
 '@BASEBOARD_FAB2_LIB.BASEBOARD_FAB2(SCH_1):PAGE191_I59@MSTR_MEMORY.LCMXO2_A(CHIPS)':
 'PR9B': CDS_PINID='PR9B';
NODE_NAME     R7D42 2
 '@BASEBOARD_FAB2_LIB.BASEBOARD_FAB2(SCH_1):PAGE191_I193@MSTR_DISCRETE.RES(CHIPS)':
 'B': CDS_PINID='B';
NET_NAME
'PU_FM_RCIN_N'
 '@BASEBOARD_FAB2_LIB.BASEBOARD_FAB2(SCH_1):PU_FM_RCIN_N':
 C_SIGNAL='@baseboard_fab2_lib.baseboard_fab2(sch_1):pu_fm_rcin_n';
NODE_NAME     U7C1 N3
 '@BASEBOARD_FAB2_LIB.BASEBOARD_FAB2(SCH_1):PAGE119_I115@MSTR_U_PROC.LBG_CORE_QAT_EXT_D(CHIPS)':
 'GPP_A0_RCIN_N_ESPI_ALERT1_N': CDS_PINID='GPP_A0_RCIN_N_ESPI_ALERT1_N';
NODE_NAME     R7D2 2
 '@BASEBOARD_FAB2_LIB.BASEBOARD_FAB2(SCH_1):PAGE133_I332@MSTR_DISCRETE.RES(CHIPS)':
 'B': CDS_PINID='B';
NET_NAME
'PU_GTL2014_1_DIR'
 '@BASEBOARD_FAB2_LIB.BASEBOARD_FAB2(SCH_1):PU_GTL2014_1_DIR':
 C_SIGNAL='@baseboard_fab2_lib.baseboard_fab2(sch_1):pu_gtl2014_1_dir';
NODE_NAME     R3P36 2
 '@BASEBOARD_FAB2_LIB.BASEBOARD_FAB2(SCH_1):PAGE96_I36@MSTR_DISCRETE.RES(CHIPS)':
 'B': CDS_PINID='B';
NODE_NAME     U3P1 1
 '@BASEBOARD_FAB2_LIB.BASEBOARD_FAB2(SCH_1):PAGE96_I42@MSTR_DIGITAL.GTL2014(CHIPS)':
 'DIR': CDS_PINID='DIR';
NET_NAME
'PU_GTL2014_2_DIR'
 '@BASEBOARD_FAB2_LIB.BASEBOARD_FAB2(SCH_1):PU_GTL2014_2_DIR':
 C_SIGNAL='@baseboard_fab2_lib.baseboard_fab2(sch_1):pu_gtl2014_2_dir';
NODE_NAME     U4C2 1
 '@BASEBOARD_FAB2_LIB.BASEBOARD_FAB2(SCH_1):PAGE96_I46@MSTR_DIGITAL.GTL2014(CHIPS)':
 'DIR': CDS_PINID='DIR';
NODE_NAME     R4C8 2
 '@BASEBOARD_FAB2_LIB.BASEBOARD_FAB2(SCH_1):PAGE96_I55@MSTR_DISCRETE.RES(CHIPS)':
 'B': CDS_PINID='B';
NET_NAME
'PU_GTL2014_3_DIR'
 '@BASEBOARD_FAB2_LIB.BASEBOARD_FAB2(SCH_1):PU_GTL2014_3_DIR':
 C_SIGNAL='@baseboard_fab2_lib.baseboard_fab2(sch_1):pu_gtl2014_3_dir';
NODE_NAME     R25W158 2
 '@BASEBOARD_FAB2_LIB.BASEBOARD_FAB2(SCH_1):PAGE269_I22@MSTR_DISCRETE.RES(CHIPS)':
 'B': CDS_PINID='B';
NODE_NAME     U25W10 1
 '@BASEBOARD_FAB2_LIB.BASEBOARD_FAB2(SCH_1):PAGE269_I49@MSTR_DIGITAL.GTL2014(CHIPS)':
 'DIR': CDS_PINID='DIR';
NET_NAME
'PU_ID_EEPROM_A0'
 '@BASEBOARD_FAB2_LIB.BASEBOARD_FAB2(SCH_1):PU_ID_EEPROM_A0':
 C_SIGNAL='@baseboard_fab2_lib.baseboard_fab2(sch_1):pu_id_eeprom_a0';
NODE_NAME     U6W3 1
 '@BASEBOARD_FAB2_LIB.BASEBOARD_FAB2(SCH_1):PAGE247_I89@MSTR_MEMORY.AT24C64(CHIPS)':
 'A0': CDS_PINID='A0';
NODE_NAME     R6W21 2
 '@BASEBOARD_FAB2_LIB.BASEBOARD_FAB2(SCH_1):PAGE247_I90@MSTR_DISCRETE.RES(CHIPS)':
 'B': CDS_PINID='B';
NET_NAME
'PU_IRQ_PCH_SCI_WHEA_N'
 '@BASEBOARD_FAB2_LIB.BASEBOARD_FAB2(SCH_1):PU_IRQ_PCH_SCI_WHEA_N':
 C_SIGNAL='@baseboard_fab2_lib.baseboard_fab2(sch_1):pu_irq_pch_sci_whea_n';
NODE_NAME     U7C1 R1
 '@BASEBOARD_FAB2_LIB.BASEBOARD_FAB2(SCH_1):PAGE119_I115@MSTR_U_PROC.LBG_CORE_QAT_EXT_D(CHIPS)':
 'GPP_A12_BMBUSY_N_SXEXITHLDOFF_N': CDS_PINID='GPP_A12_BMBUSY_N_SXEXITHLDOFF_N';
NODE_NAME     R7D4 2
 '@BASEBOARD_FAB2_LIB.BASEBOARD_FAB2(SCH_1):PAGE133_I245@MSTR_DISCRETE.RES(CHIPS)':
 'B': CDS_PINID='B';
NET_NAME
'PU_IRQ_VRALERT_N'
 '@BASEBOARD_FAB2_LIB.BASEBOARD_FAB2(SCH_1):PU_IRQ_VRALERT_N':
 C_SIGNAL='@baseboard_fab2_lib.baseboard_fab2(sch_1):pu_irq_vralert_n';
NODE_NAME     U7C1 BN15
 '@BASEBOARD_FAB2_LIB.BASEBOARD_FAB2(SCH_1):PAGE119_I115@MSTR_U_PROC.LBG_CORE_QAT_EXT_D(CHIPS)':
 'GPP_B2': CDS_PINID='GPP_B2';
NODE_NAME     R2N16 2
 '@BASEBOARD_FAB2_LIB.BASEBOARD_FAB2(SCH_1):PAGE133_I247@MSTR_DISCRETE.RES(CHIPS)':
 'B': CDS_PINID='B';
NET_NAME
'PU_JTAG_BMC_RTCK'
 '@BASEBOARD_FAB2_LIB.BASEBOARD_FAB2(SCH_1):PU_JTAG_BMC_RTCK':
 C_SIGNAL='@baseboard_fab2_lib.baseboard_fab2(sch_1):pu_jtag_bmc_rtck';
NODE_NAME     U25W4 C9
 '@BASEBOARD_FAB2_LIB.BASEBOARD_FAB2(SCH_1):PAGE144_I95@W_HDL.AST2520A1-GP-GP(CHIPS)':
 'RTCK': CDS_PINID='RTCK';
NODE_NAME     R25W105 2
 '@BASEBOARD_FAB2_LIB.BASEBOARD_FAB2(SCH_1):PAGE150_I196@MSTR_DISCRETE.RES(CHIPS)':
 'B': CDS_PINID='B';
NET_NAME
'PU_JTAG_SPRV_TCK'
 '@BASEBOARD_FAB2_LIB.BASEBOARD_FAB2(SCH_1):PU_JTAG_SPRV_TCK':
 C_SIGNAL='@baseboard_fab2_lib.baseboard_fab2(sch_1):pu_jtag_sprv_tck';
NODE_NAME     EU9E1 19
 '@BASEBOARD_FAB2_LIB.BASEBOARD_FAB2(SCH_1):PAGE139_I72@MSTR_INTEL.SPRINGVILLE(CHIPS)':
 'JTAG_CLK': CDS_PINID='JTAG_CLK';
NODE_NAME     R9E2 2
 '@BASEBOARD_FAB2_LIB.BASEBOARD_FAB2(SCH_1):PAGE139_I177@MSTR_DISCRETE.RES(CHIPS)':
 'B': CDS_PINID='B';
NET_NAME
'PU_JTAG_SPRV_TDI'
 '@BASEBOARD_FAB2_LIB.BASEBOARD_FAB2(SCH_1):PU_JTAG_SPRV_TDI':
 C_SIGNAL='@baseboard_fab2_lib.baseboard_fab2(sch_1):pu_jtag_sprv_tdi';
NODE_NAME     EU9E1 29
 '@BASEBOARD_FAB2_LIB.BASEBOARD_FAB2(SCH_1):PAGE139_I72@MSTR_INTEL.SPRINGVILLE(CHIPS)':
 'JTAG_TDI': CDS_PINID='JTAG_TDI';
NODE_NAME     R9E1 2
 '@BASEBOARD_FAB2_LIB.BASEBOARD_FAB2(SCH_1):PAGE139_I179@MSTR_DISCRETE.RES(CHIPS)':
 'B': CDS_PINID='B';
NET_NAME
'PU_JTAG_SPRV_TDO'
 '@BASEBOARD_FAB2_LIB.BASEBOARD_FAB2(SCH_1):PU_JTAG_SPRV_TDO':
 C_SIGNAL='@baseboard_fab2_lib.baseboard_fab2(sch_1):pu_jtag_sprv_tdo';
NODE_NAME     EU9E1 4
 '@BASEBOARD_FAB2_LIB.BASEBOARD_FAB2(SCH_1):PAGE139_I72@MSTR_INTEL.SPRINGVILLE(CHIPS)':
 'JTAG_TDO': CDS_PINID='JTAG_TDO';
NODE_NAME     R9E22 1
 '@BASEBOARD_FAB2_LIB.BASEBOARD_FAB2(SCH_1):PAGE139_I181@MSTR_DISCRETE.RES(CHIPS)':
 'A': CDS_PINID='A';
NET_NAME
'PU_JTAG_SPRV_TMS'
 '@BASEBOARD_FAB2_LIB.BASEBOARD_FAB2(SCH_1):PU_JTAG_SPRV_TMS':
 C_SIGNAL='@baseboard_fab2_lib.baseboard_fab2(sch_1):pu_jtag_sprv_tms';
NODE_NAME     EU9E1 18
 '@BASEBOARD_FAB2_LIB.BASEBOARD_FAB2(SCH_1):PAGE139_I72@MSTR_INTEL.SPRINGVILLE(CHIPS)':
 'JTAG_TMS': CDS_PINID='JTAG_TMS';
NODE_NAME     R9E3 2
 '@BASEBOARD_FAB2_LIB.BASEBOARD_FAB2(SCH_1):PAGE139_I178@MSTR_DISCRETE.RES(CHIPS)':
 'B': CDS_PINID='B';
NET_NAME
'PU_KEY_CONN_PIN2_R'
 '@BASEBOARD_FAB2_LIB.BASEBOARD_FAB2(SCH_1):PU_KEY_CONN_PIN2_R':
 C_SIGNAL='@baseboard_fab2_lib.baseboard_fab2(sch_1):pu_key_conn_pin2_r';
NODE_NAME     R9A16 1
 '@BASEBOARD_FAB2_LIB.BASEBOARD_FAB2(SCH_1):PAGE135_I129@MSTR_DISCRETE.RES(CHIPS)':
 'A': CDS_PINID='A';
NODE_NAME     J9A1 2
 '@BASEBOARD_FAB2_LIB.BASEBOARD_FAB2(SCH_1):PAGE135_I131@MSTR_CONN.CONN4_D42317002(CHIPS)':
 'IO2': CDS_PINID='IO2';
NET_NAME
'PU_LPC_CLKRUN_N'
 '@BASEBOARD_FAB2_LIB.BASEBOARD_FAB2(SCH_1):PU_LPC_CLKRUN_N':
 C_SIGNAL='@baseboard_fab2_lib.baseboard_fab2(sch_1):pu_lpc_clkrun_n';
NODE_NAME     U7C1 AB1
 '@BASEBOARD_FAB2_LIB.BASEBOARD_FAB2(SCH_1):PAGE119_I115@MSTR_U_PROC.LBG_CORE_QAT_EXT_D(CHIPS)':
 'GPP_A8_CLKRUN_N': CDS_PINID='GPP_A8_CLKRUN_N';
NODE_NAME     R7D8 2
 '@BASEBOARD_FAB2_LIB.BASEBOARD_FAB2(SCH_1):PAGE133_I200@MSTR_DISCRETE.RES(CHIPS)':
 'B': CDS_PINID='B';
NET_NAME
'PU_LPC_PME_N'
 '@BASEBOARD_FAB2_LIB.BASEBOARD_FAB2(SCH_1):PU_LPC_PME_N':
 C_SIGNAL='@baseboard_fab2_lib.baseboard_fab2(sch_1):pu_lpc_pme_n';
NODE_NAME     U7C1 AC2
 '@BASEBOARD_FAB2_LIB.BASEBOARD_FAB2(SCH_1):PAGE119_I115@MSTR_U_PROC.LBG_CORE_QAT_EXT_D(CHIPS)':
 'GPP_A11_PME_N': CDS_PINID='GPP_A11_PME_N';
NODE_NAME     R7D10 2
 '@BASEBOARD_FAB2_LIB.BASEBOARD_FAB2(SCH_1):PAGE133_I202@MSTR_DISCRETE.RES(CHIPS)':
 'B': CDS_PINID='B';
NET_NAME
'PU_M2_CLK_REQ_N'
 '@BASEBOARD_FAB2_LIB.BASEBOARD_FAB2(SCH_1):PU_M2_CLK_REQ_N':
 C_SIGNAL='@baseboard_fab2_lib.baseboard_fab2(sch_1):pu_m2_clk_req_n';
NODE_NAME     R8F36 2
 '@BASEBOARD_FAB2_LIB.BASEBOARD_FAB2(SCH_1):PAGE185_I136@MSTR_DISCRETE.RES(CHIPS)':
 'B': CDS_PINID='B';
NODE_NAME     J8F1 52
 '@BASEBOARD_FAB2_LIB.BASEBOARD_FAB2(SCH_1):PAGE185_I143@W_HDL.SKT-MINI67P-41-GP(CHIPS)':
 '52': CDS_PINID='\52\';
NET_NAME
'PU_NV_HOLD_N'
 '@BASEBOARD_FAB2_LIB.BASEBOARD_FAB2(SCH_1):PU_NV_HOLD_N':
 C_SIGNAL='@baseboard_fab2_lib.baseboard_fab2(sch_1):pu_nv_hold_n';
NODE_NAME     U9E1 7
 '@BASEBOARD_FAB2_LIB.BASEBOARD_FAB2(SCH_1):PAGE140_I1@MSTR_MEMORY.M25PE16(CHIPS)':
 'RESET_N': CDS_PINID='RESET_N';
NODE_NAME     R1R9 2
 '@BASEBOARD_FAB2_LIB.BASEBOARD_FAB2(SCH_1):PAGE140_I10@MSTR_DISCRETE.RES(CHIPS)':
 'B': CDS_PINID='B';
NET_NAME
'PU_NV_WP_N'
 '@BASEBOARD_FAB2_LIB.BASEBOARD_FAB2(SCH_1):PU_NV_WP_N':
 C_SIGNAL='@baseboard_fab2_lib.baseboard_fab2(sch_1):pu_nv_wp_n';
NODE_NAME     U9E1 3
 '@BASEBOARD_FAB2_LIB.BASEBOARD_FAB2(SCH_1):PAGE140_I1@MSTR_MEMORY.M25PE16(CHIPS)':
 'W_N': CDS_PINID='W_N';
NODE_NAME     R1R3 2
 '@BASEBOARD_FAB2_LIB.BASEBOARD_FAB2(SCH_1):PAGE140_I11@MSTR_DISCRETE.RES(CHIPS)':
 'B': CDS_PINID='B';
NET_NAME
'PU_PCH_TLS_ENABLE_STRAP'
 '@BASEBOARD_FAB2_LIB.BASEBOARD_FAB2(SCH_1):PU_PCH_TLS_ENABLE_STRAP':
 C_SIGNAL='@baseboard_fab2_lib.baseboard_fab2(sch_1):pu_pch_tls_enable_strap';
NODE_NAME     J8G1 27
 '@BASEBOARD_FAB2_LIB.BASEBOARD_FAB2(SCH_1):PAGE108_I258@MSTR_SCONN.SCONN200_H68296001(CHIPS)':
 'IO27': CDS_PINID='IO27';
NODE_NAME     U7C1 BY27
 '@BASEBOARD_FAB2_LIB.BASEBOARD_FAB2(SCH_1):PAGE119_I115@MSTR_U_PROC.LBG_CORE_QAT_EXT_D(CHIPS)':
 'GPP_C2_SMBALERT_N': CDS_PINID='GPP_C2_SMBALERT_N';
NODE_NAME     R8C18 2
 '@BASEBOARD_FAB2_LIB.BASEBOARD_FAB2(SCH_1):PAGE125_I40@MSTR_DISCRETE.RES(CHIPS)':
 'B': CDS_PINID='B';
NODE_NAME     R8C17 1
 '@BASEBOARD_FAB2_LIB.BASEBOARD_FAB2(SCH_1):PAGE125_I41@MSTR_DISCRETE.RES(CHIPS)':
 'A': CDS_PINID='A';
NET_NAME
'PU_PIROM_CPU1_ADDR0'
 '@BASEBOARD_FAB2_LIB.BASEBOARD_FAB2(SCH_1):PU_PIROM_CPU1_ADDR0':
 C_SIGNAL='@baseboard_fab2_lib.baseboard_fab2(sch_1):pu_pirom_cpu1_addr0';
NODE_NAME     U2D1 CU58
 '@BASEBOARD_FAB2_LIB.BASEBOARD_FAB2(SCH_1):PAGE55_I172@CHPSET_LIB.SKX_EXT_B(CHIPS)':
 'PIROM_ADDR'<0>: CDS_PINID='PIROM_ADDR(0)';
NODE_NAME     R1C34 2
 '@BASEBOARD_FAB2_LIB.BASEBOARD_FAB2(SCH_1):PAGE156_I320@MSTR_DISCRETE.RES(CHIPS)':
 'B': CDS_PINID='B';
NET_NAME
'PU_PVNN_PCH_PINALRT_N'
 '@BASEBOARD_FAB2_LIB.BASEBOARD_FAB2(SCH_1):PU_PVNN_PCH_PINALRT_N':
 C_SIGNAL='@baseboard_fab2_lib.baseboard_fab2(sch_1):pu_pvnn_pch_pinalrt_n';
NODE_NAME     EU8A1 12
 '@BASEBOARD_FAB2_LIB.BASEBOARD_FAB2(SCH_1):PAGE235_I229@MSTR_CONTROLLER.PXE1110B(CHIPS)':
 'PINALRT_N': CDS_PINID='PINALRT_N';
NODE_NAME     R8W8 2
 '@BASEBOARD_FAB2_LIB.BASEBOARD_FAB2(SCH_1):PAGE235_I249@MSTR_DISCRETE.RES(CHIPS)':
 'B': CDS_PINID='B';
NET_NAME
'PU_PVNN_PCH_VCLK'
 '@BASEBOARD_FAB2_LIB.BASEBOARD_FAB2(SCH_1):PU_PVNN_PCH_VCLK':
 C_SIGNAL='@baseboard_fab2_lib.baseboard_fab2(sch_1):pu_pvnn_pch_vclk';
NODE_NAME     EU8A1 15
 '@BASEBOARD_FAB2_LIB.BASEBOARD_FAB2(SCH_1):PAGE235_I229@MSTR_CONTROLLER.PXE1110B(CHIPS)':
 'VCLK': CDS_PINID='VCLK';
NODE_NAME     R8W2 1
 '@BASEBOARD_FAB2_LIB.BASEBOARD_FAB2(SCH_1):PAGE235_I247@MSTR_DISCRETE.RES(CHIPS)':
 'A': CDS_PINID='A';
NET_NAME
'PU_PVNN_PCH_VDIO'
 '@BASEBOARD_FAB2_LIB.BASEBOARD_FAB2(SCH_1):PU_PVNN_PCH_VDIO':
 C_SIGNAL='@baseboard_fab2_lib.baseboard_fab2(sch_1):pu_pvnn_pch_vdio';
NODE_NAME     EU8A1 16
 '@BASEBOARD_FAB2_LIB.BASEBOARD_FAB2(SCH_1):PAGE235_I229@MSTR_CONTROLLER.PXE1110B(CHIPS)':
 'VDIO': CDS_PINID='VDIO';
NODE_NAME     R8W3 2
 '@BASEBOARD_FAB2_LIB.BASEBOARD_FAB2(SCH_1):PAGE235_I248@MSTR_DISCRETE.RES(CHIPS)':
 'B': CDS_PINID='B';
NET_NAME
'PU_RST_PERST_BIT0'
 '@BASEBOARD_FAB2_LIB.BASEBOARD_FAB2(SCH_1):PU_RST_PERST_BIT0':
 C_SIGNAL='@baseboard_fab2_lib.baseboard_fab2(sch_1):pu_rst_perst_bit0';
NODE_NAME     U8D7 F4
 '@BASEBOARD_FAB2_LIB.BASEBOARD_FAB2(SCH_1):PAGE190_I179@MSTR_MEMORY.LCMXO2_A(CHIPS)':
 'PL3C': CDS_PINID='PL3C';
NODE_NAME     R2R1 2
 '@BASEBOARD_FAB2_LIB.BASEBOARD_FAB2(SCH_1):PAGE192_I34@MSTR_DISCRETE.RES(CHIPS)':
 'B': CDS_PINID='B';
NET_NAME
'PU_RST_PERST_BIT1'
 '@BASEBOARD_FAB2_LIB.BASEBOARD_FAB2(SCH_1):PU_RST_PERST_BIT1':
 C_SIGNAL='@baseboard_fab2_lib.baseboard_fab2(sch_1):pu_rst_perst_bit1';
NODE_NAME     U8D7 B9
 '@BASEBOARD_FAB2_LIB.BASEBOARD_FAB2(SCH_1):PAGE191_I59@MSTR_MEMORY.LCMXO2_A(CHIPS)':
 'PT19A': CDS_PINID='PT19A';
NODE_NAME     R7E6 2
 '@BASEBOARD_FAB2_LIB.BASEBOARD_FAB2(SCH_1):PAGE192_I33@MSTR_DISCRETE.RES(CHIPS)':
 'B': CDS_PINID='B';
NET_NAME
'PU_SPI0_RST'
 '@BASEBOARD_FAB2_LIB.BASEBOARD_FAB2(SCH_1):PU_SPI0_RST':
 C_SIGNAL='@baseboard_fab2_lib.baseboard_fab2(sch_1):pu_spi0_rst';
NODE_NAME     R7F6 2
 '@BASEBOARD_FAB2_LIB.BASEBOARD_FAB2(SCH_1):PAGE153_I90@MSTR_DISCRETE.RES(CHIPS)':
 'B': CDS_PINID='B';
NODE_NAME     U7F1 3
 '@BASEBOARD_FAB2_LIB.BASEBOARD_FAB2(SCH_1):PAGE153_I146@MSTR_MEMORY.W25Q256(CHIPS)':
 'RESET_N': CDS_PINID='RESET_N';
NET_NAME
'PU_SPI1_RST'
 '@BASEBOARD_FAB2_LIB.BASEBOARD_FAB2(SCH_1):PU_SPI1_RST':
 C_SIGNAL='@baseboard_fab2_lib.baseboard_fab2(sch_1):pu_spi1_rst';
NODE_NAME     R3T3 2
 '@BASEBOARD_FAB2_LIB.BASEBOARD_FAB2(SCH_1):PAGE153_I150@MSTR_DISCRETE.RES(CHIPS)':
 'B': CDS_PINID='B';
NODE_NAME     U3T1 3
 '@BASEBOARD_FAB2_LIB.BASEBOARD_FAB2(SCH_1):PAGE153_I185@W_HDL.W25Q256FVFIG-GP(CHIPS)':
 'RESET#': CDS_PINID='\reset#\';
NET_NAME
'PU_SPI_BMC_BT_CS0_N'
 '@BASEBOARD_FAB2_LIB.BASEBOARD_FAB2(SCH_1):PU_SPI_BMC_BT_CS0_N':
 C_SIGNAL='@baseboard_fab2_lib.baseboard_fab2(sch_1):pu_spi_bmc_bt_cs0_n';
NODE_NAME     J9G1 8
 '@BASEBOARD_FAB2_LIB.BASEBOARD_FAB2(SCH_1):PAGE137_I128@MSTR_CONN.CONN12_C73564003(CHIPS)':
 'IO8': CDS_PINID='IO8';
NODE_NAME     RN8F1 2
 '@BASEBOARD_FAB2_LIB.BASEBOARD_FAB2(SCH_1):PAGE137_I142@MSTR_DISCRETE.RES(CHIPS)':
 'B': CDS_PINID='B';
NET_NAME
'PU_SPI_BMC_BT_HOLD_N'
 '@BASEBOARD_FAB2_LIB.BASEBOARD_FAB2(SCH_1):PU_SPI_BMC_BT_HOLD_N':
 C_SIGNAL='@baseboard_fab2_lib.baseboard_fab2(sch_1):pu_spi_bmc_bt_hold_n';
NODE_NAME     R8F14 2
 '@BASEBOARD_FAB2_LIB.BASEBOARD_FAB2(SCH_1):PAGE162_I9@MSTR_DISCRETE.RES(CHIPS)':
 'B': CDS_PINID='B';
NODE_NAME     U8F2 1
 '@BASEBOARD_FAB2_LIB.BASEBOARD_FAB2(SCH_1):PAGE162_I32@MSTR_MEMORY.W25Q128(CHIPS)':
 'HOLD_N_IO'<3>: CDS_PINID='HOLD_N_IO(3)';
NET_NAME
'PU_SPI_BMC_BT_WP_N'
 '@BASEBOARD_FAB2_LIB.BASEBOARD_FAB2(SCH_1):PU_SPI_BMC_BT_WP_N':
 C_SIGNAL='@baseboard_fab2_lib.baseboard_fab2(sch_1):pu_spi_bmc_bt_wp_n';
NODE_NAME     R8F34 2
 '@BASEBOARD_FAB2_LIB.BASEBOARD_FAB2(SCH_1):PAGE162_I22@MSTR_DISCRETE.RES(CHIPS)':
 'B': CDS_PINID='B';
NODE_NAME     R8F35 1
 '@BASEBOARD_FAB2_LIB.BASEBOARD_FAB2(SCH_1):PAGE162_I24@MSTR_DISCRETE.RES(CHIPS)':
 'A': CDS_PINID='A';
NODE_NAME     U8F2 9
 '@BASEBOARD_FAB2_LIB.BASEBOARD_FAB2(SCH_1):PAGE162_I32@MSTR_MEMORY.W25Q128(CHIPS)':
 'WP_N_IO'<2>: CDS_PINID='WP_N_IO(2)';
NET_NAME
'PU_SPI_FLASH_RESET_2_N'
 '@BASEBOARD_FAB2_LIB.BASEBOARD_FAB2(SCH_1):PU_SPI_FLASH_RESET_2_N':
 C_SIGNAL='@baseboard_fab2_lib.baseboard_fab2(sch_1):pu_spi_flash_reset_2_n';
NODE_NAME     R8F16 2
 '@BASEBOARD_FAB2_LIB.BASEBOARD_FAB2(SCH_1):PAGE162_I8@MSTR_DISCRETE.RES(CHIPS)':
 'B': CDS_PINID='B';
NODE_NAME     U8F2 3
 '@BASEBOARD_FAB2_LIB.BASEBOARD_FAB2(SCH_1):PAGE162_I32@MSTR_MEMORY.W25Q128(CHIPS)':
 'RESET_N': CDS_PINID='RESET_N';
NET_NAME
'PU_SPRV_LAN_PWR_GOOD'
 '@BASEBOARD_FAB2_LIB.BASEBOARD_FAB2(SCH_1):PU_SPRV_LAN_PWR_GOOD':
 C_SIGNAL='@baseboard_fab2_lib.baseboard_fab2(sch_1):pu_sprv_lan_pwr_good';
NODE_NAME     EU9E1 1
 '@BASEBOARD_FAB2_LIB.BASEBOARD_FAB2(SCH_1):PAGE139_I72@MSTR_INTEL.SPRINGVILLE(CHIPS)':
 'LAN_PWR_GOOD': CDS_PINID='LAN_PWR_GOOD';
NODE_NAME     R9F5 2
 '@BASEBOARD_FAB2_LIB.BASEBOARD_FAB2(SCH_1):PAGE139_I173@MSTR_DISCRETE.RES(CHIPS)':
 'B': CDS_PINID='B';
NET_NAME
'PU_THERMTRIP_FORCE_N'
 '@BASEBOARD_FAB2_LIB.BASEBOARD_FAB2(SCH_1):PU_THERMTRIP_FORCE_N':
 C_SIGNAL='@baseboard_fab2_lib.baseboard_fab2(sch_1):pu_thermtrip_force_n';
NODE_NAME     U8D7 A12
 '@BASEBOARD_FAB2_LIB.BASEBOARD_FAB2(SCH_1):PAGE191_I59@MSTR_MEMORY.LCMXO2_A(CHIPS)':
 'PT22B': CDS_PINID='PT22B';
NODE_NAME     R7E5 2
 '@BASEBOARD_FAB2_LIB.BASEBOARD_FAB2(SCH_1):PAGE192_I38@MSTR_DISCRETE.RES(CHIPS)':
 'B': CDS_PINID='B';
NET_NAME
'PU_TMP421_1_A1'
 '@BASEBOARD_FAB2_LIB.BASEBOARD_FAB2(SCH_1):PU_TMP421_1_A1':
 C_SIGNAL='@baseboard_fab2_lib.baseboard_fab2(sch_1):pu_tmp421_1_a1';
NODE_NAME     U9B4 3
 '@BASEBOARD_FAB2_LIB.BASEBOARD_FAB2(SCH_1):PAGE167_I1@MSTR_ANALOG.TMP421(CHIPS)':
 'A'<1>: CDS_PINID='A(1)';
NODE_NAME     R9B6 2
 '@BASEBOARD_FAB2_LIB.BASEBOARD_FAB2(SCH_1):PAGE167_I35@MSTR_DISCRETE.RES(CHIPS)':
 'B': CDS_PINID='B';
NET_NAME
'PU_TMP421_2_A0'
 '@BASEBOARD_FAB2_LIB.BASEBOARD_FAB2(SCH_1):PU_TMP421_2_A0':
 C_SIGNAL='@baseboard_fab2_lib.baseboard_fab2(sch_1):pu_tmp421_2_a0';
NODE_NAME     U1E1 4
 '@BASEBOARD_FAB2_LIB.BASEBOARD_FAB2(SCH_1):PAGE167_I30@MSTR_ANALOG.TMP421(CHIPS)':
 'A'<0>: CDS_PINID='A(0)';
NODE_NAME     R1E9 2
 '@BASEBOARD_FAB2_LIB.BASEBOARD_FAB2(SCH_1):PAGE167_I34@MSTR_DISCRETE.RES(CHIPS)':
 'B': CDS_PINID='B';
NET_NAME
'PU_TPM_SPI_BMC_HOLD_N'
 '@BASEBOARD_FAB2_LIB.BASEBOARD_FAB2(SCH_1):PU_TPM_SPI_BMC_HOLD_N':
 C_SIGNAL='@baseboard_fab2_lib.baseboard_fab2(sch_1):pu_tpm_spi_bmc_hold_n';
NODE_NAME     RN8F3 2
 '@BASEBOARD_FAB2_LIB.BASEBOARD_FAB2(SCH_1):PAGE246_I11@MSTR_DISCRETE.RES(CHIPS)':
 'B': CDS_PINID='B';
NODE_NAME     UN8F2 1
 '@BASEBOARD_FAB2_LIB.BASEBOARD_FAB2(SCH_1):PAGE246_I17@MSTR_MEMORY.W25Q256(CHIPS)':
 'HOLD_N_IO'<3>: CDS_PINID='HOLD_N_IO(3)';
NET_NAME
'PU_TPM_SPI_FLASH_RESET_2_N'
 '@BASEBOARD_FAB2_LIB.BASEBOARD_FAB2(SCH_1):PU_TPM_SPI_FLASH_RESET_2_N':
 C_SIGNAL='@baseboard_fab2_lib.baseboard_fab2(sch_1):pu_tpm_spi_flash_reset_2_n';
NODE_NAME     RN8F4 2
 '@BASEBOARD_FAB2_LIB.BASEBOARD_FAB2(SCH_1):PAGE246_I12@MSTR_DISCRETE.RES(CHIPS)':
 'B': CDS_PINID='B';
NODE_NAME     UN8F2 3
 '@BASEBOARD_FAB2_LIB.BASEBOARD_FAB2(SCH_1):PAGE246_I17@MSTR_MEMORY.W25Q256(CHIPS)':
 'RESET_N': CDS_PINID='RESET_N';
NET_NAME
'PU_TRI_STATE_EN'
 '@BASEBOARD_FAB2_LIB.BASEBOARD_FAB2(SCH_1):PU_TRI_STATE_EN':
 C_SIGNAL='@baseboard_fab2_lib.baseboard_fab2(sch_1):pu_tri_state_en';
NODE_NAME     U8E4 1
 '@BASEBOARD_FAB2_LIB.BASEBOARD_FAB2(SCH_1):PAGE142_I1@MSTR_TTL.TTL1G126_A(CHIPS)':
 'OE': CDS_PINID='OE';
NODE_NAME     R8E23 1
 '@BASEBOARD_FAB2_LIB.BASEBOARD_FAB2(SCH_1):PAGE142_I3@MSTR_DISCRETE.RES(CHIPS)':
 'A': CDS_PINID='A';
NET_NAME
'PU_UV_HIGH_SET'
 '@BASEBOARD_FAB2_LIB.BASEBOARD_FAB2(SCH_1):PU_UV_HIGH_SET':
 C_SIGNAL='@baseboard_fab2_lib.baseboard_fab2(sch_1):pu_uv_high_set';
NODE_NAME     J9G1 1
 '@BASEBOARD_FAB2_LIB.BASEBOARD_FAB2(SCH_1):PAGE137_I128@MSTR_CONN.CONN12_C73564003(CHIPS)':
 'IO1': CDS_PINID='IO1';
NODE_NAME     R6W1 2
 '@BASEBOARD_FAB2_LIB.BASEBOARD_FAB2(SCH_1):PAGE137_I149@MSTR_DISCRETE.RES(CHIPS)':
 'B': CDS_PINID='B';
NET_NAME
'PU_VR_PVCCIN_CPU0_FLT1_SMBALT_N'
 '@BASEBOARD_FAB2_LIB.BASEBOARD_FAB2(SCH_1):PU_VR_PVCCIN_CPU0_FLT1_SMBALT_N_IMON':
 C_SIGNAL='@baseboard_fab2_lib.baseboard_fab2(sch_1):pu_vr_pvccin_cpu0_flt1_smba~
lt_n_imon';
NODE_NAME     R4E20 2
 '@BASEBOARD_FAB2_LIB.BASEBOARD_FAB2(SCH_1):PAGE201_I116@MSTR_DISCRETE.RES(CHIPS)':
 'B': CDS_PINID='B';
NODE_NAME     EU4D4 20
 '@BASEBOARD_FAB2_LIB.BASEBOARD_FAB2(SCH_1):PAGE201_I155@MSTR_CONTROLLER.PXE1610B(CHIPS)':
 'MP2': CDS_PINID='MP2';
NET_NAME
'PU_VR_PVCCIN_CPU0_IMON'
 '@BASEBOARD_FAB2_LIB.BASEBOARD_FAB2(SCH_1):PU_VR_PVCCIN_CPU0_IMON':
 C_SIGNAL='@baseboard_fab2_lib.baseboard_fab2(sch_1):pu_vr_pvccin_cpu0_imon';
NODE_NAME     R4D31 2
 '@BASEBOARD_FAB2_LIB.BASEBOARD_FAB2(SCH_1):PAGE201_I22@MSTR_DISCRETE.RES(CHIPS)':
 'B': CDS_PINID='B';
NODE_NAME     EU4D4 39
 '@BASEBOARD_FAB2_LIB.BASEBOARD_FAB2(SCH_1):PAGE201_I155@MSTR_CONTROLLER.PXE1610B(CHIPS)':
 'MP3': CDS_PINID='MP3';
NET_NAME
'PU_VR_PVCCIN_CPU1_FLT1_SMBALT_N'
 '@BASEBOARD_FAB2_LIB.BASEBOARD_FAB2(SCH_1):PU_VR_PVCCIN_CPU1_FLT1_SMBALT_N_IMON':
 C_SIGNAL='@baseboard_fab2_lib.baseboard_fab2(sch_1):pu_vr_pvccin_cpu1_flt1_smba~
lt_n_imon';
NODE_NAME     R1D53 2
 '@BASEBOARD_FAB2_LIB.BASEBOARD_FAB2(SCH_1):PAGE206_I33@MSTR_DISCRETE.RES(CHIPS)':
 'B': CDS_PINID='B';
NODE_NAME     EU1C2 20
 '@BASEBOARD_FAB2_LIB.BASEBOARD_FAB2(SCH_1):PAGE206_I130@MSTR_CONTROLLER.PXE1610B(CHIPS)':
 'MP2': CDS_PINID='MP2';
NET_NAME
'PU_VR_PVCCIN_CPU1_IMON'
 '@BASEBOARD_FAB2_LIB.BASEBOARD_FAB2(SCH_1):PU_VR_PVCCIN_CPU1_IMON':
 C_SIGNAL='@baseboard_fab2_lib.baseboard_fab2(sch_1):pu_vr_pvccin_cpu1_imon';
NODE_NAME     R1C18 2
 '@BASEBOARD_FAB2_LIB.BASEBOARD_FAB2(SCH_1):PAGE206_I34@MSTR_DISCRETE.RES(CHIPS)':
 'B': CDS_PINID='B';
NODE_NAME     EU1C2 39
 '@BASEBOARD_FAB2_LIB.BASEBOARD_FAB2(SCH_1):PAGE206_I130@MSTR_CONTROLLER.PXE1610B(CHIPS)':
 'MP3': CDS_PINID='MP3';
NET_NAME
'PU_VR_PVCCIO_CPU0_FAULT1'
 '@BASEBOARD_FAB2_LIB.BASEBOARD_FAB2(SCH_1):PU_VR_PVCCIO_CPU0_FAULT1':
 C_SIGNAL='@baseboard_fab2_lib.baseboard_fab2(sch_1):pu_vr_pvccio_cpu0_fault1';
NODE_NAME     R3N23 2
 '@BASEBOARD_FAB2_LIB.BASEBOARD_FAB2(SCH_1):PAGE211_I60@MSTR_DISCRETE.RES(CHIPS)':
 'B': CDS_PINID='B';
NODE_NAME     EU3P1 32
 '@BASEBOARD_FAB2_LIB.BASEBOARD_FAB2(SCH_1):PAGE211_I93@MSTR_CONTROLLER.PXE1110B(CHIPS)':
 'MP4': CDS_PINID='MP4';
NET_NAME
'PU_VR_PVCCIO_CPU1_FAULT1'
 '@BASEBOARD_FAB2_LIB.BASEBOARD_FAB2(SCH_1):PU_VR_PVCCIO_CPU1_FAULT1':
 C_SIGNAL='@baseboard_fab2_lib.baseboard_fab2(sch_1):pu_vr_pvccio_cpu1_fault1';
NODE_NAME     R6P49 2
 '@BASEBOARD_FAB2_LIB.BASEBOARD_FAB2(SCH_1):PAGE213_I14@MSTR_DISCRETE.RES(CHIPS)':
 'B': CDS_PINID='B';
NODE_NAME     EU4D5 32
 '@BASEBOARD_FAB2_LIB.BASEBOARD_FAB2(SCH_1):PAGE213_I96@MSTR_CONTROLLER.PXE1110B(CHIPS)':
 'MP4': CDS_PINID='MP4';
NET_NAME
'PU_VR_PVDDQ_ABC_FAULT1'
 '@BASEBOARD_FAB2_LIB.BASEBOARD_FAB2(SCH_1):PU_VR_PVDDQ_ABC_FAULT1':
 C_SIGNAL='@baseboard_fab2_lib.baseboard_fab2(sch_1):pu_vr_pvddq_abc_fault1';
NODE_NAME     EU7G1 13
 '@BASEBOARD_FAB2_LIB.BASEBOARD_FAB2(SCH_1):PAGE215_I69@MSTR_CONTROLLER.PXM1310B(CHIPS)':
 'MP0': CDS_PINID='MP0';
NODE_NAME     R12W25 1
 '@BASEBOARD_FAB2_LIB.BASEBOARD_FAB2(SCH_1):PAGE215_I74@MSTR_DISCRETE.RES(CHIPS)':
 'A': CDS_PINID='A';
NET_NAME
'PU_VR_PVDDQ_DEF_FAULT1'
 '@BASEBOARD_FAB2_LIB.BASEBOARD_FAB2(SCH_1):PU_VR_PVDDQ_DEF_FAULT1':
 C_SIGNAL='@baseboard_fab2_lib.baseboard_fab2(sch_1):pu_vr_pvddq_def_fault1';
NODE_NAME     EU7A5 13
 '@BASEBOARD_FAB2_LIB.BASEBOARD_FAB2(SCH_1):PAGE218_I69@MSTR_CONTROLLER.PXM1310B(CHIPS)':
 'MP0': CDS_PINID='MP0';
NODE_NAME     R12W28 1
 '@BASEBOARD_FAB2_LIB.BASEBOARD_FAB2(SCH_1):PAGE218_I75@MSTR_DISCRETE.RES(CHIPS)':
 'A': CDS_PINID='A';
NET_NAME
'PU_VR_PVDDQ_GHJ_FAULT1'
 '@BASEBOARD_FAB2_LIB.BASEBOARD_FAB2(SCH_1):PU_VR_PVDDQ_GHJ_FAULT1':
 C_SIGNAL='@baseboard_fab2_lib.baseboard_fab2(sch_1):pu_vr_pvddq_ghj_fault1';
NODE_NAME     EU1G2 13
 '@BASEBOARD_FAB2_LIB.BASEBOARD_FAB2(SCH_1):PAGE223_I69@MSTR_CONTROLLER.PXM1310B(CHIPS)':
 'MP0': CDS_PINID='MP0';
NODE_NAME     R12W31 1
 '@BASEBOARD_FAB2_LIB.BASEBOARD_FAB2(SCH_1):PAGE223_I75@MSTR_DISCRETE.RES(CHIPS)':
 'A': CDS_PINID='A';
NET_NAME
'PU_VR_PVDDQ_KLM_FAULT1'
 '@BASEBOARD_FAB2_LIB.BASEBOARD_FAB2(SCH_1):PU_VR_PVDDQ_KLM_FAULT1':
 C_SIGNAL='@baseboard_fab2_lib.baseboard_fab2(sch_1):pu_vr_pvddq_klm_fault1';
NODE_NAME     EU1B1 13
 '@BASEBOARD_FAB2_LIB.BASEBOARD_FAB2(SCH_1):PAGE226_I69@MSTR_CONTROLLER.PXM1310B(CHIPS)':
 'MP0': CDS_PINID='MP0';
NODE_NAME     R12W34 1
 '@BASEBOARD_FAB2_LIB.BASEBOARD_FAB2(SCH_1):PAGE226_I74@MSTR_DISCRETE.RES(CHIPS)':
 'A': CDS_PINID='A';
NET_NAME
'PU_VR_PVNN_PCH_FAULT1'
 '@BASEBOARD_FAB2_LIB.BASEBOARD_FAB2(SCH_1):PU_VR_PVNN_PCH_FAULT1':
 C_SIGNAL='@baseboard_fab2_lib.baseboard_fab2(sch_1):pu_vr_pvnn_pch_fault1';
NODE_NAME     R2L24 2
 '@BASEBOARD_FAB2_LIB.BASEBOARD_FAB2(SCH_1):PAGE235_I148@MSTR_DISCRETE.RES(CHIPS)':
 'B': CDS_PINID='B';
NODE_NAME     EU8A1 32
 '@BASEBOARD_FAB2_LIB.BASEBOARD_FAB2(SCH_1):PAGE235_I229@MSTR_CONTROLLER.PXE1110B(CHIPS)':
 'MP4': CDS_PINID='MP4';
NET_NAME
'PVCCIN_CPU0'
 '@BASEBOARD_FAB2_LIB.BASEBOARD_FAB2(SCH_1):PVCCIN_CPU0':
 C_SIGNAL='@baseboard_fab2_lib.baseboard_fab2(sch_1):pvccin_cpu0';
NODE_NAME     R5P1 1
 '@BASEBOARD_FAB2_LIB.BASEBOARD_FAB2(SCH_1):PAGE37_I309@MSTR_DISCRETE.RES(CHIPS)':
 'A': CDS_PINID='A';
NODE_NAME     U5D1 BN78
 '@BASEBOARD_FAB2_LIB.BASEBOARD_FAB2(SCH_1):PAGE37_I310@CHPSET_LIB.SKX_EXT_B(CHIPS)':
 'VCCIN'<130>: CDS_PINID='VCCIN(130)';
NODE_NAME     U5D1 BN76
 '@BASEBOARD_FAB2_LIB.BASEBOARD_FAB2(SCH_1):PAGE37_I310@CHPSET_LIB.SKX_EXT_B(CHIPS)':
 'VCCIN'<131>: CDS_PINID='VCCIN(131)';
NODE_NAME     U5D1 BN74
 '@BASEBOARD_FAB2_LIB.BASEBOARD_FAB2(SCH_1):PAGE37_I310@CHPSET_LIB.SKX_EXT_B(CHIPS)':
 'VCCIN'<132>: CDS_PINID='VCCIN(132)';
NODE_NAME     U5D1 BN72
 '@BASEBOARD_FAB2_LIB.BASEBOARD_FAB2(SCH_1):PAGE37_I310@CHPSET_LIB.SKX_EXT_B(CHIPS)':
 'VCCIN'<133>: CDS_PINID='VCCIN(133)';
NODE_NAME     U5D1 BN70
 '@BASEBOARD_FAB2_LIB.BASEBOARD_FAB2(SCH_1):PAGE37_I310@CHPSET_LIB.SKX_EXT_B(CHIPS)':
 'VCCIN'<134>: CDS_PINID='VCCIN(134)';
NODE_NAME     U5D1 BN68
 '@BASEBOARD_FAB2_LIB.BASEBOARD_FAB2(SCH_1):PAGE37_I310@CHPSET_LIB.SKX_EXT_B(CHIPS)':
 'VCCIN'<135>: CDS_PINID='VCCIN(135)';
NODE_NAME     U5D1 BN66
 '@BASEBOARD_FAB2_LIB.BASEBOARD_FAB2(SCH_1):PAGE37_I310@CHPSET_LIB.SKX_EXT_B(CHIPS)':
 'VCCIN'<136>: CDS_PINID='VCCIN(136)';
NODE_NAME     U5D1 BN64
 '@BASEBOARD_FAB2_LIB.BASEBOARD_FAB2(SCH_1):PAGE37_I310@CHPSET_LIB.SKX_EXT_B(CHIPS)':
 'VCCIN'<137>: CDS_PINID='VCCIN(137)';
NODE_NAME     U5D1 BN62
 '@BASEBOARD_FAB2_LIB.BASEBOARD_FAB2(SCH_1):PAGE37_I310@CHPSET_LIB.SKX_EXT_B(CHIPS)':
 'VCCIN'<138>: CDS_PINID='VCCIN(138)';
NODE_NAME     U5D1 BN60
 '@BASEBOARD_FAB2_LIB.BASEBOARD_FAB2(SCH_1):PAGE37_I310@CHPSET_LIB.SKX_EXT_B(CHIPS)':
 'VCCIN'<139>: CDS_PINID='VCCIN(139)';
NODE_NAME     U5D1 BM83
 '@BASEBOARD_FAB2_LIB.BASEBOARD_FAB2(SCH_1):PAGE37_I310@CHPSET_LIB.SKX_EXT_B(CHIPS)':
 'VCCIN'<140>: CDS_PINID='VCCIN(140)';
NODE_NAME     U5D1 BM81
 '@BASEBOARD_FAB2_LIB.BASEBOARD_FAB2(SCH_1):PAGE37_I310@CHPSET_LIB.SKX_EXT_B(CHIPS)':
 'VCCIN'<141>: CDS_PINID='VCCIN(141)';
NODE_NAME     U5D1 BM79
 '@BASEBOARD_FAB2_LIB.BASEBOARD_FAB2(SCH_1):PAGE37_I310@CHPSET_LIB.SKX_EXT_B(CHIPS)':
 'VCCIN'<142>: CDS_PINID='VCCIN(142)';
NODE_NAME     U5D1 BM77
 '@BASEBOARD_FAB2_LIB.BASEBOARD_FAB2(SCH_1):PAGE37_I310@CHPSET_LIB.SKX_EXT_B(CHIPS)':
 'VCCIN'<143>: CDS_PINID='VCCIN(143)';
NODE_NAME     U5D1 BM75
 '@BASEBOARD_FAB2_LIB.BASEBOARD_FAB2(SCH_1):PAGE37_I310@CHPSET_LIB.SKX_EXT_B(CHIPS)':
 'VCCIN'<144>: CDS_PINID='VCCIN(144)';
NODE_NAME     U5D1 BM73
 '@BASEBOARD_FAB2_LIB.BASEBOARD_FAB2(SCH_1):PAGE37_I310@CHPSET_LIB.SKX_EXT_B(CHIPS)':
 'VCCIN'<145>: CDS_PINID='VCCIN(145)';
NODE_NAME     U5D1 BM71
 '@BASEBOARD_FAB2_LIB.BASEBOARD_FAB2(SCH_1):PAGE37_I310@CHPSET_LIB.SKX_EXT_B(CHIPS)':
 'VCCIN'<146>: CDS_PINID='VCCIN(146)';
NODE_NAME     U5D1 BM69
 '@BASEBOARD_FAB2_LIB.BASEBOARD_FAB2(SCH_1):PAGE37_I310@CHPSET_LIB.SKX_EXT_B(CHIPS)':
 'VCCIN'<147>: CDS_PINID='VCCIN(147)';
NODE_NAME     U5D1 BM67
 '@BASEBOARD_FAB2_LIB.BASEBOARD_FAB2(SCH_1):PAGE37_I310@CHPSET_LIB.SKX_EXT_B(CHIPS)':
 'VCCIN'<148>: CDS_PINID='VCCIN(148)';
NODE_NAME     U5D1 BM65
 '@BASEBOARD_FAB2_LIB.BASEBOARD_FAB2(SCH_1):PAGE37_I310@CHPSET_LIB.SKX_EXT_B(CHIPS)':
 'VCCIN'<149>: CDS_PINID='VCCIN(149)';
NODE_NAME     U5D1 BM63
 '@BASEBOARD_FAB2_LIB.BASEBOARD_FAB2(SCH_1):PAGE37_I310@CHPSET_LIB.SKX_EXT_B(CHIPS)':
 'VCCIN'<150>: CDS_PINID='VCCIN(150)';
NODE_NAME     U5D1 BM61
 '@BASEBOARD_FAB2_LIB.BASEBOARD_FAB2(SCH_1):PAGE37_I310@CHPSET_LIB.SKX_EXT_B(CHIPS)':
 'VCCIN'<151>: CDS_PINID='VCCIN(151)';
NODE_NAME     U5D1 BL84
 '@BASEBOARD_FAB2_LIB.BASEBOARD_FAB2(SCH_1):PAGE37_I310@CHPSET_LIB.SKX_EXT_B(CHIPS)':
 'VCCIN'<152>: CDS_PINID='VCCIN(152)';
NODE_NAME     U5D1 BL62
 '@BASEBOARD_FAB2_LIB.BASEBOARD_FAB2(SCH_1):PAGE37_I310@CHPSET_LIB.SKX_EXT_B(CHIPS)':
 'VCCIN'<153>: CDS_PINID='VCCIN(153)';
NODE_NAME     U5D1 BL60
 '@BASEBOARD_FAB2_LIB.BASEBOARD_FAB2(SCH_1):PAGE37_I310@CHPSET_LIB.SKX_EXT_B(CHIPS)':
 'VCCIN'<154>: CDS_PINID='VCCIN(154)';
NODE_NAME     U5D1 BK83
 '@BASEBOARD_FAB2_LIB.BASEBOARD_FAB2(SCH_1):PAGE37_I310@CHPSET_LIB.SKX_EXT_B(CHIPS)':
 'VCCIN'<155>: CDS_PINID='VCCIN(155)';
NODE_NAME     U5D1 BK81
 '@BASEBOARD_FAB2_LIB.BASEBOARD_FAB2(SCH_1):PAGE37_I310@CHPSET_LIB.SKX_EXT_B(CHIPS)':
 'VCCIN'<156>: CDS_PINID='VCCIN(156)';
NODE_NAME     U5D1 BK79
 '@BASEBOARD_FAB2_LIB.BASEBOARD_FAB2(SCH_1):PAGE37_I310@CHPSET_LIB.SKX_EXT_B(CHIPS)':
 'VCCIN'<157>: CDS_PINID='VCCIN(157)';
NODE_NAME     U5D1 BK77
 '@BASEBOARD_FAB2_LIB.BASEBOARD_FAB2(SCH_1):PAGE37_I310@CHPSET_LIB.SKX_EXT_B(CHIPS)':
 'VCCIN'<158>: CDS_PINID='VCCIN(158)';
NODE_NAME     U5D1 BK75
 '@BASEBOARD_FAB2_LIB.BASEBOARD_FAB2(SCH_1):PAGE37_I310@CHPSET_LIB.SKX_EXT_B(CHIPS)':
 'VCCIN'<159>: CDS_PINID='VCCIN(159)';
NODE_NAME     U5D1 BK73
 '@BASEBOARD_FAB2_LIB.BASEBOARD_FAB2(SCH_1):PAGE37_I310@CHPSET_LIB.SKX_EXT_B(CHIPS)':
 'VCCIN'<160>: CDS_PINID='VCCIN(160)';
NODE_NAME     U5D1 BK71
 '@BASEBOARD_FAB2_LIB.BASEBOARD_FAB2(SCH_1):PAGE37_I310@CHPSET_LIB.SKX_EXT_B(CHIPS)':
 'VCCIN'<161>: CDS_PINID='VCCIN(161)';
NODE_NAME     U5D1 BK69
 '@BASEBOARD_FAB2_LIB.BASEBOARD_FAB2(SCH_1):PAGE37_I310@CHPSET_LIB.SKX_EXT_B(CHIPS)':
 'VCCIN'<162>: CDS_PINID='VCCIN(162)';
NODE_NAME     U5D1 BK67
 '@BASEBOARD_FAB2_LIB.BASEBOARD_FAB2(SCH_1):PAGE37_I310@CHPSET_LIB.SKX_EXT_B(CHIPS)':
 'VCCIN'<163>: CDS_PINID='VCCIN(163)';
NODE_NAME     U5D1 BK65
 '@BASEBOARD_FAB2_LIB.BASEBOARD_FAB2(SCH_1):PAGE37_I310@CHPSET_LIB.SKX_EXT_B(CHIPS)':
 'VCCIN'<164>: CDS_PINID='VCCIN(164)';
NODE_NAME     U5D1 BK63
 '@BASEBOARD_FAB2_LIB.BASEBOARD_FAB2(SCH_1):PAGE37_I310@CHPSET_LIB.SKX_EXT_B(CHIPS)':
 'VCCIN'<165>: CDS_PINID='VCCIN(165)';
NODE_NAME     U5D1 BK61
 '@BASEBOARD_FAB2_LIB.BASEBOARD_FAB2(SCH_1):PAGE37_I310@CHPSET_LIB.SKX_EXT_B(CHIPS)':
 'VCCIN'<166>: CDS_PINID='VCCIN(166)';
NODE_NAME     U5D1 BJ84
 '@BASEBOARD_FAB2_LIB.BASEBOARD_FAB2(SCH_1):PAGE37_I310@CHPSET_LIB.SKX_EXT_B(CHIPS)':
 'VCCIN'<167>: CDS_PINID='VCCIN(167)';
NODE_NAME     U5D1 BJ82
 '@BASEBOARD_FAB2_LIB.BASEBOARD_FAB2(SCH_1):PAGE37_I310@CHPSET_LIB.SKX_EXT_B(CHIPS)':
 'VCCIN'<168>: CDS_PINID='VCCIN(168)';
NODE_NAME     U5D1 BJ80
 '@BASEBOARD_FAB2_LIB.BASEBOARD_FAB2(SCH_1):PAGE37_I310@CHPSET_LIB.SKX_EXT_B(CHIPS)':
 'VCCIN'<169>: CDS_PINID='VCCIN(169)';
NODE_NAME     U5D1 BJ78
 '@BASEBOARD_FAB2_LIB.BASEBOARD_FAB2(SCH_1):PAGE37_I310@CHPSET_LIB.SKX_EXT_B(CHIPS)':
 'VCCIN'<170>: CDS_PINID='VCCIN(170)';
NODE_NAME     U5D1 BJ76
 '@BASEBOARD_FAB2_LIB.BASEBOARD_FAB2(SCH_1):PAGE37_I310@CHPSET_LIB.SKX_EXT_B(CHIPS)':
 'VCCIN'<171>: CDS_PINID='VCCIN(171)';
NODE_NAME     U5D1 BJ74
 '@BASEBOARD_FAB2_LIB.BASEBOARD_FAB2(SCH_1):PAGE37_I310@CHPSET_LIB.SKX_EXT_B(CHIPS)':
 'VCCIN'<172>: CDS_PINID='VCCIN(172)';
NODE_NAME     U5D1 BJ72
 '@BASEBOARD_FAB2_LIB.BASEBOARD_FAB2(SCH_1):PAGE37_I310@CHPSET_LIB.SKX_EXT_B(CHIPS)':
 'VCCIN'<173>: CDS_PINID='VCCIN(173)';
NODE_NAME     U5D1 BJ70
 '@BASEBOARD_FAB2_LIB.BASEBOARD_FAB2(SCH_1):PAGE37_I310@CHPSET_LIB.SKX_EXT_B(CHIPS)':
 'VCCIN'<174>: CDS_PINID='VCCIN(174)';
NODE_NAME     U5D1 BJ68
 '@BASEBOARD_FAB2_LIB.BASEBOARD_FAB2(SCH_1):PAGE37_I310@CHPSET_LIB.SKX_EXT_B(CHIPS)':
 'VCCIN'<175>: CDS_PINID='VCCIN(175)';
NODE_NAME     U5D1 BJ66
 '@BASEBOARD_FAB2_LIB.BASEBOARD_FAB2(SCH_1):PAGE37_I310@CHPSET_LIB.SKX_EXT_B(CHIPS)':
 'VCCIN'<176>: CDS_PINID='VCCIN(176)';
NODE_NAME     U5D1 BJ64
 '@BASEBOARD_FAB2_LIB.BASEBOARD_FAB2(SCH_1):PAGE37_I310@CHPSET_LIB.SKX_EXT_B(CHIPS)':
 'VCCIN'<177>: CDS_PINID='VCCIN(177)';
NODE_NAME     U5D1 BJ62
 '@BASEBOARD_FAB2_LIB.BASEBOARD_FAB2(SCH_1):PAGE37_I310@CHPSET_LIB.SKX_EXT_B(CHIPS)':
 'VCCIN'<178>: CDS_PINID='VCCIN(178)';
NODE_NAME     U5D1 BJ60
 '@BASEBOARD_FAB2_LIB.BASEBOARD_FAB2(SCH_1):PAGE37_I310@CHPSET_LIB.SKX_EXT_B(CHIPS)':
 'VCCIN'<179>: CDS_PINID='VCCIN(179)';
NODE_NAME     U5D1 BH83
 '@BASEBOARD_FAB2_LIB.BASEBOARD_FAB2(SCH_1):PAGE37_I310@CHPSET_LIB.SKX_EXT_B(CHIPS)':
 'VCCIN'<180>: CDS_PINID='VCCIN(180)';
NODE_NAME     U5D1 BH81
 '@BASEBOARD_FAB2_LIB.BASEBOARD_FAB2(SCH_1):PAGE37_I310@CHPSET_LIB.SKX_EXT_B(CHIPS)':
 'VCCIN'<181>: CDS_PINID='VCCIN(181)';
NODE_NAME     U5D1 BH79
 '@BASEBOARD_FAB2_LIB.BASEBOARD_FAB2(SCH_1):PAGE37_I310@CHPSET_LIB.SKX_EXT_B(CHIPS)':
 'VCCIN'<182>: CDS_PINID='VCCIN(182)';
NODE_NAME     U5D1 BH77
 '@BASEBOARD_FAB2_LIB.BASEBOARD_FAB2(SCH_1):PAGE37_I310@CHPSET_LIB.SKX_EXT_B(CHIPS)':
 'VCCIN'<183>: CDS_PINID='VCCIN(183)';
NODE_NAME     U5D1 BH75
 '@BASEBOARD_FAB2_LIB.BASEBOARD_FAB2(SCH_1):PAGE37_I310@CHPSET_LIB.SKX_EXT_B(CHIPS)':
 'VCCIN'<184>: CDS_PINID='VCCIN(184)';
NODE_NAME     U5D1 BH73
 '@BASEBOARD_FAB2_LIB.BASEBOARD_FAB2(SCH_1):PAGE37_I310@CHPSET_LIB.SKX_EXT_B(CHIPS)':
 'VCCIN'<185>: CDS_PINID='VCCIN(185)';
NODE_NAME     U5D1 BH71
 '@BASEBOARD_FAB2_LIB.BASEBOARD_FAB2(SCH_1):PAGE37_I310@CHPSET_LIB.SKX_EXT_B(CHIPS)':
 'VCCIN'<186>: CDS_PINID='VCCIN(186)';
NODE_NAME     U5D1 BH69
 '@BASEBOARD_FAB2_LIB.BASEBOARD_FAB2(SCH_1):PAGE37_I310@CHPSET_LIB.SKX_EXT_B(CHIPS)':
 'VCCIN'<187>: CDS_PINID='VCCIN(187)';
NODE_NAME     U5D1 BH67
 '@BASEBOARD_FAB2_LIB.BASEBOARD_FAB2(SCH_1):PAGE37_I310@CHPSET_LIB.SKX_EXT_B(CHIPS)':
 'VCCIN'<188>: CDS_PINID='VCCIN(188)';
NODE_NAME     U5D1 BH65
 '@BASEBOARD_FAB2_LIB.BASEBOARD_FAB2(SCH_1):PAGE37_I310@CHPSET_LIB.SKX_EXT_B(CHIPS)':
 'VCCIN'<189>: CDS_PINID='VCCIN(189)';
NODE_NAME     U5D1 BH63
 '@BASEBOARD_FAB2_LIB.BASEBOARD_FAB2(SCH_1):PAGE37_I310@CHPSET_LIB.SKX_EXT_B(CHIPS)':
 'VCCIN'<190>: CDS_PINID='VCCIN(190)';
NODE_NAME     U5D1 BH61
 '@BASEBOARD_FAB2_LIB.BASEBOARD_FAB2(SCH_1):PAGE37_I310@CHPSET_LIB.SKX_EXT_B(CHIPS)':
 'VCCIN'<191>: CDS_PINID='VCCIN(191)';
NODE_NAME     U5D1 BG84
 '@BASEBOARD_FAB2_LIB.BASEBOARD_FAB2(SCH_1):PAGE37_I310@CHPSET_LIB.SKX_EXT_B(CHIPS)':
 'VCCIN'<192>: CDS_PINID='VCCIN(192)';
NODE_NAME     U5D1 BG70
 '@BASEBOARD_FAB2_LIB.BASEBOARD_FAB2(SCH_1):PAGE37_I310@CHPSET_LIB.SKX_EXT_B(CHIPS)':
 'VCCIN'<193>: CDS_PINID='VCCIN(193)';
NODE_NAME     U5D1 BG68
 '@BASEBOARD_FAB2_LIB.BASEBOARD_FAB2(SCH_1):PAGE37_I310@CHPSET_LIB.SKX_EXT_B(CHIPS)':
 'VCCIN'<194>: CDS_PINID='VCCIN(194)';
NODE_NAME     U5D1 BG66
 '@BASEBOARD_FAB2_LIB.BASEBOARD_FAB2(SCH_1):PAGE37_I310@CHPSET_LIB.SKX_EXT_B(CHIPS)':
 'VCCIN'<195>: CDS_PINID='VCCIN(195)';
NODE_NAME     U5D1 BG64
 '@BASEBOARD_FAB2_LIB.BASEBOARD_FAB2(SCH_1):PAGE37_I310@CHPSET_LIB.SKX_EXT_B(CHIPS)':
 'VCCIN'<196>: CDS_PINID='VCCIN(196)';
NODE_NAME     U5D1 BG62
 '@BASEBOARD_FAB2_LIB.BASEBOARD_FAB2(SCH_1):PAGE37_I310@CHPSET_LIB.SKX_EXT_B(CHIPS)':
 'VCCIN'<197>: CDS_PINID='VCCIN(197)';
NODE_NAME     U5D1 BG60
 '@BASEBOARD_FAB2_LIB.BASEBOARD_FAB2(SCH_1):PAGE37_I310@CHPSET_LIB.SKX_EXT_B(CHIPS)':
 'VCCIN'<198>: CDS_PINID='VCCIN(198)';
NODE_NAME     U5D1 BF85
 '@BASEBOARD_FAB2_LIB.BASEBOARD_FAB2(SCH_1):PAGE37_I310@CHPSET_LIB.SKX_EXT_B(CHIPS)':
 'VCCIN'<199>: CDS_PINID='VCCIN(199)';
NODE_NAME     U5D1 BF83
 '@BASEBOARD_FAB2_LIB.BASEBOARD_FAB2(SCH_1):PAGE37_I310@CHPSET_LIB.SKX_EXT_B(CHIPS)':
 'VCCIN'<200>: CDS_PINID='VCCIN(200)';
NODE_NAME     U5D1 BF81
 '@BASEBOARD_FAB2_LIB.BASEBOARD_FAB2(SCH_1):PAGE37_I310@CHPSET_LIB.SKX_EXT_B(CHIPS)':
 'VCCIN'<201>: CDS_PINID='VCCIN(201)';
NODE_NAME     U5D1 BF79
 '@BASEBOARD_FAB2_LIB.BASEBOARD_FAB2(SCH_1):PAGE37_I310@CHPSET_LIB.SKX_EXT_B(CHIPS)':
 'VCCIN'<202>: CDS_PINID='VCCIN(202)';
NODE_NAME     U5D1 BF77
 '@BASEBOARD_FAB2_LIB.BASEBOARD_FAB2(SCH_1):PAGE37_I310@CHPSET_LIB.SKX_EXT_B(CHIPS)':
 'VCCIN'<203>: CDS_PINID='VCCIN(203)';
NODE_NAME     U5D1 BF75
 '@BASEBOARD_FAB2_LIB.BASEBOARD_FAB2(SCH_1):PAGE37_I310@CHPSET_LIB.SKX_EXT_B(CHIPS)':
 'VCCIN'<204>: CDS_PINID='VCCIN(204)';
NODE_NAME     U5D1 BF73
 '@BASEBOARD_FAB2_LIB.BASEBOARD_FAB2(SCH_1):PAGE37_I310@CHPSET_LIB.SKX_EXT_B(CHIPS)':
 'VCCIN'<205>: CDS_PINID='VCCIN(205)';
NODE_NAME     U5D1 BF61
 '@BASEBOARD_FAB2_LIB.BASEBOARD_FAB2(SCH_1):PAGE37_I310@CHPSET_LIB.SKX_EXT_B(CHIPS)':
 'VCCIN'<206>: CDS_PINID='VCCIN(206)';
NODE_NAME     U5D1 BE84
 '@BASEBOARD_FAB2_LIB.BASEBOARD_FAB2(SCH_1):PAGE37_I310@CHPSET_LIB.SKX_EXT_B(CHIPS)':
 'VCCIN'<207>: CDS_PINID='VCCIN(207)';
NODE_NAME     U5D1 BE82
 '@BASEBOARD_FAB2_LIB.BASEBOARD_FAB2(SCH_1):PAGE37_I310@CHPSET_LIB.SKX_EXT_B(CHIPS)':
 'VCCIN'<208>: CDS_PINID='VCCIN(208)';
NODE_NAME     U5D1 BE80
 '@BASEBOARD_FAB2_LIB.BASEBOARD_FAB2(SCH_1):PAGE37_I310@CHPSET_LIB.SKX_EXT_B(CHIPS)':
 'VCCIN'<209>: CDS_PINID='VCCIN(209)';
NODE_NAME     U5D1 BE78
 '@BASEBOARD_FAB2_LIB.BASEBOARD_FAB2(SCH_1):PAGE37_I310@CHPSET_LIB.SKX_EXT_B(CHIPS)':
 'VCCIN'<210>: CDS_PINID='VCCIN(210)';
NODE_NAME     U5D1 BE76
 '@BASEBOARD_FAB2_LIB.BASEBOARD_FAB2(SCH_1):PAGE37_I310@CHPSET_LIB.SKX_EXT_B(CHIPS)':
 'VCCIN'<211>: CDS_PINID='VCCIN(211)';
NODE_NAME     U5D1 BE74
 '@BASEBOARD_FAB2_LIB.BASEBOARD_FAB2(SCH_1):PAGE37_I310@CHPSET_LIB.SKX_EXT_B(CHIPS)':
 'VCCIN'<212>: CDS_PINID='VCCIN(212)';
NODE_NAME     U5D1 BE72
 '@BASEBOARD_FAB2_LIB.BASEBOARD_FAB2(SCH_1):PAGE37_I310@CHPSET_LIB.SKX_EXT_B(CHIPS)':
 'VCCIN'<213>: CDS_PINID='VCCIN(213)';
NODE_NAME     U5D1 BE62
 '@BASEBOARD_FAB2_LIB.BASEBOARD_FAB2(SCH_1):PAGE37_I310@CHPSET_LIB.SKX_EXT_B(CHIPS)':
 'VCCIN'<214>: CDS_PINID='VCCIN(214)';
NODE_NAME     U5D1 BE60
 '@BASEBOARD_FAB2_LIB.BASEBOARD_FAB2(SCH_1):PAGE37_I310@CHPSET_LIB.SKX_EXT_B(CHIPS)':
 'VCCIN'<215>: CDS_PINID='VCCIN(215)';
NODE_NAME     U5D1 BD85
 '@BASEBOARD_FAB2_LIB.BASEBOARD_FAB2(SCH_1):PAGE37_I310@CHPSET_LIB.SKX_EXT_B(CHIPS)':
 'VCCIN'<216>: CDS_PINID='VCCIN(216)';
NODE_NAME     U5D1 BD83
 '@BASEBOARD_FAB2_LIB.BASEBOARD_FAB2(SCH_1):PAGE37_I310@CHPSET_LIB.SKX_EXT_B(CHIPS)':
 'VCCIN'<217>: CDS_PINID='VCCIN(217)';
NODE_NAME     U5D1 BD81
 '@BASEBOARD_FAB2_LIB.BASEBOARD_FAB2(SCH_1):PAGE37_I310@CHPSET_LIB.SKX_EXT_B(CHIPS)':
 'VCCIN'<218>: CDS_PINID='VCCIN(218)';
NODE_NAME     U5D1 BD79
 '@BASEBOARD_FAB2_LIB.BASEBOARD_FAB2(SCH_1):PAGE37_I310@CHPSET_LIB.SKX_EXT_B(CHIPS)':
 'VCCIN'<219>: CDS_PINID='VCCIN(219)';
NODE_NAME     U5D1 BD77
 '@BASEBOARD_FAB2_LIB.BASEBOARD_FAB2(SCH_1):PAGE37_I310@CHPSET_LIB.SKX_EXT_B(CHIPS)':
 'VCCIN'<220>: CDS_PINID='VCCIN(220)';
NODE_NAME     U5D1 BD75
 '@BASEBOARD_FAB2_LIB.BASEBOARD_FAB2(SCH_1):PAGE37_I310@CHPSET_LIB.SKX_EXT_B(CHIPS)':
 'VCCIN'<221>: CDS_PINID='VCCIN(221)';
NODE_NAME     U5D1 BD73
 '@BASEBOARD_FAB2_LIB.BASEBOARD_FAB2(SCH_1):PAGE37_I310@CHPSET_LIB.SKX_EXT_B(CHIPS)':
 'VCCIN'<222>: CDS_PINID='VCCIN(222)';
NODE_NAME     U5D1 BD61
 '@BASEBOARD_FAB2_LIB.BASEBOARD_FAB2(SCH_1):PAGE37_I310@CHPSET_LIB.SKX_EXT_B(CHIPS)':
 'VCCIN'<223>: CDS_PINID='VCCIN(223)';
NODE_NAME     U5D1 BC84
 '@BASEBOARD_FAB2_LIB.BASEBOARD_FAB2(SCH_1):PAGE37_I310@CHPSET_LIB.SKX_EXT_B(CHIPS)':
 'VCCIN'<224>: CDS_PINID='VCCIN(224)';
NODE_NAME     U5D1 BC62
 '@BASEBOARD_FAB2_LIB.BASEBOARD_FAB2(SCH_1):PAGE37_I310@CHPSET_LIB.SKX_EXT_B(CHIPS)':
 'VCCIN'<225>: CDS_PINID='VCCIN(225)';
NODE_NAME     U5D1 BC60
 '@BASEBOARD_FAB2_LIB.BASEBOARD_FAB2(SCH_1):PAGE37_I310@CHPSET_LIB.SKX_EXT_B(CHIPS)':
 'VCCIN'<226>: CDS_PINID='VCCIN(226)';
NODE_NAME     U5D1 BB85
 '@BASEBOARD_FAB2_LIB.BASEBOARD_FAB2(SCH_1):PAGE37_I310@CHPSET_LIB.SKX_EXT_B(CHIPS)':
 'VCCIN'<227>: CDS_PINID='VCCIN(227)';
NODE_NAME     U5D1 BB61
 '@BASEBOARD_FAB2_LIB.BASEBOARD_FAB2(SCH_1):PAGE37_I310@CHPSET_LIB.SKX_EXT_B(CHIPS)':
 'VCCIN'<228>: CDS_PINID='VCCIN(228)';
NODE_NAME     U5D1 BA60
 '@BASEBOARD_FAB2_LIB.BASEBOARD_FAB2(SCH_1):PAGE37_I310@CHPSET_LIB.SKX_EXT_B(CHIPS)':
 'VCCIN'<229>: CDS_PINID='VCCIN(229)';
NODE_NAME     U5D1 AY61
 '@BASEBOARD_FAB2_LIB.BASEBOARD_FAB2(SCH_1):PAGE37_I310@CHPSET_LIB.SKX_EXT_B(CHIPS)':
 'VCCIN'<230>: CDS_PINID='VCCIN(230)';
NODE_NAME     U5D1 AW60
 '@BASEBOARD_FAB2_LIB.BASEBOARD_FAB2(SCH_1):PAGE37_I310@CHPSET_LIB.SKX_EXT_B(CHIPS)':
 'VCCIN'<231>: CDS_PINID='VCCIN(231)';
NODE_NAME     U5D1 AV61
 '@BASEBOARD_FAB2_LIB.BASEBOARD_FAB2(SCH_1):PAGE37_I310@CHPSET_LIB.SKX_EXT_B(CHIPS)':
 'VCCIN'<232>: CDS_PINID='VCCIN(232)';
NODE_NAME     U5D1 AV59
 '@BASEBOARD_FAB2_LIB.BASEBOARD_FAB2(SCH_1):PAGE37_I310@CHPSET_LIB.SKX_EXT_B(CHIPS)':
 'VCCIN'<233>: CDS_PINID='VCCIN(233)';
NODE_NAME     U5D1 AU60
 '@BASEBOARD_FAB2_LIB.BASEBOARD_FAB2(SCH_1):PAGE37_I310@CHPSET_LIB.SKX_EXT_B(CHIPS)':
 'VCCIN'<234>: CDS_PINID='VCCIN(234)';
NODE_NAME     U5D1 AU58
 '@BASEBOARD_FAB2_LIB.BASEBOARD_FAB2(SCH_1):PAGE37_I310@CHPSET_LIB.SKX_EXT_B(CHIPS)':
 'VCCIN'<235>: CDS_PINID='VCCIN(235)';
NODE_NAME     U5D1 AT59
 '@BASEBOARD_FAB2_LIB.BASEBOARD_FAB2(SCH_1):PAGE37_I310@CHPSET_LIB.SKX_EXT_B(CHIPS)':
 'VCCIN'<236>: CDS_PINID='VCCIN(236)';
NODE_NAME     U5D1 AT57
 '@BASEBOARD_FAB2_LIB.BASEBOARD_FAB2(SCH_1):PAGE37_I310@CHPSET_LIB.SKX_EXT_B(CHIPS)':
 'VCCIN'<237>: CDS_PINID='VCCIN(237)';
NODE_NAME     U5D1 AR58
 '@BASEBOARD_FAB2_LIB.BASEBOARD_FAB2(SCH_1):PAGE37_I310@CHPSET_LIB.SKX_EXT_B(CHIPS)':
 'VCCIN'<238>: CDS_PINID='VCCIN(238)';
NODE_NAME     U5D1 AR56
 '@BASEBOARD_FAB2_LIB.BASEBOARD_FAB2(SCH_1):PAGE37_I310@CHPSET_LIB.SKX_EXT_B(CHIPS)':
 'VCCIN'<239>: CDS_PINID='VCCIN(239)';
NODE_NAME     U5D1 AP57
 '@BASEBOARD_FAB2_LIB.BASEBOARD_FAB2(SCH_1):PAGE37_I310@CHPSET_LIB.SKX_EXT_B(CHIPS)':
 'VCCIN'<240>: CDS_PINID='VCCIN(240)';
NODE_NAME     U5D1 AP55
 '@BASEBOARD_FAB2_LIB.BASEBOARD_FAB2(SCH_1):PAGE37_I310@CHPSET_LIB.SKX_EXT_B(CHIPS)':
 'VCCIN'<241>: CDS_PINID='VCCIN(241)';
NODE_NAME     U5D1 AN56
 '@BASEBOARD_FAB2_LIB.BASEBOARD_FAB2(SCH_1):PAGE37_I310@CHPSET_LIB.SKX_EXT_B(CHIPS)':
 'VCCIN'<242>: CDS_PINID='VCCIN(242)';
NODE_NAME     U5D1 AN54
 '@BASEBOARD_FAB2_LIB.BASEBOARD_FAB2(SCH_1):PAGE37_I310@CHPSET_LIB.SKX_EXT_B(CHIPS)':
 'VCCIN'<243>: CDS_PINID='VCCIN(243)';
NODE_NAME     U5D1 AN32
 '@BASEBOARD_FAB2_LIB.BASEBOARD_FAB2(SCH_1):PAGE37_I310@CHPSET_LIB.SKX_EXT_B(CHIPS)':
 'VCCIN'<244>: CDS_PINID='VCCIN(244)';
NODE_NAME     U5D1 AM55
 '@BASEBOARD_FAB2_LIB.BASEBOARD_FAB2(SCH_1):PAGE37_I310@CHPSET_LIB.SKX_EXT_B(CHIPS)':
 'VCCIN'<245>: CDS_PINID='VCCIN(245)';
NODE_NAME     U5D1 AM53
 '@BASEBOARD_FAB2_LIB.BASEBOARD_FAB2(SCH_1):PAGE37_I310@CHPSET_LIB.SKX_EXT_B(CHIPS)':
 'VCCIN'<246>: CDS_PINID='VCCIN(246)';
NODE_NAME     U5D1 AM33
 '@BASEBOARD_FAB2_LIB.BASEBOARD_FAB2(SCH_1):PAGE37_I310@CHPSET_LIB.SKX_EXT_B(CHIPS)':
 'VCCIN'<247>: CDS_PINID='VCCIN(247)';
NODE_NAME     U5D1 AL54
 '@BASEBOARD_FAB2_LIB.BASEBOARD_FAB2(SCH_1):PAGE37_I310@CHPSET_LIB.SKX_EXT_B(CHIPS)':
 'VCCIN'<248>: CDS_PINID='VCCIN(248)';
NODE_NAME     U5D1 AL52
 '@BASEBOARD_FAB2_LIB.BASEBOARD_FAB2(SCH_1):PAGE37_I310@CHPSET_LIB.SKX_EXT_B(CHIPS)':
 'VCCIN'<249>: CDS_PINID='VCCIN(249)';
NODE_NAME     U5D1 AL50
 '@BASEBOARD_FAB2_LIB.BASEBOARD_FAB2(SCH_1):PAGE37_I310@CHPSET_LIB.SKX_EXT_B(CHIPS)':
 'VCCIN'<250>: CDS_PINID='VCCIN(250)';
NODE_NAME     U5D1 AL48
 '@BASEBOARD_FAB2_LIB.BASEBOARD_FAB2(SCH_1):PAGE37_I310@CHPSET_LIB.SKX_EXT_B(CHIPS)':
 'VCCIN'<251>: CDS_PINID='VCCIN(251)';
NODE_NAME     U5D1 AL46
 '@BASEBOARD_FAB2_LIB.BASEBOARD_FAB2(SCH_1):PAGE37_I310@CHPSET_LIB.SKX_EXT_B(CHIPS)':
 'VCCIN'<252>: CDS_PINID='VCCIN(252)';
NODE_NAME     U5D1 AL34
 '@BASEBOARD_FAB2_LIB.BASEBOARD_FAB2(SCH_1):PAGE37_I310@CHPSET_LIB.SKX_EXT_B(CHIPS)':
 'VCCIN'<253>: CDS_PINID='VCCIN(253)';
NODE_NAME     U5D1 AK53
 '@BASEBOARD_FAB2_LIB.BASEBOARD_FAB2(SCH_1):PAGE37_I310@CHPSET_LIB.SKX_EXT_B(CHIPS)':
 'VCCIN'<254>: CDS_PINID='VCCIN(254)';
NODE_NAME     U5D1 AK51
 '@BASEBOARD_FAB2_LIB.BASEBOARD_FAB2(SCH_1):PAGE37_I310@CHPSET_LIB.SKX_EXT_B(CHIPS)':
 'VCCIN'<255>: CDS_PINID='VCCIN(255)';
NODE_NAME     U5D1 AK49
 '@BASEBOARD_FAB2_LIB.BASEBOARD_FAB2(SCH_1):PAGE37_I310@CHPSET_LIB.SKX_EXT_B(CHIPS)':
 'VCCIN'<256>: CDS_PINID='VCCIN(256)';
NODE_NAME     U5D1 AK47
 '@BASEBOARD_FAB2_LIB.BASEBOARD_FAB2(SCH_1):PAGE37_I310@CHPSET_LIB.SKX_EXT_B(CHIPS)':
 'VCCIN'<257>: CDS_PINID='VCCIN(257)';
NODE_NAME     U5D1 AK45
 '@BASEBOARD_FAB2_LIB.BASEBOARD_FAB2(SCH_1):PAGE37_I310@CHPSET_LIB.SKX_EXT_B(CHIPS)':
 'VCCIN'<258>: CDS_PINID='VCCIN(258)';
NODE_NAME     U5D1 AK35
 '@BASEBOARD_FAB2_LIB.BASEBOARD_FAB2(SCH_1):PAGE37_I310@CHPSET_LIB.SKX_EXT_B(CHIPS)':
 'VCCIN'<259>: CDS_PINID='VCCIN(259)';
NODE_NAME     U5D1 AJ36
 '@BASEBOARD_FAB2_LIB.BASEBOARD_FAB2(SCH_1):PAGE37_I310@CHPSET_LIB.SKX_EXT_B(CHIPS)':
 'VCCIN'<260>: CDS_PINID='VCCIN(260)';
NODE_NAME     U5D1 AH41
 '@BASEBOARD_FAB2_LIB.BASEBOARD_FAB2(SCH_1):PAGE37_I310@CHPSET_LIB.SKX_EXT_B(CHIPS)':
 'VCCIN'<261>: CDS_PINID='VCCIN(261)';
NODE_NAME     U5D1 AH39
 '@BASEBOARD_FAB2_LIB.BASEBOARD_FAB2(SCH_1):PAGE37_I310@CHPSET_LIB.SKX_EXT_B(CHIPS)':
 'VCCIN'<262>: CDS_PINID='VCCIN(262)';
NODE_NAME     U5D1 AH37
 '@BASEBOARD_FAB2_LIB.BASEBOARD_FAB2(SCH_1):PAGE37_I310@CHPSET_LIB.SKX_EXT_B(CHIPS)':
 'VCCIN'<263>: CDS_PINID='VCCIN(263)';
NODE_NAME     U5D1 AG42
 '@BASEBOARD_FAB2_LIB.BASEBOARD_FAB2(SCH_1):PAGE37_I310@CHPSET_LIB.SKX_EXT_B(CHIPS)':
 'VCCIN'<264>: CDS_PINID='VCCIN(264)';
NODE_NAME     U5D1 AG40
 '@BASEBOARD_FAB2_LIB.BASEBOARD_FAB2(SCH_1):PAGE37_I310@CHPSET_LIB.SKX_EXT_B(CHIPS)':
 'VCCIN'<265>: CDS_PINID='VCCIN(265)';
NODE_NAME     U5D1 AG38
 '@BASEBOARD_FAB2_LIB.BASEBOARD_FAB2(SCH_1):PAGE37_I310@CHPSET_LIB.SKX_EXT_B(CHIPS)':
 'VCCIN'<266>: CDS_PINID='VCCIN(266)';
NODE_NAME     U5D1 AF43
 '@BASEBOARD_FAB2_LIB.BASEBOARD_FAB2(SCH_1):PAGE37_I310@CHPSET_LIB.SKX_EXT_B(CHIPS)':
 'VCCIN'<267>: CDS_PINID='VCCIN(267)';
NODE_NAME     U5D1 CY49
 '@BASEBOARD_FAB2_LIB.BASEBOARD_FAB2(SCH_1):PAGE37_I311@CHPSET_LIB.SKX_EXT_B(CHIPS)':
 'VCCIN'<0>: CDS_PINID='VCCIN(0)';
NODE_NAME     U5D1 CY47
 '@BASEBOARD_FAB2_LIB.BASEBOARD_FAB2(SCH_1):PAGE37_I311@CHPSET_LIB.SKX_EXT_B(CHIPS)':
 'VCCIN'<1>: CDS_PINID='VCCIN(1)';
NODE_NAME     U5D1 CW50
 '@BASEBOARD_FAB2_LIB.BASEBOARD_FAB2(SCH_1):PAGE37_I311@CHPSET_LIB.SKX_EXT_B(CHIPS)':
 'VCCIN'<2>: CDS_PINID='VCCIN(2)';
NODE_NAME     U5D1 CW48
 '@BASEBOARD_FAB2_LIB.BASEBOARD_FAB2(SCH_1):PAGE37_I311@CHPSET_LIB.SKX_EXT_B(CHIPS)':
 'VCCIN'<3>: CDS_PINID='VCCIN(3)';
NODE_NAME     U5D1 CW46
 '@BASEBOARD_FAB2_LIB.BASEBOARD_FAB2(SCH_1):PAGE37_I311@CHPSET_LIB.SKX_EXT_B(CHIPS)':
 'VCCIN'<4>: CDS_PINID='VCCIN(4)';
NODE_NAME     U5D1 CV51
 '@BASEBOARD_FAB2_LIB.BASEBOARD_FAB2(SCH_1):PAGE37_I311@CHPSET_LIB.SKX_EXT_B(CHIPS)':
 'VCCIN'<5>: CDS_PINID='VCCIN(5)';
NODE_NAME     U5D1 CU54
 '@BASEBOARD_FAB2_LIB.BASEBOARD_FAB2(SCH_1):PAGE37_I311@CHPSET_LIB.SKX_EXT_B(CHIPS)':
 'VCCIN'<6>: CDS_PINID='VCCIN(6)';
NODE_NAME     U5D1 CU52
 '@BASEBOARD_FAB2_LIB.BASEBOARD_FAB2(SCH_1):PAGE37_I311@CHPSET_LIB.SKX_EXT_B(CHIPS)':
 'VCCIN'<7>: CDS_PINID='VCCIN(7)';
NODE_NAME     U5D1 CU42
 '@BASEBOARD_FAB2_LIB.BASEBOARD_FAB2(SCH_1):PAGE37_I311@CHPSET_LIB.SKX_EXT_B(CHIPS)':
 'VCCIN'<8>: CDS_PINID='VCCIN(8)';
NODE_NAME     U5D1 CU40
 '@BASEBOARD_FAB2_LIB.BASEBOARD_FAB2(SCH_1):PAGE37_I311@CHPSET_LIB.SKX_EXT_B(CHIPS)':
 'VCCIN'<9>: CDS_PINID='VCCIN(9)';
NODE_NAME     U5D1 CU38
 '@BASEBOARD_FAB2_LIB.BASEBOARD_FAB2(SCH_1):PAGE37_I311@CHPSET_LIB.SKX_EXT_B(CHIPS)':
 'VCCIN'<10>: CDS_PINID='VCCIN(10)';
NODE_NAME     U5D1 CT55
 '@BASEBOARD_FAB2_LIB.BASEBOARD_FAB2(SCH_1):PAGE37_I311@CHPSET_LIB.SKX_EXT_B(CHIPS)':
 'VCCIN'<11>: CDS_PINID='VCCIN(11)';
NODE_NAME     U5D1 CT53
 '@BASEBOARD_FAB2_LIB.BASEBOARD_FAB2(SCH_1):PAGE37_I311@CHPSET_LIB.SKX_EXT_B(CHIPS)':
 'VCCIN'<12>: CDS_PINID='VCCIN(12)';
NODE_NAME     U5D1 CT41
 '@BASEBOARD_FAB2_LIB.BASEBOARD_FAB2(SCH_1):PAGE37_I311@CHPSET_LIB.SKX_EXT_B(CHIPS)':
 'VCCIN'<13>: CDS_PINID='VCCIN(13)';
NODE_NAME     U5D1 CT39
 '@BASEBOARD_FAB2_LIB.BASEBOARD_FAB2(SCH_1):PAGE37_I311@CHPSET_LIB.SKX_EXT_B(CHIPS)':
 'VCCIN'<14>: CDS_PINID='VCCIN(14)';
NODE_NAME     U5D1 CT37
 '@BASEBOARD_FAB2_LIB.BASEBOARD_FAB2(SCH_1):PAGE37_I311@CHPSET_LIB.SKX_EXT_B(CHIPS)':
 'VCCIN'<15>: CDS_PINID='VCCIN(15)';
NODE_NAME     U5D1 CR56
 '@BASEBOARD_FAB2_LIB.BASEBOARD_FAB2(SCH_1):PAGE37_I311@CHPSET_LIB.SKX_EXT_B(CHIPS)':
 'VCCIN'<16>: CDS_PINID='VCCIN(16)';
NODE_NAME     U5D1 CR54
 '@BASEBOARD_FAB2_LIB.BASEBOARD_FAB2(SCH_1):PAGE37_I311@CHPSET_LIB.SKX_EXT_B(CHIPS)':
 'VCCIN'<17>: CDS_PINID='VCCIN(17)';
NODE_NAME     U5D1 CR34
 '@BASEBOARD_FAB2_LIB.BASEBOARD_FAB2(SCH_1):PAGE37_I311@CHPSET_LIB.SKX_EXT_B(CHIPS)':
 'VCCIN'<18>: CDS_PINID='VCCIN(18)';
NODE_NAME     U5D1 CP57
 '@BASEBOARD_FAB2_LIB.BASEBOARD_FAB2(SCH_1):PAGE37_I311@CHPSET_LIB.SKX_EXT_B(CHIPS)':
 'VCCIN'<19>: CDS_PINID='VCCIN(19)';
NODE_NAME     U5D1 CP55
 '@BASEBOARD_FAB2_LIB.BASEBOARD_FAB2(SCH_1):PAGE37_I311@CHPSET_LIB.SKX_EXT_B(CHIPS)':
 'VCCIN'<20>: CDS_PINID='VCCIN(20)';
NODE_NAME     U5D1 CP33
 '@BASEBOARD_FAB2_LIB.BASEBOARD_FAB2(SCH_1):PAGE37_I311@CHPSET_LIB.SKX_EXT_B(CHIPS)':
 'VCCIN'<21>: CDS_PINID='VCCIN(21)';
NODE_NAME     U5D1 CN58
 '@BASEBOARD_FAB2_LIB.BASEBOARD_FAB2(SCH_1):PAGE37_I311@CHPSET_LIB.SKX_EXT_B(CHIPS)':
 'VCCIN'<22>: CDS_PINID='VCCIN(22)';
NODE_NAME     U5D1 CN56
 '@BASEBOARD_FAB2_LIB.BASEBOARD_FAB2(SCH_1):PAGE37_I311@CHPSET_LIB.SKX_EXT_B(CHIPS)':
 'VCCIN'<23>: CDS_PINID='VCCIN(23)';
NODE_NAME     U5D1 CM59
 '@BASEBOARD_FAB2_LIB.BASEBOARD_FAB2(SCH_1):PAGE37_I311@CHPSET_LIB.SKX_EXT_B(CHIPS)':
 'VCCIN'<24>: CDS_PINID='VCCIN(24)';
NODE_NAME     U5D1 CM57
 '@BASEBOARD_FAB2_LIB.BASEBOARD_FAB2(SCH_1):PAGE37_I311@CHPSET_LIB.SKX_EXT_B(CHIPS)':
 'VCCIN'<25>: CDS_PINID='VCCIN(25)';
NODE_NAME     U5D1 CL60
 '@BASEBOARD_FAB2_LIB.BASEBOARD_FAB2(SCH_1):PAGE37_I311@CHPSET_LIB.SKX_EXT_B(CHIPS)':
 'VCCIN'<26>: CDS_PINID='VCCIN(26)';
NODE_NAME     U5D1 CL58
 '@BASEBOARD_FAB2_LIB.BASEBOARD_FAB2(SCH_1):PAGE37_I311@CHPSET_LIB.SKX_EXT_B(CHIPS)':
 'VCCIN'<27>: CDS_PINID='VCCIN(27)';
NODE_NAME     U5D1 CK61
 '@BASEBOARD_FAB2_LIB.BASEBOARD_FAB2(SCH_1):PAGE37_I311@CHPSET_LIB.SKX_EXT_B(CHIPS)':
 'VCCIN'<28>: CDS_PINID='VCCIN(28)';
NODE_NAME     U5D1 CK59
 '@BASEBOARD_FAB2_LIB.BASEBOARD_FAB2(SCH_1):PAGE37_I311@CHPSET_LIB.SKX_EXT_B(CHIPS)':
 'VCCIN'<29>: CDS_PINID='VCCIN(29)';
NODE_NAME     U5D1 CJ60
 '@BASEBOARD_FAB2_LIB.BASEBOARD_FAB2(SCH_1):PAGE37_I311@CHPSET_LIB.SKX_EXT_B(CHIPS)':
 'VCCIN'<30>: CDS_PINID='VCCIN(30)';
NODE_NAME     U5D1 CH85
 '@BASEBOARD_FAB2_LIB.BASEBOARD_FAB2(SCH_1):PAGE37_I311@CHPSET_LIB.SKX_EXT_B(CHIPS)':
 'VCCIN'<31>: CDS_PINID='VCCIN(31)';
NODE_NAME     U5D1 CH61
 '@BASEBOARD_FAB2_LIB.BASEBOARD_FAB2(SCH_1):PAGE37_I311@CHPSET_LIB.SKX_EXT_B(CHIPS)':
 'VCCIN'<32>: CDS_PINID='VCCIN(32)';
NODE_NAME     U5D1 CG84
 '@BASEBOARD_FAB2_LIB.BASEBOARD_FAB2(SCH_1):PAGE37_I311@CHPSET_LIB.SKX_EXT_B(CHIPS)':
 'VCCIN'<33>: CDS_PINID='VCCIN(33)';
NODE_NAME     U5D1 CG60
 '@BASEBOARD_FAB2_LIB.BASEBOARD_FAB2(SCH_1):PAGE37_I311@CHPSET_LIB.SKX_EXT_B(CHIPS)':
 'VCCIN'<34>: CDS_PINID='VCCIN(34)';
NODE_NAME     U5D1 CF85
 '@BASEBOARD_FAB2_LIB.BASEBOARD_FAB2(SCH_1):PAGE37_I311@CHPSET_LIB.SKX_EXT_B(CHIPS)':
 'VCCIN'<35>: CDS_PINID='VCCIN(35)';
NODE_NAME     U5D1 CF61
 '@BASEBOARD_FAB2_LIB.BASEBOARD_FAB2(SCH_1):PAGE37_I311@CHPSET_LIB.SKX_EXT_B(CHIPS)':
 'VCCIN'<36>: CDS_PINID='VCCIN(36)';
NODE_NAME     U5D1 CE84
 '@BASEBOARD_FAB2_LIB.BASEBOARD_FAB2(SCH_1):PAGE37_I311@CHPSET_LIB.SKX_EXT_B(CHIPS)':
 'VCCIN'<37>: CDS_PINID='VCCIN(37)';
NODE_NAME     U5D1 CE60
 '@BASEBOARD_FAB2_LIB.BASEBOARD_FAB2(SCH_1):PAGE37_I311@CHPSET_LIB.SKX_EXT_B(CHIPS)':
 'VCCIN'<38>: CDS_PINID='VCCIN(38)';
NODE_NAME     U5D1 CD85
 '@BASEBOARD_FAB2_LIB.BASEBOARD_FAB2(SCH_1):PAGE37_I311@CHPSET_LIB.SKX_EXT_B(CHIPS)':
 'VCCIN'<39>: CDS_PINID='VCCIN(39)';
NODE_NAME     U5D1 CD83
 '@BASEBOARD_FAB2_LIB.BASEBOARD_FAB2(SCH_1):PAGE37_I311@CHPSET_LIB.SKX_EXT_B(CHIPS)':
 'VCCIN'<40>: CDS_PINID='VCCIN(40)';
NODE_NAME     U5D1 CD61
 '@BASEBOARD_FAB2_LIB.BASEBOARD_FAB2(SCH_1):PAGE37_I311@CHPSET_LIB.SKX_EXT_B(CHIPS)':
 'VCCIN'<41>: CDS_PINID='VCCIN(41)';
NODE_NAME     U5D1 CC84
 '@BASEBOARD_FAB2_LIB.BASEBOARD_FAB2(SCH_1):PAGE37_I311@CHPSET_LIB.SKX_EXT_B(CHIPS)':
 'VCCIN'<42>: CDS_PINID='VCCIN(42)';
NODE_NAME     U5D1 CC62
 '@BASEBOARD_FAB2_LIB.BASEBOARD_FAB2(SCH_1):PAGE37_I311@CHPSET_LIB.SKX_EXT_B(CHIPS)':
 'VCCIN'<43>: CDS_PINID='VCCIN(43)';
NODE_NAME     U5D1 CC60
 '@BASEBOARD_FAB2_LIB.BASEBOARD_FAB2(SCH_1):PAGE37_I311@CHPSET_LIB.SKX_EXT_B(CHIPS)':
 'VCCIN'<44>: CDS_PINID='VCCIN(44)';
NODE_NAME     U5D1 CB83
 '@BASEBOARD_FAB2_LIB.BASEBOARD_FAB2(SCH_1):PAGE37_I311@CHPSET_LIB.SKX_EXT_B(CHIPS)':
 'VCCIN'<45>: CDS_PINID='VCCIN(45)';
NODE_NAME     U5D1 CB81
 '@BASEBOARD_FAB2_LIB.BASEBOARD_FAB2(SCH_1):PAGE37_I311@CHPSET_LIB.SKX_EXT_B(CHIPS)':
 'VCCIN'<46>: CDS_PINID='VCCIN(46)';
NODE_NAME     U5D1 CB79
 '@BASEBOARD_FAB2_LIB.BASEBOARD_FAB2(SCH_1):PAGE37_I311@CHPSET_LIB.SKX_EXT_B(CHIPS)':
 'VCCIN'<47>: CDS_PINID='VCCIN(47)';
NODE_NAME     U5D1 CB77
 '@BASEBOARD_FAB2_LIB.BASEBOARD_FAB2(SCH_1):PAGE37_I311@CHPSET_LIB.SKX_EXT_B(CHIPS)':
 'VCCIN'<48>: CDS_PINID='VCCIN(48)';
NODE_NAME     U5D1 CB75
 '@BASEBOARD_FAB2_LIB.BASEBOARD_FAB2(SCH_1):PAGE37_I311@CHPSET_LIB.SKX_EXT_B(CHIPS)':
 'VCCIN'<49>: CDS_PINID='VCCIN(49)';
NODE_NAME     U5D1 CB73
 '@BASEBOARD_FAB2_LIB.BASEBOARD_FAB2(SCH_1):PAGE37_I311@CHPSET_LIB.SKX_EXT_B(CHIPS)':
 'VCCIN'<50>: CDS_PINID='VCCIN(50)';
NODE_NAME     U5D1 CB61
 '@BASEBOARD_FAB2_LIB.BASEBOARD_FAB2(SCH_1):PAGE37_I311@CHPSET_LIB.SKX_EXT_B(CHIPS)':
 'VCCIN'<51>: CDS_PINID='VCCIN(51)';
NODE_NAME     U5D1 CA84
 '@BASEBOARD_FAB2_LIB.BASEBOARD_FAB2(SCH_1):PAGE37_I311@CHPSET_LIB.SKX_EXT_B(CHIPS)':
 'VCCIN'<52>: CDS_PINID='VCCIN(52)';
NODE_NAME     U5D1 CA82
 '@BASEBOARD_FAB2_LIB.BASEBOARD_FAB2(SCH_1):PAGE37_I311@CHPSET_LIB.SKX_EXT_B(CHIPS)':
 'VCCIN'<53>: CDS_PINID='VCCIN(53)';
NODE_NAME     U5D1 CA80
 '@BASEBOARD_FAB2_LIB.BASEBOARD_FAB2(SCH_1):PAGE37_I311@CHPSET_LIB.SKX_EXT_B(CHIPS)':
 'VCCIN'<54>: CDS_PINID='VCCIN(54)';
NODE_NAME     U5D1 CA78
 '@BASEBOARD_FAB2_LIB.BASEBOARD_FAB2(SCH_1):PAGE37_I311@CHPSET_LIB.SKX_EXT_B(CHIPS)':
 'VCCIN'<55>: CDS_PINID='VCCIN(55)';
NODE_NAME     U5D1 CA76
 '@BASEBOARD_FAB2_LIB.BASEBOARD_FAB2(SCH_1):PAGE37_I311@CHPSET_LIB.SKX_EXT_B(CHIPS)':
 'VCCIN'<56>: CDS_PINID='VCCIN(56)';
NODE_NAME     U5D1 CA74
 '@BASEBOARD_FAB2_LIB.BASEBOARD_FAB2(SCH_1):PAGE37_I311@CHPSET_LIB.SKX_EXT_B(CHIPS)':
 'VCCIN'<57>: CDS_PINID='VCCIN(57)';
NODE_NAME     U5D1 CA72
 '@BASEBOARD_FAB2_LIB.BASEBOARD_FAB2(SCH_1):PAGE37_I311@CHPSET_LIB.SKX_EXT_B(CHIPS)':
 'VCCIN'<58>: CDS_PINID='VCCIN(58)';
NODE_NAME     U5D1 CA62
 '@BASEBOARD_FAB2_LIB.BASEBOARD_FAB2(SCH_1):PAGE37_I311@CHPSET_LIB.SKX_EXT_B(CHIPS)':
 'VCCIN'<59>: CDS_PINID='VCCIN(59)';
NODE_NAME     U5D1 CA60
 '@BASEBOARD_FAB2_LIB.BASEBOARD_FAB2(SCH_1):PAGE37_I311@CHPSET_LIB.SKX_EXT_B(CHIPS)':
 'VCCIN'<60>: CDS_PINID='VCCIN(60)';
NODE_NAME     U5D1 BY83
 '@BASEBOARD_FAB2_LIB.BASEBOARD_FAB2(SCH_1):PAGE37_I311@CHPSET_LIB.SKX_EXT_B(CHIPS)':
 'VCCIN'<61>: CDS_PINID='VCCIN(61)';
NODE_NAME     U5D1 BY81
 '@BASEBOARD_FAB2_LIB.BASEBOARD_FAB2(SCH_1):PAGE37_I311@CHPSET_LIB.SKX_EXT_B(CHIPS)':
 'VCCIN'<62>: CDS_PINID='VCCIN(62)';
NODE_NAME     U5D1 BY79
 '@BASEBOARD_FAB2_LIB.BASEBOARD_FAB2(SCH_1):PAGE37_I311@CHPSET_LIB.SKX_EXT_B(CHIPS)':
 'VCCIN'<63>: CDS_PINID='VCCIN(63)';
NODE_NAME     U5D1 BY77
 '@BASEBOARD_FAB2_LIB.BASEBOARD_FAB2(SCH_1):PAGE37_I311@CHPSET_LIB.SKX_EXT_B(CHIPS)':
 'VCCIN'<64>: CDS_PINID='VCCIN(64)';
NODE_NAME     U5D1 BY75
 '@BASEBOARD_FAB2_LIB.BASEBOARD_FAB2(SCH_1):PAGE37_I311@CHPSET_LIB.SKX_EXT_B(CHIPS)':
 'VCCIN'<65>: CDS_PINID='VCCIN(65)';
NODE_NAME     U5D1 BY73
 '@BASEBOARD_FAB2_LIB.BASEBOARD_FAB2(SCH_1):PAGE37_I311@CHPSET_LIB.SKX_EXT_B(CHIPS)':
 'VCCIN'<66>: CDS_PINID='VCCIN(66)';
NODE_NAME     U5D1 BY61
 '@BASEBOARD_FAB2_LIB.BASEBOARD_FAB2(SCH_1):PAGE37_I311@CHPSET_LIB.SKX_EXT_B(CHIPS)':
 'VCCIN'<67>: CDS_PINID='VCCIN(67)';
NODE_NAME     U5D1 BW84
 '@BASEBOARD_FAB2_LIB.BASEBOARD_FAB2(SCH_1):PAGE37_I311@CHPSET_LIB.SKX_EXT_B(CHIPS)':
 'VCCIN'<68>: CDS_PINID='VCCIN(68)';
NODE_NAME     U5D1 BW70
 '@BASEBOARD_FAB2_LIB.BASEBOARD_FAB2(SCH_1):PAGE37_I311@CHPSET_LIB.SKX_EXT_B(CHIPS)':
 'VCCIN'<69>: CDS_PINID='VCCIN(69)';
NODE_NAME     U5D1 BW68
 '@BASEBOARD_FAB2_LIB.BASEBOARD_FAB2(SCH_1):PAGE37_I311@CHPSET_LIB.SKX_EXT_B(CHIPS)':
 'VCCIN'<70>: CDS_PINID='VCCIN(70)';
NODE_NAME     U5D1 BW66
 '@BASEBOARD_FAB2_LIB.BASEBOARD_FAB2(SCH_1):PAGE37_I311@CHPSET_LIB.SKX_EXT_B(CHIPS)':
 'VCCIN'<71>: CDS_PINID='VCCIN(71)';
NODE_NAME     U5D1 BW64
 '@BASEBOARD_FAB2_LIB.BASEBOARD_FAB2(SCH_1):PAGE37_I311@CHPSET_LIB.SKX_EXT_B(CHIPS)':
 'VCCIN'<72>: CDS_PINID='VCCIN(72)';
NODE_NAME     U5D1 BW62
 '@BASEBOARD_FAB2_LIB.BASEBOARD_FAB2(SCH_1):PAGE37_I311@CHPSET_LIB.SKX_EXT_B(CHIPS)':
 'VCCIN'<73>: CDS_PINID='VCCIN(73)';
NODE_NAME     U5D1 BW60
 '@BASEBOARD_FAB2_LIB.BASEBOARD_FAB2(SCH_1):PAGE37_I311@CHPSET_LIB.SKX_EXT_B(CHIPS)':
 'VCCIN'<74>: CDS_PINID='VCCIN(74)';
NODE_NAME     U5D1 BV83
 '@BASEBOARD_FAB2_LIB.BASEBOARD_FAB2(SCH_1):PAGE37_I311@CHPSET_LIB.SKX_EXT_B(CHIPS)':
 'VCCIN'<75>: CDS_PINID='VCCIN(75)';
NODE_NAME     U5D1 BV81
 '@BASEBOARD_FAB2_LIB.BASEBOARD_FAB2(SCH_1):PAGE37_I311@CHPSET_LIB.SKX_EXT_B(CHIPS)':
 'VCCIN'<76>: CDS_PINID='VCCIN(76)';
NODE_NAME     U5D1 BV79
 '@BASEBOARD_FAB2_LIB.BASEBOARD_FAB2(SCH_1):PAGE37_I311@CHPSET_LIB.SKX_EXT_B(CHIPS)':
 'VCCIN'<77>: CDS_PINID='VCCIN(77)';
NODE_NAME     U5D1 BV77
 '@BASEBOARD_FAB2_LIB.BASEBOARD_FAB2(SCH_1):PAGE37_I311@CHPSET_LIB.SKX_EXT_B(CHIPS)':
 'VCCIN'<78>: CDS_PINID='VCCIN(78)';
NODE_NAME     U5D1 BV75
 '@BASEBOARD_FAB2_LIB.BASEBOARD_FAB2(SCH_1):PAGE37_I311@CHPSET_LIB.SKX_EXT_B(CHIPS)':
 'VCCIN'<79>: CDS_PINID='VCCIN(79)';
NODE_NAME     U5D1 BV73
 '@BASEBOARD_FAB2_LIB.BASEBOARD_FAB2(SCH_1):PAGE37_I311@CHPSET_LIB.SKX_EXT_B(CHIPS)':
 'VCCIN'<80>: CDS_PINID='VCCIN(80)';
NODE_NAME     U5D1 BV71
 '@BASEBOARD_FAB2_LIB.BASEBOARD_FAB2(SCH_1):PAGE37_I311@CHPSET_LIB.SKX_EXT_B(CHIPS)':
 'VCCIN'<81>: CDS_PINID='VCCIN(81)';
NODE_NAME     U5D1 BV69
 '@BASEBOARD_FAB2_LIB.BASEBOARD_FAB2(SCH_1):PAGE37_I311@CHPSET_LIB.SKX_EXT_B(CHIPS)':
 'VCCIN'<82>: CDS_PINID='VCCIN(82)';
NODE_NAME     U5D1 BV67
 '@BASEBOARD_FAB2_LIB.BASEBOARD_FAB2(SCH_1):PAGE37_I311@CHPSET_LIB.SKX_EXT_B(CHIPS)':
 'VCCIN'<83>: CDS_PINID='VCCIN(83)';
NODE_NAME     U5D1 BV65
 '@BASEBOARD_FAB2_LIB.BASEBOARD_FAB2(SCH_1):PAGE37_I311@CHPSET_LIB.SKX_EXT_B(CHIPS)':
 'VCCIN'<84>: CDS_PINID='VCCIN(84)';
NODE_NAME     U5D1 BV63
 '@BASEBOARD_FAB2_LIB.BASEBOARD_FAB2(SCH_1):PAGE37_I311@CHPSET_LIB.SKX_EXT_B(CHIPS)':
 'VCCIN'<85>: CDS_PINID='VCCIN(85)';
NODE_NAME     U5D1 BV61
 '@BASEBOARD_FAB2_LIB.BASEBOARD_FAB2(SCH_1):PAGE37_I311@CHPSET_LIB.SKX_EXT_B(CHIPS)':
 'VCCIN'<86>: CDS_PINID='VCCIN(86)';
NODE_NAME     U5D1 BU84
 '@BASEBOARD_FAB2_LIB.BASEBOARD_FAB2(SCH_1):PAGE37_I311@CHPSET_LIB.SKX_EXT_B(CHIPS)':
 'VCCIN'<87>: CDS_PINID='VCCIN(87)';
NODE_NAME     U5D1 BU82
 '@BASEBOARD_FAB2_LIB.BASEBOARD_FAB2(SCH_1):PAGE37_I311@CHPSET_LIB.SKX_EXT_B(CHIPS)':
 'VCCIN'<88>: CDS_PINID='VCCIN(88)';
NODE_NAME     U5D1 BU80
 '@BASEBOARD_FAB2_LIB.BASEBOARD_FAB2(SCH_1):PAGE37_I311@CHPSET_LIB.SKX_EXT_B(CHIPS)':
 'VCCIN'<89>: CDS_PINID='VCCIN(89)';
NODE_NAME     U5D1 BU78
 '@BASEBOARD_FAB2_LIB.BASEBOARD_FAB2(SCH_1):PAGE37_I311@CHPSET_LIB.SKX_EXT_B(CHIPS)':
 'VCCIN'<90>: CDS_PINID='VCCIN(90)';
NODE_NAME     U5D1 BU76
 '@BASEBOARD_FAB2_LIB.BASEBOARD_FAB2(SCH_1):PAGE37_I311@CHPSET_LIB.SKX_EXT_B(CHIPS)':
 'VCCIN'<91>: CDS_PINID='VCCIN(91)';
NODE_NAME     U5D1 BU74
 '@BASEBOARD_FAB2_LIB.BASEBOARD_FAB2(SCH_1):PAGE37_I311@CHPSET_LIB.SKX_EXT_B(CHIPS)':
 'VCCIN'<92>: CDS_PINID='VCCIN(92)';
NODE_NAME     U5D1 BU72
 '@BASEBOARD_FAB2_LIB.BASEBOARD_FAB2(SCH_1):PAGE37_I311@CHPSET_LIB.SKX_EXT_B(CHIPS)':
 'VCCIN'<93>: CDS_PINID='VCCIN(93)';
NODE_NAME     U5D1 BU70
 '@BASEBOARD_FAB2_LIB.BASEBOARD_FAB2(SCH_1):PAGE37_I311@CHPSET_LIB.SKX_EXT_B(CHIPS)':
 'VCCIN'<94>: CDS_PINID='VCCIN(94)';
NODE_NAME     U5D1 BU68
 '@BASEBOARD_FAB2_LIB.BASEBOARD_FAB2(SCH_1):PAGE37_I311@CHPSET_LIB.SKX_EXT_B(CHIPS)':
 'VCCIN'<95>: CDS_PINID='VCCIN(95)';
NODE_NAME     U5D1 BU66
 '@BASEBOARD_FAB2_LIB.BASEBOARD_FAB2(SCH_1):PAGE37_I311@CHPSET_LIB.SKX_EXT_B(CHIPS)':
 'VCCIN'<96>: CDS_PINID='VCCIN(96)';
NODE_NAME     U5D1 BU64
 '@BASEBOARD_FAB2_LIB.BASEBOARD_FAB2(SCH_1):PAGE37_I311@CHPSET_LIB.SKX_EXT_B(CHIPS)':
 'VCCIN'<97>: CDS_PINID='VCCIN(97)';
NODE_NAME     U5D1 BU62
 '@BASEBOARD_FAB2_LIB.BASEBOARD_FAB2(SCH_1):PAGE37_I311@CHPSET_LIB.SKX_EXT_B(CHIPS)':
 'VCCIN'<98>: CDS_PINID='VCCIN(98)';
NODE_NAME     U5D1 BU60
 '@BASEBOARD_FAB2_LIB.BASEBOARD_FAB2(SCH_1):PAGE37_I311@CHPSET_LIB.SKX_EXT_B(CHIPS)':
 'VCCIN'<99>: CDS_PINID='VCCIN(99)';
NODE_NAME     U5D1 BT83
 '@BASEBOARD_FAB2_LIB.BASEBOARD_FAB2(SCH_1):PAGE37_I311@CHPSET_LIB.SKX_EXT_B(CHIPS)':
 'VCCIN'<100>: CDS_PINID='VCCIN(100)';
NODE_NAME     U5D1 BT81
 '@BASEBOARD_FAB2_LIB.BASEBOARD_FAB2(SCH_1):PAGE37_I311@CHPSET_LIB.SKX_EXT_B(CHIPS)':
 'VCCIN'<101>: CDS_PINID='VCCIN(101)';
NODE_NAME     U5D1 BT79
 '@BASEBOARD_FAB2_LIB.BASEBOARD_FAB2(SCH_1):PAGE37_I311@CHPSET_LIB.SKX_EXT_B(CHIPS)':
 'VCCIN'<102>: CDS_PINID='VCCIN(102)';
NODE_NAME     U5D1 BT77
 '@BASEBOARD_FAB2_LIB.BASEBOARD_FAB2(SCH_1):PAGE37_I311@CHPSET_LIB.SKX_EXT_B(CHIPS)':
 'VCCIN'<103>: CDS_PINID='VCCIN(103)';
NODE_NAME     U5D1 BT75
 '@BASEBOARD_FAB2_LIB.BASEBOARD_FAB2(SCH_1):PAGE37_I311@CHPSET_LIB.SKX_EXT_B(CHIPS)':
 'VCCIN'<104>: CDS_PINID='VCCIN(104)';
NODE_NAME     U5D1 BT73
 '@BASEBOARD_FAB2_LIB.BASEBOARD_FAB2(SCH_1):PAGE37_I311@CHPSET_LIB.SKX_EXT_B(CHIPS)':
 'VCCIN'<105>: CDS_PINID='VCCIN(105)';
NODE_NAME     U5D1 BT71
 '@BASEBOARD_FAB2_LIB.BASEBOARD_FAB2(SCH_1):PAGE37_I311@CHPSET_LIB.SKX_EXT_B(CHIPS)':
 'VCCIN'<106>: CDS_PINID='VCCIN(106)';
NODE_NAME     U5D1 BT69
 '@BASEBOARD_FAB2_LIB.BASEBOARD_FAB2(SCH_1):PAGE37_I311@CHPSET_LIB.SKX_EXT_B(CHIPS)':
 'VCCIN'<107>: CDS_PINID='VCCIN(107)';
NODE_NAME     U5D1 BT67
 '@BASEBOARD_FAB2_LIB.BASEBOARD_FAB2(SCH_1):PAGE37_I311@CHPSET_LIB.SKX_EXT_B(CHIPS)':
 'VCCIN'<108>: CDS_PINID='VCCIN(108)';
NODE_NAME     U5D1 BT65
 '@BASEBOARD_FAB2_LIB.BASEBOARD_FAB2(SCH_1):PAGE37_I311@CHPSET_LIB.SKX_EXT_B(CHIPS)':
 'VCCIN'<109>: CDS_PINID='VCCIN(109)';
NODE_NAME     U5D1 BT63
 '@BASEBOARD_FAB2_LIB.BASEBOARD_FAB2(SCH_1):PAGE37_I311@CHPSET_LIB.SKX_EXT_B(CHIPS)':
 'VCCIN'<110>: CDS_PINID='VCCIN(110)';
NODE_NAME     U5D1 BT61
 '@BASEBOARD_FAB2_LIB.BASEBOARD_FAB2(SCH_1):PAGE37_I311@CHPSET_LIB.SKX_EXT_B(CHIPS)':
 'VCCIN'<111>: CDS_PINID='VCCIN(111)';
NODE_NAME     U5D1 BR84
 '@BASEBOARD_FAB2_LIB.BASEBOARD_FAB2(SCH_1):PAGE37_I311@CHPSET_LIB.SKX_EXT_B(CHIPS)':
 'VCCIN'<112>: CDS_PINID='VCCIN(112)';
NODE_NAME     U5D1 BR62
 '@BASEBOARD_FAB2_LIB.BASEBOARD_FAB2(SCH_1):PAGE37_I311@CHPSET_LIB.SKX_EXT_B(CHIPS)':
 'VCCIN'<113>: CDS_PINID='VCCIN(113)';
NODE_NAME     U5D1 BR60
 '@BASEBOARD_FAB2_LIB.BASEBOARD_FAB2(SCH_1):PAGE37_I311@CHPSET_LIB.SKX_EXT_B(CHIPS)':
 'VCCIN'<114>: CDS_PINID='VCCIN(114)';
NODE_NAME     U5D1 BP83
 '@BASEBOARD_FAB2_LIB.BASEBOARD_FAB2(SCH_1):PAGE37_I311@CHPSET_LIB.SKX_EXT_B(CHIPS)':
 'VCCIN'<115>: CDS_PINID='VCCIN(115)';
NODE_NAME     U5D1 BP81
 '@BASEBOARD_FAB2_LIB.BASEBOARD_FAB2(SCH_1):PAGE37_I311@CHPSET_LIB.SKX_EXT_B(CHIPS)':
 'VCCIN'<116>: CDS_PINID='VCCIN(116)';
NODE_NAME     U5D1 BP79
 '@BASEBOARD_FAB2_LIB.BASEBOARD_FAB2(SCH_1):PAGE37_I311@CHPSET_LIB.SKX_EXT_B(CHIPS)':
 'VCCIN'<117>: CDS_PINID='VCCIN(117)';
NODE_NAME     U5D1 BP77
 '@BASEBOARD_FAB2_LIB.BASEBOARD_FAB2(SCH_1):PAGE37_I311@CHPSET_LIB.SKX_EXT_B(CHIPS)':
 'VCCIN'<118>: CDS_PINID='VCCIN(118)';
NODE_NAME     U5D1 BP75
 '@BASEBOARD_FAB2_LIB.BASEBOARD_FAB2(SCH_1):PAGE37_I311@CHPSET_LIB.SKX_EXT_B(CHIPS)':
 'VCCIN'<119>: CDS_PINID='VCCIN(119)';
NODE_NAME     U5D1 BP73
 '@BASEBOARD_FAB2_LIB.BASEBOARD_FAB2(SCH_1):PAGE37_I311@CHPSET_LIB.SKX_EXT_B(CHIPS)':
 'VCCIN'<120>: CDS_PINID='VCCIN(120)';
NODE_NAME     U5D1 BP71
 '@BASEBOARD_FAB2_LIB.BASEBOARD_FAB2(SCH_1):PAGE37_I311@CHPSET_LIB.SKX_EXT_B(CHIPS)':
 'VCCIN'<121>: CDS_PINID='VCCIN(121)';
NODE_NAME     U5D1 BP69
 '@BASEBOARD_FAB2_LIB.BASEBOARD_FAB2(SCH_1):PAGE37_I311@CHPSET_LIB.SKX_EXT_B(CHIPS)':
 'VCCIN'<122>: CDS_PINID='VCCIN(122)';
NODE_NAME     U5D1 BP67
 '@BASEBOARD_FAB2_LIB.BASEBOARD_FAB2(SCH_1):PAGE37_I311@CHPSET_LIB.SKX_EXT_B(CHIPS)':
 'VCCIN'<123>: CDS_PINID='VCCIN(123)';
NODE_NAME     U5D1 BP65
 '@BASEBOARD_FAB2_LIB.BASEBOARD_FAB2(SCH_1):PAGE37_I311@CHPSET_LIB.SKX_EXT_B(CHIPS)':
 'VCCIN'<124>: CDS_PINID='VCCIN(124)';
NODE_NAME     U5D1 BP63
 '@BASEBOARD_FAB2_LIB.BASEBOARD_FAB2(SCH_1):PAGE37_I311@CHPSET_LIB.SKX_EXT_B(CHIPS)':
 'VCCIN'<125>: CDS_PINID='VCCIN(125)';
NODE_NAME     U5D1 BP61
 '@BASEBOARD_FAB2_LIB.BASEBOARD_FAB2(SCH_1):PAGE37_I311@CHPSET_LIB.SKX_EXT_B(CHIPS)':
 'VCCIN'<126>: CDS_PINID='VCCIN(126)';
NODE_NAME     U5D1 BN84
 '@BASEBOARD_FAB2_LIB.BASEBOARD_FAB2(SCH_1):PAGE37_I311@CHPSET_LIB.SKX_EXT_B(CHIPS)':
 'VCCIN'<127>: CDS_PINID='VCCIN(127)';
NODE_NAME     U5D1 BN82
 '@BASEBOARD_FAB2_LIB.BASEBOARD_FAB2(SCH_1):PAGE37_I311@CHPSET_LIB.SKX_EXT_B(CHIPS)':
 'VCCIN'<128>: CDS_PINID='VCCIN(128)';
NODE_NAME     U5D1 BN80
 '@BASEBOARD_FAB2_LIB.BASEBOARD_FAB2(SCH_1):PAGE37_I311@CHPSET_LIB.SKX_EXT_B(CHIPS)':
 'VCCIN'<129>: CDS_PINID='VCCIN(129)';
NODE_NAME     C5P23 1
 '@BASEBOARD_FAB2_LIB.BASEBOARD_FAB2(SCH_1):PAGE42_I28@MSTR_DISCRETE.CAP(CHIPS)':
 'A': CDS_PINID='A';
NODE_NAME     C5P24 1
 '@BASEBOARD_FAB2_LIB.BASEBOARD_FAB2(SCH_1):PAGE42_I33@MSTR_DISCRETE.CAP(CHIPS)':
 'A': CDS_PINID='A';
NODE_NAME     C5P25 1
 '@BASEBOARD_FAB2_LIB.BASEBOARD_FAB2(SCH_1):PAGE42_I37@MSTR_DISCRETE.CAP(CHIPS)':
 'A': CDS_PINID='A';
NODE_NAME     C5P14 1
 '@BASEBOARD_FAB2_LIB.BASEBOARD_FAB2(SCH_1):PAGE42_I41@MSTR_DISCRETE.CAP(CHIPS)':
 'A': CDS_PINID='A';
NODE_NAME     C5P27 1
 '@BASEBOARD_FAB2_LIB.BASEBOARD_FAB2(SCH_1):PAGE42_I44@MSTR_DISCRETE.CAP(CHIPS)':
 'A': CDS_PINID='A';
NODE_NAME     C5P33 1
 '@BASEBOARD_FAB2_LIB.BASEBOARD_FAB2(SCH_1):PAGE42_I50@MSTR_DISCRETE.CAP(CHIPS)':
 'A': CDS_PINID='A';
NODE_NAME     C5P35 1
 '@BASEBOARD_FAB2_LIB.BASEBOARD_FAB2(SCH_1):PAGE42_I51@MSTR_DISCRETE.CAP(CHIPS)':
 'A': CDS_PINID='A';
NODE_NAME     C5P32 1
 '@BASEBOARD_FAB2_LIB.BASEBOARD_FAB2(SCH_1):PAGE42_I53@MSTR_DISCRETE.CAP(CHIPS)':
 'A': CDS_PINID='A';
NODE_NAME     C5P34 1
 '@BASEBOARD_FAB2_LIB.BASEBOARD_FAB2(SCH_1):PAGE42_I54@MSTR_DISCRETE.CAP(CHIPS)':
 'A': CDS_PINID='A';
NODE_NAME     C5P22 1
 '@BASEBOARD_FAB2_LIB.BASEBOARD_FAB2(SCH_1):PAGE42_I55@MSTR_DISCRETE.CAP(CHIPS)':
 'A': CDS_PINID='A';
NODE_NAME     C5P26 1
 '@BASEBOARD_FAB2_LIB.BASEBOARD_FAB2(SCH_1):PAGE42_I56@MSTR_DISCRETE.CAP(CHIPS)':
 'A': CDS_PINID='A';
NODE_NAME     C5P40 1
 '@BASEBOARD_FAB2_LIB.BASEBOARD_FAB2(SCH_1):PAGE42_I57@MSTR_DISCRETE.CAP(CHIPS)':
 'A': CDS_PINID='A';
NODE_NAME     C5P37 1
 '@BASEBOARD_FAB2_LIB.BASEBOARD_FAB2(SCH_1):PAGE42_I63@MSTR_DISCRETE.CAP(CHIPS)':
 'A': CDS_PINID='A';
NODE_NAME     C5P36 1
 '@BASEBOARD_FAB2_LIB.BASEBOARD_FAB2(SCH_1):PAGE42_I65@MSTR_DISCRETE.CAP(CHIPS)':
 'A': CDS_PINID='A';
NODE_NAME     C5D28 1
 '@BASEBOARD_FAB2_LIB.BASEBOARD_FAB2(SCH_1):PAGE42_I100@DEV_DISCRETE.CAP_A(CHIPS)':
 'A': CDS_PINID='A';
NODE_NAME     C5D29 1
 '@BASEBOARD_FAB2_LIB.BASEBOARD_FAB2(SCH_1):PAGE42_I102@DEV_DISCRETE.CAP_A(CHIPS)':
 'A': CDS_PINID='A';
NODE_NAME     C5D32 1
 '@BASEBOARD_FAB2_LIB.BASEBOARD_FAB2(SCH_1):PAGE42_I103@DEV_DISCRETE.CAP_A(CHIPS)':
 'A': CDS_PINID='A';
NODE_NAME     C5D47 1
 '@BASEBOARD_FAB2_LIB.BASEBOARD_FAB2(SCH_1):PAGE42_I104@DEV_DISCRETE.CAP_A(CHIPS)':
 'A': CDS_PINID='A';
NODE_NAME     C5D31 1
 '@BASEBOARD_FAB2_LIB.BASEBOARD_FAB2(SCH_1):PAGE42_I106@DEV_DISCRETE.CAP_A(CHIPS)':
 'A': CDS_PINID='A';
NODE_NAME     C5D46 1
 '@BASEBOARD_FAB2_LIB.BASEBOARD_FAB2(SCH_1):PAGE42_I107@DEV_DISCRETE.CAP_A(CHIPS)':
 'A': CDS_PINID='A';
NODE_NAME     C5D27 1
 '@BASEBOARD_FAB2_LIB.BASEBOARD_FAB2(SCH_1):PAGE42_I109@DEV_DISCRETE.CAP_A(CHIPS)':
 'A': CDS_PINID='A';
NODE_NAME     C5D30 1
 '@BASEBOARD_FAB2_LIB.BASEBOARD_FAB2(SCH_1):PAGE42_I111@DEV_DISCRETE.CAP_A(CHIPS)':
 'A': CDS_PINID='A';
NODE_NAME     C5D41 1
 '@BASEBOARD_FAB2_LIB.BASEBOARD_FAB2(SCH_1):PAGE42_I114@DEV_DISCRETE.CAP_A(CHIPS)':
 'A': CDS_PINID='A';
NODE_NAME     C5D40 1
 '@BASEBOARD_FAB2_LIB.BASEBOARD_FAB2(SCH_1):PAGE42_I115@DEV_DISCRETE.CAP_A(CHIPS)':
 'A': CDS_PINID='A';
NODE_NAME     C5D14 1
 '@BASEBOARD_FAB2_LIB.BASEBOARD_FAB2(SCH_1):PAGE42_I117@DEV_DISCRETE.CAP_A(CHIPS)':
 'A': CDS_PINID='A';
NODE_NAME     C5D17 1
 '@BASEBOARD_FAB2_LIB.BASEBOARD_FAB2(SCH_1):PAGE42_I118@DEV_DISCRETE.CAP_A(CHIPS)':
 'A': CDS_PINID='A';
NODE_NAME     C5D16 1
 '@BASEBOARD_FAB2_LIB.BASEBOARD_FAB2(SCH_1):PAGE42_I123@DEV_DISCRETE.CAP_A(CHIPS)':
 'A': CDS_PINID='A';
NODE_NAME     C5D5 1
 '@BASEBOARD_FAB2_LIB.BASEBOARD_FAB2(SCH_1):PAGE42_I125@DEV_DISCRETE.CAP_A(CHIPS)':
 'A': CDS_PINID='A';
NODE_NAME     C5D19 1
 '@BASEBOARD_FAB2_LIB.BASEBOARD_FAB2(SCH_1):PAGE42_I128@DEV_DISCRETE.CAP_A(CHIPS)':
 'A': CDS_PINID='A';
NODE_NAME     C5D43 1
 '@BASEBOARD_FAB2_LIB.BASEBOARD_FAB2(SCH_1):PAGE42_I131@DEV_DISCRETE.CAP_A(CHIPS)':
 'A': CDS_PINID='A';
NODE_NAME     C5D15 1
 '@BASEBOARD_FAB2_LIB.BASEBOARD_FAB2(SCH_1):PAGE42_I132@DEV_DISCRETE.CAP_A(CHIPS)':
 'A': CDS_PINID='A';
NODE_NAME     C5D18 1
 '@BASEBOARD_FAB2_LIB.BASEBOARD_FAB2(SCH_1):PAGE42_I134@DEV_DISCRETE.CAP_A(CHIPS)':
 'A': CDS_PINID='A';
NODE_NAME     C5D42 1
 '@BASEBOARD_FAB2_LIB.BASEBOARD_FAB2(SCH_1):PAGE42_I135@DEV_DISCRETE.CAP_A(CHIPS)':
 'A': CDS_PINID='A';
NODE_NAME     C5D24 1
 '@BASEBOARD_FAB2_LIB.BASEBOARD_FAB2(SCH_1):PAGE42_I138@DEV_DISCRETE.CAP_A(CHIPS)':
 'A': CDS_PINID='A';
NODE_NAME     C5D39 1
 '@BASEBOARD_FAB2_LIB.BASEBOARD_FAB2(SCH_1):PAGE42_I140@DEV_DISCRETE.CAP_A(CHIPS)':
 'A': CDS_PINID='A';
NODE_NAME     C5D44 1
 '@BASEBOARD_FAB2_LIB.BASEBOARD_FAB2(SCH_1):PAGE42_I142@DEV_DISCRETE.CAP_A(CHIPS)':
 'A': CDS_PINID='A';
NODE_NAME     C5D26 1
 '@BASEBOARD_FAB2_LIB.BASEBOARD_FAB2(SCH_1):PAGE42_I154@DEV_DISCRETE.CAP_A(CHIPS)':
 'A': CDS_PINID='A';
NODE_NAME     C5D25 1
 '@BASEBOARD_FAB2_LIB.BASEBOARD_FAB2(SCH_1):PAGE42_I155@DEV_DISCRETE.CAP_A(CHIPS)':
 'A': CDS_PINID='A';
NODE_NAME     C5D45 1
 '@BASEBOARD_FAB2_LIB.BASEBOARD_FAB2(SCH_1):PAGE42_I156@DEV_DISCRETE.CAP_A(CHIPS)':
 'A': CDS_PINID='A';
NODE_NAME     C5P15 1
 '@BASEBOARD_FAB2_LIB.BASEBOARD_FAB2(SCH_1):PAGE42_I187@MSTR_DISCRETE.CAP(CHIPS)':
 'A': CDS_PINID='A';
NODE_NAME     C5P16 1
 '@BASEBOARD_FAB2_LIB.BASEBOARD_FAB2(SCH_1):PAGE42_I188@MSTR_DISCRETE.CAP(CHIPS)':
 'A': CDS_PINID='A';
NODE_NAME     C5P17 1
 '@BASEBOARD_FAB2_LIB.BASEBOARD_FAB2(SCH_1):PAGE42_I190@MSTR_DISCRETE.CAP(CHIPS)':
 'A': CDS_PINID='A';
NODE_NAME     C6R7 1
 '@BASEBOARD_FAB2_LIB.BASEBOARD_FAB2(SCH_1):PAGE202_I9@DEV_DISCRETE.CAP_A(CHIPS)':
 'A': CDS_PINID='A';
NODE_NAME     C4E11 1
 '@BASEBOARD_FAB2_LIB.BASEBOARD_FAB2(SCH_1):PAGE202_I27@DEV_DISCRETE.CAP_A(CHIPS)':
 'A': CDS_PINID='A';
NODE_NAME     C4E3 1
 '@BASEBOARD_FAB2_LIB.BASEBOARD_FAB2(SCH_1):PAGE202_I61@DEV_DISCRETE.CAP_A(CHIPS)':
 'A': CDS_PINID='A';
NODE_NAME     C6P16 1
 '@BASEBOARD_FAB2_LIB.BASEBOARD_FAB2(SCH_1):PAGE202_I62@DEV_DISCRETE.CAP_A(CHIPS)':
 'A': CDS_PINID='A';
NODE_NAME     EU4E1 1
 '@BASEBOARD_FAB2_LIB.BASEBOARD_FAB2(SCH_1):PAGE202_I63@MSTR_DISCRETE.IR354XX(CHIPS)':
 'VOS': CDS_PINID='VOS';
NODE_NAME     EU4D6 1
 '@BASEBOARD_FAB2_LIB.BASEBOARD_FAB2(SCH_1):PAGE202_I64@MSTR_DISCRETE.IR354XX(CHIPS)':
 'VOS': CDS_PINID='VOS';
NODE_NAME     C6R3 1
 '@BASEBOARD_FAB2_LIB.BASEBOARD_FAB2(SCH_1):PAGE203_I16@MSTR_DISCRETE.CAPP(CHIPS)':
 'A': CDS_PINID='A';
NODE_NAME     C6R9 1
 '@BASEBOARD_FAB2_LIB.BASEBOARD_FAB2(SCH_1):PAGE203_I18@MSTR_DISCRETE.CAPP(CHIPS)':
 'A': CDS_PINID='A';
NODE_NAME     C6P3 1
 '@BASEBOARD_FAB2_LIB.BASEBOARD_FAB2(SCH_1):PAGE203_I25@DEV_DISCRETE.CAP_A(CHIPS)':
 'A': CDS_PINID='A';
NODE_NAME     C6P23 1
 '@BASEBOARD_FAB2_LIB.BASEBOARD_FAB2(SCH_1):PAGE203_I28@MSTR_DISCRETE.CAPP(CHIPS)':
 'A': CDS_PINID='A';
NODE_NAME     C6P14 1
 '@BASEBOARD_FAB2_LIB.BASEBOARD_FAB2(SCH_1):PAGE203_I29@MSTR_DISCRETE.CAPP(CHIPS)':
 'A': CDS_PINID='A';
NODE_NAME     C6P18 1
 '@BASEBOARD_FAB2_LIB.BASEBOARD_FAB2(SCH_1):PAGE203_I30@MSTR_DISCRETE.CAPP(CHIPS)':
 'A': CDS_PINID='A';
NODE_NAME     C6P8 1
 '@BASEBOARD_FAB2_LIB.BASEBOARD_FAB2(SCH_1):PAGE203_I32@MSTR_DISCRETE.CAPP(CHIPS)':
 'A': CDS_PINID='A';
NODE_NAME     C6N9 1
 '@BASEBOARD_FAB2_LIB.BASEBOARD_FAB2(SCH_1):PAGE203_I34@MSTR_DISCRETE.CAPP(CHIPS)':
 'A': CDS_PINID='A';
NODE_NAME     C6P21 1
 '@BASEBOARD_FAB2_LIB.BASEBOARD_FAB2(SCH_1):PAGE203_I66@DEV_DISCRETE.CAP_A(CHIPS)':
 'A': CDS_PINID='A';
NODE_NAME     R4E13 1
 '@BASEBOARD_FAB2_LIB.BASEBOARD_FAB2(SCH_1):PAGE203_I67@MSTR_DISCRETE.RES(CHIPS)':
 'A': CDS_PINID='A';
NODE_NAME     C4D34 1
 '@BASEBOARD_FAB2_LIB.BASEBOARD_FAB2(SCH_1):PAGE203_I68@DEV_DISCRETE.CAP_A(CHIPS)':
 'A': CDS_PINID='A';
NODE_NAME     C4D4 1
 '@BASEBOARD_FAB2_LIB.BASEBOARD_FAB2(SCH_1):PAGE203_I69@DEV_DISCRETE.CAP_A(CHIPS)':
 'A': CDS_PINID='A';
NODE_NAME     EU4D3 1
 '@BASEBOARD_FAB2_LIB.BASEBOARD_FAB2(SCH_1):PAGE203_I70@MSTR_DISCRETE.IR354XX(CHIPS)':
 'VOS': CDS_PINID='VOS';
NODE_NAME     EU4D1 1
 '@BASEBOARD_FAB2_LIB.BASEBOARD_FAB2(SCH_1):PAGE203_I71@MSTR_DISCRETE.IR354XX(CHIPS)':
 'VOS': CDS_PINID='VOS';
NODE_NAME     C4D12 1
 '@BASEBOARD_FAB2_LIB.BASEBOARD_FAB2(SCH_1):PAGE204_I9@DEV_DISCRETE.CAP_A(CHIPS)':
 'A': CDS_PINID='A';
NODE_NAME     R4E14 2
 '@BASEBOARD_FAB2_LIB.BASEBOARD_FAB2(SCH_1):PAGE204_I60@MSTR_DISCRETE.RES(CHIPS)':
 'B': CDS_PINID='B';
NODE_NAME     C6R2 1
 '@BASEBOARD_FAB2_LIB.BASEBOARD_FAB2(SCH_1):PAGE204_I70@DEV_DISCRETE.CAP_A(CHIPS)':
 'A': CDS_PINID='A';
NODE_NAME     EU4C2 1
 '@BASEBOARD_FAB2_LIB.BASEBOARD_FAB2(SCH_1):PAGE204_I71@MSTR_DISCRETE.IR354XX(CHIPS)':
 'VOS': CDS_PINID='VOS';
NODE_NAME     L4E1 2
 '@BASEBOARD_FAB2_LIB.BASEBOARD_FAB2(SCH_1):PAGE202_I109@W_HDL.IND-120NH-30-GP(CHIPS)':
 'F': CDS_PINID='F';
NODE_NAME     L4D3 2
 '@BASEBOARD_FAB2_LIB.BASEBOARD_FAB2(SCH_1):PAGE202_I110@W_HDL.IND-120NH-30-GP(CHIPS)':
 'F': CDS_PINID='F';
NODE_NAME     L4D2 2
 '@BASEBOARD_FAB2_LIB.BASEBOARD_FAB2(SCH_1):PAGE203_I130@W_HDL.IND-120NH-30-GP(CHIPS)':
 'F': CDS_PINID='F';
NODE_NAME     L4D1 2
 '@BASEBOARD_FAB2_LIB.BASEBOARD_FAB2(SCH_1):PAGE203_I131@W_HDL.IND-120NH-30-GP(CHIPS)':
 'F': CDS_PINID='F';
NODE_NAME     L4C3 2
 '@BASEBOARD_FAB2_LIB.BASEBOARD_FAB2(SCH_1):PAGE204_I104@W_HDL.IND-120NH-30-GP(CHIPS)':
 'F': CDS_PINID='F';
NODE_NAME     C8W3 1
 '@BASEBOARD_FAB2_LIB.BASEBOARD_FAB2(SCH_1):PAGE42_I211@MSTR_DISCRETE.CAP(CHIPS)':
 'A': CDS_PINID='A';
NET_NAME
'PVCCIN_CPU1'
 '@BASEBOARD_FAB2_LIB.BASEBOARD_FAB2(SCH_1):PVCCIN_CPU1':
 C_SIGNAL='@baseboard_fab2_lib.baseboard_fab2(sch_1):pvccin_cpu1';
NODE_NAME     RT8P1 1
 '@BASEBOARD_FAB2_LIB.BASEBOARD_FAB2(SCH_1):PAGE71_I49@MSTR_DISCRETE.RES(CHIPS)':
 'A': CDS_PINID='A';
NODE_NAME     U2D1 BN78
 '@BASEBOARD_FAB2_LIB.BASEBOARD_FAB2(SCH_1):PAGE71_I50@CHPSET_LIB.SKX_EXT_B(CHIPS)':
 'VCCIN'<130>: CDS_PINID='VCCIN(130)';
NODE_NAME     U2D1 BN76
 '@BASEBOARD_FAB2_LIB.BASEBOARD_FAB2(SCH_1):PAGE71_I50@CHPSET_LIB.SKX_EXT_B(CHIPS)':
 'VCCIN'<131>: CDS_PINID='VCCIN(131)';
NODE_NAME     U2D1 BN74
 '@BASEBOARD_FAB2_LIB.BASEBOARD_FAB2(SCH_1):PAGE71_I50@CHPSET_LIB.SKX_EXT_B(CHIPS)':
 'VCCIN'<132>: CDS_PINID='VCCIN(132)';
NODE_NAME     U2D1 BN72
 '@BASEBOARD_FAB2_LIB.BASEBOARD_FAB2(SCH_1):PAGE71_I50@CHPSET_LIB.SKX_EXT_B(CHIPS)':
 'VCCIN'<133>: CDS_PINID='VCCIN(133)';
NODE_NAME     U2D1 BN70
 '@BASEBOARD_FAB2_LIB.BASEBOARD_FAB2(SCH_1):PAGE71_I50@CHPSET_LIB.SKX_EXT_B(CHIPS)':
 'VCCIN'<134>: CDS_PINID='VCCIN(134)';
NODE_NAME     U2D1 BN68
 '@BASEBOARD_FAB2_LIB.BASEBOARD_FAB2(SCH_1):PAGE71_I50@CHPSET_LIB.SKX_EXT_B(CHIPS)':
 'VCCIN'<135>: CDS_PINID='VCCIN(135)';
NODE_NAME     U2D1 BN66
 '@BASEBOARD_FAB2_LIB.BASEBOARD_FAB2(SCH_1):PAGE71_I50@CHPSET_LIB.SKX_EXT_B(CHIPS)':
 'VCCIN'<136>: CDS_PINID='VCCIN(136)';
NODE_NAME     U2D1 BN64
 '@BASEBOARD_FAB2_LIB.BASEBOARD_FAB2(SCH_1):PAGE71_I50@CHPSET_LIB.SKX_EXT_B(CHIPS)':
 'VCCIN'<137>: CDS_PINID='VCCIN(137)';
NODE_NAME     U2D1 BN62
 '@BASEBOARD_FAB2_LIB.BASEBOARD_FAB2(SCH_1):PAGE71_I50@CHPSET_LIB.SKX_EXT_B(CHIPS)':
 'VCCIN'<138>: CDS_PINID='VCCIN(138)';
NODE_NAME     U2D1 BN60
 '@BASEBOARD_FAB2_LIB.BASEBOARD_FAB2(SCH_1):PAGE71_I50@CHPSET_LIB.SKX_EXT_B(CHIPS)':
 'VCCIN'<139>: CDS_PINID='VCCIN(139)';
NODE_NAME     U2D1 BM83
 '@BASEBOARD_FAB2_LIB.BASEBOARD_FAB2(SCH_1):PAGE71_I50@CHPSET_LIB.SKX_EXT_B(CHIPS)':
 'VCCIN'<140>: CDS_PINID='VCCIN(140)';
NODE_NAME     U2D1 BM81
 '@BASEBOARD_FAB2_LIB.BASEBOARD_FAB2(SCH_1):PAGE71_I50@CHPSET_LIB.SKX_EXT_B(CHIPS)':
 'VCCIN'<141>: CDS_PINID='VCCIN(141)';
NODE_NAME     U2D1 BM79
 '@BASEBOARD_FAB2_LIB.BASEBOARD_FAB2(SCH_1):PAGE71_I50@CHPSET_LIB.SKX_EXT_B(CHIPS)':
 'VCCIN'<142>: CDS_PINID='VCCIN(142)';
NODE_NAME     U2D1 BM77
 '@BASEBOARD_FAB2_LIB.BASEBOARD_FAB2(SCH_1):PAGE71_I50@CHPSET_LIB.SKX_EXT_B(CHIPS)':
 'VCCIN'<143>: CDS_PINID='VCCIN(143)';
NODE_NAME     U2D1 BM75
 '@BASEBOARD_FAB2_LIB.BASEBOARD_FAB2(SCH_1):PAGE71_I50@CHPSET_LIB.SKX_EXT_B(CHIPS)':
 'VCCIN'<144>: CDS_PINID='VCCIN(144)';
NODE_NAME     U2D1 BM73
 '@BASEBOARD_FAB2_LIB.BASEBOARD_FAB2(SCH_1):PAGE71_I50@CHPSET_LIB.SKX_EXT_B(CHIPS)':
 'VCCIN'<145>: CDS_PINID='VCCIN(145)';
NODE_NAME     U2D1 BM71
 '@BASEBOARD_FAB2_LIB.BASEBOARD_FAB2(SCH_1):PAGE71_I50@CHPSET_LIB.SKX_EXT_B(CHIPS)':
 'VCCIN'<146>: CDS_PINID='VCCIN(146)';
NODE_NAME     U2D1 BM69
 '@BASEBOARD_FAB2_LIB.BASEBOARD_FAB2(SCH_1):PAGE71_I50@CHPSET_LIB.SKX_EXT_B(CHIPS)':
 'VCCIN'<147>: CDS_PINID='VCCIN(147)';
NODE_NAME     U2D1 BM67
 '@BASEBOARD_FAB2_LIB.BASEBOARD_FAB2(SCH_1):PAGE71_I50@CHPSET_LIB.SKX_EXT_B(CHIPS)':
 'VCCIN'<148>: CDS_PINID='VCCIN(148)';
NODE_NAME     U2D1 BM65
 '@BASEBOARD_FAB2_LIB.BASEBOARD_FAB2(SCH_1):PAGE71_I50@CHPSET_LIB.SKX_EXT_B(CHIPS)':
 'VCCIN'<149>: CDS_PINID='VCCIN(149)';
NODE_NAME     U2D1 BM63
 '@BASEBOARD_FAB2_LIB.BASEBOARD_FAB2(SCH_1):PAGE71_I50@CHPSET_LIB.SKX_EXT_B(CHIPS)':
 'VCCIN'<150>: CDS_PINID='VCCIN(150)';
NODE_NAME     U2D1 BM61
 '@BASEBOARD_FAB2_LIB.BASEBOARD_FAB2(SCH_1):PAGE71_I50@CHPSET_LIB.SKX_EXT_B(CHIPS)':
 'VCCIN'<151>: CDS_PINID='VCCIN(151)';
NODE_NAME     U2D1 BL84
 '@BASEBOARD_FAB2_LIB.BASEBOARD_FAB2(SCH_1):PAGE71_I50@CHPSET_LIB.SKX_EXT_B(CHIPS)':
 'VCCIN'<152>: CDS_PINID='VCCIN(152)';
NODE_NAME     U2D1 BL62
 '@BASEBOARD_FAB2_LIB.BASEBOARD_FAB2(SCH_1):PAGE71_I50@CHPSET_LIB.SKX_EXT_B(CHIPS)':
 'VCCIN'<153>: CDS_PINID='VCCIN(153)';
NODE_NAME     U2D1 BL60
 '@BASEBOARD_FAB2_LIB.BASEBOARD_FAB2(SCH_1):PAGE71_I50@CHPSET_LIB.SKX_EXT_B(CHIPS)':
 'VCCIN'<154>: CDS_PINID='VCCIN(154)';
NODE_NAME     U2D1 BK83
 '@BASEBOARD_FAB2_LIB.BASEBOARD_FAB2(SCH_1):PAGE71_I50@CHPSET_LIB.SKX_EXT_B(CHIPS)':
 'VCCIN'<155>: CDS_PINID='VCCIN(155)';
NODE_NAME     U2D1 BK81
 '@BASEBOARD_FAB2_LIB.BASEBOARD_FAB2(SCH_1):PAGE71_I50@CHPSET_LIB.SKX_EXT_B(CHIPS)':
 'VCCIN'<156>: CDS_PINID='VCCIN(156)';
NODE_NAME     U2D1 BK79
 '@BASEBOARD_FAB2_LIB.BASEBOARD_FAB2(SCH_1):PAGE71_I50@CHPSET_LIB.SKX_EXT_B(CHIPS)':
 'VCCIN'<157>: CDS_PINID='VCCIN(157)';
NODE_NAME     U2D1 BK77
 '@BASEBOARD_FAB2_LIB.BASEBOARD_FAB2(SCH_1):PAGE71_I50@CHPSET_LIB.SKX_EXT_B(CHIPS)':
 'VCCIN'<158>: CDS_PINID='VCCIN(158)';
NODE_NAME     U2D1 BK75
 '@BASEBOARD_FAB2_LIB.BASEBOARD_FAB2(SCH_1):PAGE71_I50@CHPSET_LIB.SKX_EXT_B(CHIPS)':
 'VCCIN'<159>: CDS_PINID='VCCIN(159)';
NODE_NAME     U2D1 BK73
 '@BASEBOARD_FAB2_LIB.BASEBOARD_FAB2(SCH_1):PAGE71_I50@CHPSET_LIB.SKX_EXT_B(CHIPS)':
 'VCCIN'<160>: CDS_PINID='VCCIN(160)';
NODE_NAME     U2D1 BK71
 '@BASEBOARD_FAB2_LIB.BASEBOARD_FAB2(SCH_1):PAGE71_I50@CHPSET_LIB.SKX_EXT_B(CHIPS)':
 'VCCIN'<161>: CDS_PINID='VCCIN(161)';
NODE_NAME     U2D1 BK69
 '@BASEBOARD_FAB2_LIB.BASEBOARD_FAB2(SCH_1):PAGE71_I50@CHPSET_LIB.SKX_EXT_B(CHIPS)':
 'VCCIN'<162>: CDS_PINID='VCCIN(162)';
NODE_NAME     U2D1 BK67
 '@BASEBOARD_FAB2_LIB.BASEBOARD_FAB2(SCH_1):PAGE71_I50@CHPSET_LIB.SKX_EXT_B(CHIPS)':
 'VCCIN'<163>: CDS_PINID='VCCIN(163)';
NODE_NAME     U2D1 BK65
 '@BASEBOARD_FAB2_LIB.BASEBOARD_FAB2(SCH_1):PAGE71_I50@CHPSET_LIB.SKX_EXT_B(CHIPS)':
 'VCCIN'<164>: CDS_PINID='VCCIN(164)';
NODE_NAME     U2D1 BK63
 '@BASEBOARD_FAB2_LIB.BASEBOARD_FAB2(SCH_1):PAGE71_I50@CHPSET_LIB.SKX_EXT_B(CHIPS)':
 'VCCIN'<165>: CDS_PINID='VCCIN(165)';
NODE_NAME     U2D1 BK61
 '@BASEBOARD_FAB2_LIB.BASEBOARD_FAB2(SCH_1):PAGE71_I50@CHPSET_LIB.SKX_EXT_B(CHIPS)':
 'VCCIN'<166>: CDS_PINID='VCCIN(166)';
NODE_NAME     U2D1 BJ84
 '@BASEBOARD_FAB2_LIB.BASEBOARD_FAB2(SCH_1):PAGE71_I50@CHPSET_LIB.SKX_EXT_B(CHIPS)':
 'VCCIN'<167>: CDS_PINID='VCCIN(167)';
NODE_NAME     U2D1 BJ82
 '@BASEBOARD_FAB2_LIB.BASEBOARD_FAB2(SCH_1):PAGE71_I50@CHPSET_LIB.SKX_EXT_B(CHIPS)':
 'VCCIN'<168>: CDS_PINID='VCCIN(168)';
NODE_NAME     U2D1 BJ80
 '@BASEBOARD_FAB2_LIB.BASEBOARD_FAB2(SCH_1):PAGE71_I50@CHPSET_LIB.SKX_EXT_B(CHIPS)':
 'VCCIN'<169>: CDS_PINID='VCCIN(169)';
NODE_NAME     U2D1 BJ78
 '@BASEBOARD_FAB2_LIB.BASEBOARD_FAB2(SCH_1):PAGE71_I50@CHPSET_LIB.SKX_EXT_B(CHIPS)':
 'VCCIN'<170>: CDS_PINID='VCCIN(170)';
NODE_NAME     U2D1 BJ76
 '@BASEBOARD_FAB2_LIB.BASEBOARD_FAB2(SCH_1):PAGE71_I50@CHPSET_LIB.SKX_EXT_B(CHIPS)':
 'VCCIN'<171>: CDS_PINID='VCCIN(171)';
NODE_NAME     U2D1 BJ74
 '@BASEBOARD_FAB2_LIB.BASEBOARD_FAB2(SCH_1):PAGE71_I50@CHPSET_LIB.SKX_EXT_B(CHIPS)':
 'VCCIN'<172>: CDS_PINID='VCCIN(172)';
NODE_NAME     U2D1 BJ72
 '@BASEBOARD_FAB2_LIB.BASEBOARD_FAB2(SCH_1):PAGE71_I50@CHPSET_LIB.SKX_EXT_B(CHIPS)':
 'VCCIN'<173>: CDS_PINID='VCCIN(173)';
NODE_NAME     U2D1 BJ70
 '@BASEBOARD_FAB2_LIB.BASEBOARD_FAB2(SCH_1):PAGE71_I50@CHPSET_LIB.SKX_EXT_B(CHIPS)':
 'VCCIN'<174>: CDS_PINID='VCCIN(174)';
NODE_NAME     U2D1 BJ68
 '@BASEBOARD_FAB2_LIB.BASEBOARD_FAB2(SCH_1):PAGE71_I50@CHPSET_LIB.SKX_EXT_B(CHIPS)':
 'VCCIN'<175>: CDS_PINID='VCCIN(175)';
NODE_NAME     U2D1 BJ66
 '@BASEBOARD_FAB2_LIB.BASEBOARD_FAB2(SCH_1):PAGE71_I50@CHPSET_LIB.SKX_EXT_B(CHIPS)':
 'VCCIN'<176>: CDS_PINID='VCCIN(176)';
NODE_NAME     U2D1 BJ64
 '@BASEBOARD_FAB2_LIB.BASEBOARD_FAB2(SCH_1):PAGE71_I50@CHPSET_LIB.SKX_EXT_B(CHIPS)':
 'VCCIN'<177>: CDS_PINID='VCCIN(177)';
NODE_NAME     U2D1 BJ62
 '@BASEBOARD_FAB2_LIB.BASEBOARD_FAB2(SCH_1):PAGE71_I50@CHPSET_LIB.SKX_EXT_B(CHIPS)':
 'VCCIN'<178>: CDS_PINID='VCCIN(178)';
NODE_NAME     U2D1 BJ60
 '@BASEBOARD_FAB2_LIB.BASEBOARD_FAB2(SCH_1):PAGE71_I50@CHPSET_LIB.SKX_EXT_B(CHIPS)':
 'VCCIN'<179>: CDS_PINID='VCCIN(179)';
NODE_NAME     U2D1 BH83
 '@BASEBOARD_FAB2_LIB.BASEBOARD_FAB2(SCH_1):PAGE71_I50@CHPSET_LIB.SKX_EXT_B(CHIPS)':
 'VCCIN'<180>: CDS_PINID='VCCIN(180)';
NODE_NAME     U2D1 BH81
 '@BASEBOARD_FAB2_LIB.BASEBOARD_FAB2(SCH_1):PAGE71_I50@CHPSET_LIB.SKX_EXT_B(CHIPS)':
 'VCCIN'<181>: CDS_PINID='VCCIN(181)';
NODE_NAME     U2D1 BH79
 '@BASEBOARD_FAB2_LIB.BASEBOARD_FAB2(SCH_1):PAGE71_I50@CHPSET_LIB.SKX_EXT_B(CHIPS)':
 'VCCIN'<182>: CDS_PINID='VCCIN(182)';
NODE_NAME     U2D1 BH77
 '@BASEBOARD_FAB2_LIB.BASEBOARD_FAB2(SCH_1):PAGE71_I50@CHPSET_LIB.SKX_EXT_B(CHIPS)':
 'VCCIN'<183>: CDS_PINID='VCCIN(183)';
NODE_NAME     U2D1 BH75
 '@BASEBOARD_FAB2_LIB.BASEBOARD_FAB2(SCH_1):PAGE71_I50@CHPSET_LIB.SKX_EXT_B(CHIPS)':
 'VCCIN'<184>: CDS_PINID='VCCIN(184)';
NODE_NAME     U2D1 BH73
 '@BASEBOARD_FAB2_LIB.BASEBOARD_FAB2(SCH_1):PAGE71_I50@CHPSET_LIB.SKX_EXT_B(CHIPS)':
 'VCCIN'<185>: CDS_PINID='VCCIN(185)';
NODE_NAME     U2D1 BH71
 '@BASEBOARD_FAB2_LIB.BASEBOARD_FAB2(SCH_1):PAGE71_I50@CHPSET_LIB.SKX_EXT_B(CHIPS)':
 'VCCIN'<186>: CDS_PINID='VCCIN(186)';
NODE_NAME     U2D1 BH69
 '@BASEBOARD_FAB2_LIB.BASEBOARD_FAB2(SCH_1):PAGE71_I50@CHPSET_LIB.SKX_EXT_B(CHIPS)':
 'VCCIN'<187>: CDS_PINID='VCCIN(187)';
NODE_NAME     U2D1 BH67
 '@BASEBOARD_FAB2_LIB.BASEBOARD_FAB2(SCH_1):PAGE71_I50@CHPSET_LIB.SKX_EXT_B(CHIPS)':
 'VCCIN'<188>: CDS_PINID='VCCIN(188)';
NODE_NAME     U2D1 BH65
 '@BASEBOARD_FAB2_LIB.BASEBOARD_FAB2(SCH_1):PAGE71_I50@CHPSET_LIB.SKX_EXT_B(CHIPS)':
 'VCCIN'<189>: CDS_PINID='VCCIN(189)';
NODE_NAME     U2D1 BH63
 '@BASEBOARD_FAB2_LIB.BASEBOARD_FAB2(SCH_1):PAGE71_I50@CHPSET_LIB.SKX_EXT_B(CHIPS)':
 'VCCIN'<190>: CDS_PINID='VCCIN(190)';
NODE_NAME     U2D1 BH61
 '@BASEBOARD_FAB2_LIB.BASEBOARD_FAB2(SCH_1):PAGE71_I50@CHPSET_LIB.SKX_EXT_B(CHIPS)':
 'VCCIN'<191>: CDS_PINID='VCCIN(191)';
NODE_NAME     U2D1 BG84
 '@BASEBOARD_FAB2_LIB.BASEBOARD_FAB2(SCH_1):PAGE71_I50@CHPSET_LIB.SKX_EXT_B(CHIPS)':
 'VCCIN'<192>: CDS_PINID='VCCIN(192)';
NODE_NAME     U2D1 BG70
 '@BASEBOARD_FAB2_LIB.BASEBOARD_FAB2(SCH_1):PAGE71_I50@CHPSET_LIB.SKX_EXT_B(CHIPS)':
 'VCCIN'<193>: CDS_PINID='VCCIN(193)';
NODE_NAME     U2D1 BG68
 '@BASEBOARD_FAB2_LIB.BASEBOARD_FAB2(SCH_1):PAGE71_I50@CHPSET_LIB.SKX_EXT_B(CHIPS)':
 'VCCIN'<194>: CDS_PINID='VCCIN(194)';
NODE_NAME     U2D1 BG66
 '@BASEBOARD_FAB2_LIB.BASEBOARD_FAB2(SCH_1):PAGE71_I50@CHPSET_LIB.SKX_EXT_B(CHIPS)':
 'VCCIN'<195>: CDS_PINID='VCCIN(195)';
NODE_NAME     U2D1 BG64
 '@BASEBOARD_FAB2_LIB.BASEBOARD_FAB2(SCH_1):PAGE71_I50@CHPSET_LIB.SKX_EXT_B(CHIPS)':
 'VCCIN'<196>: CDS_PINID='VCCIN(196)';
NODE_NAME     U2D1 BG62
 '@BASEBOARD_FAB2_LIB.BASEBOARD_FAB2(SCH_1):PAGE71_I50@CHPSET_LIB.SKX_EXT_B(CHIPS)':
 'VCCIN'<197>: CDS_PINID='VCCIN(197)';
NODE_NAME     U2D1 BG60
 '@BASEBOARD_FAB2_LIB.BASEBOARD_FAB2(SCH_1):PAGE71_I50@CHPSET_LIB.SKX_EXT_B(CHIPS)':
 'VCCIN'<198>: CDS_PINID='VCCIN(198)';
NODE_NAME     U2D1 BF85
 '@BASEBOARD_FAB2_LIB.BASEBOARD_FAB2(SCH_1):PAGE71_I50@CHPSET_LIB.SKX_EXT_B(CHIPS)':
 'VCCIN'<199>: CDS_PINID='VCCIN(199)';
NODE_NAME     U2D1 BF83
 '@BASEBOARD_FAB2_LIB.BASEBOARD_FAB2(SCH_1):PAGE71_I50@CHPSET_LIB.SKX_EXT_B(CHIPS)':
 'VCCIN'<200>: CDS_PINID='VCCIN(200)';
NODE_NAME     U2D1 BF81
 '@BASEBOARD_FAB2_LIB.BASEBOARD_FAB2(SCH_1):PAGE71_I50@CHPSET_LIB.SKX_EXT_B(CHIPS)':
 'VCCIN'<201>: CDS_PINID='VCCIN(201)';
NODE_NAME     U2D1 BF79
 '@BASEBOARD_FAB2_LIB.BASEBOARD_FAB2(SCH_1):PAGE71_I50@CHPSET_LIB.SKX_EXT_B(CHIPS)':
 'VCCIN'<202>: CDS_PINID='VCCIN(202)';
NODE_NAME     U2D1 BF77
 '@BASEBOARD_FAB2_LIB.BASEBOARD_FAB2(SCH_1):PAGE71_I50@CHPSET_LIB.SKX_EXT_B(CHIPS)':
 'VCCIN'<203>: CDS_PINID='VCCIN(203)';
NODE_NAME     U2D1 BF75
 '@BASEBOARD_FAB2_LIB.BASEBOARD_FAB2(SCH_1):PAGE71_I50@CHPSET_LIB.SKX_EXT_B(CHIPS)':
 'VCCIN'<204>: CDS_PINID='VCCIN(204)';
NODE_NAME     U2D1 BF73
 '@BASEBOARD_FAB2_LIB.BASEBOARD_FAB2(SCH_1):PAGE71_I50@CHPSET_LIB.SKX_EXT_B(CHIPS)':
 'VCCIN'<205>: CDS_PINID='VCCIN(205)';
NODE_NAME     U2D1 BF61
 '@BASEBOARD_FAB2_LIB.BASEBOARD_FAB2(SCH_1):PAGE71_I50@CHPSET_LIB.SKX_EXT_B(CHIPS)':
 'VCCIN'<206>: CDS_PINID='VCCIN(206)';
NODE_NAME     U2D1 BE84
 '@BASEBOARD_FAB2_LIB.BASEBOARD_FAB2(SCH_1):PAGE71_I50@CHPSET_LIB.SKX_EXT_B(CHIPS)':
 'VCCIN'<207>: CDS_PINID='VCCIN(207)';
NODE_NAME     U2D1 BE82
 '@BASEBOARD_FAB2_LIB.BASEBOARD_FAB2(SCH_1):PAGE71_I50@CHPSET_LIB.SKX_EXT_B(CHIPS)':
 'VCCIN'<208>: CDS_PINID='VCCIN(208)';
NODE_NAME     U2D1 BE80
 '@BASEBOARD_FAB2_LIB.BASEBOARD_FAB2(SCH_1):PAGE71_I50@CHPSET_LIB.SKX_EXT_B(CHIPS)':
 'VCCIN'<209>: CDS_PINID='VCCIN(209)';
NODE_NAME     U2D1 BE78
 '@BASEBOARD_FAB2_LIB.BASEBOARD_FAB2(SCH_1):PAGE71_I50@CHPSET_LIB.SKX_EXT_B(CHIPS)':
 'VCCIN'<210>: CDS_PINID='VCCIN(210)';
NODE_NAME     U2D1 BE76
 '@BASEBOARD_FAB2_LIB.BASEBOARD_FAB2(SCH_1):PAGE71_I50@CHPSET_LIB.SKX_EXT_B(CHIPS)':
 'VCCIN'<211>: CDS_PINID='VCCIN(211)';
NODE_NAME     U2D1 BE74
 '@BASEBOARD_FAB2_LIB.BASEBOARD_FAB2(SCH_1):PAGE71_I50@CHPSET_LIB.SKX_EXT_B(CHIPS)':
 'VCCIN'<212>: CDS_PINID='VCCIN(212)';
NODE_NAME     U2D1 BE72
 '@BASEBOARD_FAB2_LIB.BASEBOARD_FAB2(SCH_1):PAGE71_I50@CHPSET_LIB.SKX_EXT_B(CHIPS)':
 'VCCIN'<213>: CDS_PINID='VCCIN(213)';
NODE_NAME     U2D1 BE62
 '@BASEBOARD_FAB2_LIB.BASEBOARD_FAB2(SCH_1):PAGE71_I50@CHPSET_LIB.SKX_EXT_B(CHIPS)':
 'VCCIN'<214>: CDS_PINID='VCCIN(214)';
NODE_NAME     U2D1 BE60
 '@BASEBOARD_FAB2_LIB.BASEBOARD_FAB2(SCH_1):PAGE71_I50@CHPSET_LIB.SKX_EXT_B(CHIPS)':
 'VCCIN'<215>: CDS_PINID='VCCIN(215)';
NODE_NAME     U2D1 BD85
 '@BASEBOARD_FAB2_LIB.BASEBOARD_FAB2(SCH_1):PAGE71_I50@CHPSET_LIB.SKX_EXT_B(CHIPS)':
 'VCCIN'<216>: CDS_PINID='VCCIN(216)';
NODE_NAME     U2D1 BD83
 '@BASEBOARD_FAB2_LIB.BASEBOARD_FAB2(SCH_1):PAGE71_I50@CHPSET_LIB.SKX_EXT_B(CHIPS)':
 'VCCIN'<217>: CDS_PINID='VCCIN(217)';
NODE_NAME     U2D1 BD81
 '@BASEBOARD_FAB2_LIB.BASEBOARD_FAB2(SCH_1):PAGE71_I50@CHPSET_LIB.SKX_EXT_B(CHIPS)':
 'VCCIN'<218>: CDS_PINID='VCCIN(218)';
NODE_NAME     U2D1 BD79
 '@BASEBOARD_FAB2_LIB.BASEBOARD_FAB2(SCH_1):PAGE71_I50@CHPSET_LIB.SKX_EXT_B(CHIPS)':
 'VCCIN'<219>: CDS_PINID='VCCIN(219)';
NODE_NAME     U2D1 BD77
 '@BASEBOARD_FAB2_LIB.BASEBOARD_FAB2(SCH_1):PAGE71_I50@CHPSET_LIB.SKX_EXT_B(CHIPS)':
 'VCCIN'<220>: CDS_PINID='VCCIN(220)';
NODE_NAME     U2D1 BD75
 '@BASEBOARD_FAB2_LIB.BASEBOARD_FAB2(SCH_1):PAGE71_I50@CHPSET_LIB.SKX_EXT_B(CHIPS)':
 'VCCIN'<221>: CDS_PINID='VCCIN(221)';
NODE_NAME     U2D1 BD73
 '@BASEBOARD_FAB2_LIB.BASEBOARD_FAB2(SCH_1):PAGE71_I50@CHPSET_LIB.SKX_EXT_B(CHIPS)':
 'VCCIN'<222>: CDS_PINID='VCCIN(222)';
NODE_NAME     U2D1 BD61
 '@BASEBOARD_FAB2_LIB.BASEBOARD_FAB2(SCH_1):PAGE71_I50@CHPSET_LIB.SKX_EXT_B(CHIPS)':
 'VCCIN'<223>: CDS_PINID='VCCIN(223)';
NODE_NAME     U2D1 BC84
 '@BASEBOARD_FAB2_LIB.BASEBOARD_FAB2(SCH_1):PAGE71_I50@CHPSET_LIB.SKX_EXT_B(CHIPS)':
 'VCCIN'<224>: CDS_PINID='VCCIN(224)';
NODE_NAME     U2D1 BC62
 '@BASEBOARD_FAB2_LIB.BASEBOARD_FAB2(SCH_1):PAGE71_I50@CHPSET_LIB.SKX_EXT_B(CHIPS)':
 'VCCIN'<225>: CDS_PINID='VCCIN(225)';
NODE_NAME     U2D1 BC60
 '@BASEBOARD_FAB2_LIB.BASEBOARD_FAB2(SCH_1):PAGE71_I50@CHPSET_LIB.SKX_EXT_B(CHIPS)':
 'VCCIN'<226>: CDS_PINID='VCCIN(226)';
NODE_NAME     U2D1 BB85
 '@BASEBOARD_FAB2_LIB.BASEBOARD_FAB2(SCH_1):PAGE71_I50@CHPSET_LIB.SKX_EXT_B(CHIPS)':
 'VCCIN'<227>: CDS_PINID='VCCIN(227)';
NODE_NAME     U2D1 BB61
 '@BASEBOARD_FAB2_LIB.BASEBOARD_FAB2(SCH_1):PAGE71_I50@CHPSET_LIB.SKX_EXT_B(CHIPS)':
 'VCCIN'<228>: CDS_PINID='VCCIN(228)';
NODE_NAME     U2D1 BA60
 '@BASEBOARD_FAB2_LIB.BASEBOARD_FAB2(SCH_1):PAGE71_I50@CHPSET_LIB.SKX_EXT_B(CHIPS)':
 'VCCIN'<229>: CDS_PINID='VCCIN(229)';
NODE_NAME     U2D1 AY61
 '@BASEBOARD_FAB2_LIB.BASEBOARD_FAB2(SCH_1):PAGE71_I50@CHPSET_LIB.SKX_EXT_B(CHIPS)':
 'VCCIN'<230>: CDS_PINID='VCCIN(230)';
NODE_NAME     U2D1 AW60
 '@BASEBOARD_FAB2_LIB.BASEBOARD_FAB2(SCH_1):PAGE71_I50@CHPSET_LIB.SKX_EXT_B(CHIPS)':
 'VCCIN'<231>: CDS_PINID='VCCIN(231)';
NODE_NAME     U2D1 AV61
 '@BASEBOARD_FAB2_LIB.BASEBOARD_FAB2(SCH_1):PAGE71_I50@CHPSET_LIB.SKX_EXT_B(CHIPS)':
 'VCCIN'<232>: CDS_PINID='VCCIN(232)';
NODE_NAME     U2D1 AV59
 '@BASEBOARD_FAB2_LIB.BASEBOARD_FAB2(SCH_1):PAGE71_I50@CHPSET_LIB.SKX_EXT_B(CHIPS)':
 'VCCIN'<233>: CDS_PINID='VCCIN(233)';
NODE_NAME     U2D1 AU60
 '@BASEBOARD_FAB2_LIB.BASEBOARD_FAB2(SCH_1):PAGE71_I50@CHPSET_LIB.SKX_EXT_B(CHIPS)':
 'VCCIN'<234>: CDS_PINID='VCCIN(234)';
NODE_NAME     U2D1 AU58
 '@BASEBOARD_FAB2_LIB.BASEBOARD_FAB2(SCH_1):PAGE71_I50@CHPSET_LIB.SKX_EXT_B(CHIPS)':
 'VCCIN'<235>: CDS_PINID='VCCIN(235)';
NODE_NAME     U2D1 AT59
 '@BASEBOARD_FAB2_LIB.BASEBOARD_FAB2(SCH_1):PAGE71_I50@CHPSET_LIB.SKX_EXT_B(CHIPS)':
 'VCCIN'<236>: CDS_PINID='VCCIN(236)';
NODE_NAME     U2D1 AT57
 '@BASEBOARD_FAB2_LIB.BASEBOARD_FAB2(SCH_1):PAGE71_I50@CHPSET_LIB.SKX_EXT_B(CHIPS)':
 'VCCIN'<237>: CDS_PINID='VCCIN(237)';
NODE_NAME     U2D1 AR58
 '@BASEBOARD_FAB2_LIB.BASEBOARD_FAB2(SCH_1):PAGE71_I50@CHPSET_LIB.SKX_EXT_B(CHIPS)':
 'VCCIN'<238>: CDS_PINID='VCCIN(238)';
NODE_NAME     U2D1 AR56
 '@BASEBOARD_FAB2_LIB.BASEBOARD_FAB2(SCH_1):PAGE71_I50@CHPSET_LIB.SKX_EXT_B(CHIPS)':
 'VCCIN'<239>: CDS_PINID='VCCIN(239)';
NODE_NAME     U2D1 AP57
 '@BASEBOARD_FAB2_LIB.BASEBOARD_FAB2(SCH_1):PAGE71_I50@CHPSET_LIB.SKX_EXT_B(CHIPS)':
 'VCCIN'<240>: CDS_PINID='VCCIN(240)';
NODE_NAME     U2D1 AP55
 '@BASEBOARD_FAB2_LIB.BASEBOARD_FAB2(SCH_1):PAGE71_I50@CHPSET_LIB.SKX_EXT_B(CHIPS)':
 'VCCIN'<241>: CDS_PINID='VCCIN(241)';
NODE_NAME     U2D1 AN56
 '@BASEBOARD_FAB2_LIB.BASEBOARD_FAB2(SCH_1):PAGE71_I50@CHPSET_LIB.SKX_EXT_B(CHIPS)':
 'VCCIN'<242>: CDS_PINID='VCCIN(242)';
NODE_NAME     U2D1 AN54
 '@BASEBOARD_FAB2_LIB.BASEBOARD_FAB2(SCH_1):PAGE71_I50@CHPSET_LIB.SKX_EXT_B(CHIPS)':
 'VCCIN'<243>: CDS_PINID='VCCIN(243)';
NODE_NAME     U2D1 AN32
 '@BASEBOARD_FAB2_LIB.BASEBOARD_FAB2(SCH_1):PAGE71_I50@CHPSET_LIB.SKX_EXT_B(CHIPS)':
 'VCCIN'<244>: CDS_PINID='VCCIN(244)';
NODE_NAME     U2D1 AM55
 '@BASEBOARD_FAB2_LIB.BASEBOARD_FAB2(SCH_1):PAGE71_I50@CHPSET_LIB.SKX_EXT_B(CHIPS)':
 'VCCIN'<245>: CDS_PINID='VCCIN(245)';
NODE_NAME     U2D1 AM53
 '@BASEBOARD_FAB2_LIB.BASEBOARD_FAB2(SCH_1):PAGE71_I50@CHPSET_LIB.SKX_EXT_B(CHIPS)':
 'VCCIN'<246>: CDS_PINID='VCCIN(246)';
NODE_NAME     U2D1 AM33
 '@BASEBOARD_FAB2_LIB.BASEBOARD_FAB2(SCH_1):PAGE71_I50@CHPSET_LIB.SKX_EXT_B(CHIPS)':
 'VCCIN'<247>: CDS_PINID='VCCIN(247)';
NODE_NAME     U2D1 AL54
 '@BASEBOARD_FAB2_LIB.BASEBOARD_FAB2(SCH_1):PAGE71_I50@CHPSET_LIB.SKX_EXT_B(CHIPS)':
 'VCCIN'<248>: CDS_PINID='VCCIN(248)';
NODE_NAME     U2D1 AL52
 '@BASEBOARD_FAB2_LIB.BASEBOARD_FAB2(SCH_1):PAGE71_I50@CHPSET_LIB.SKX_EXT_B(CHIPS)':
 'VCCIN'<249>: CDS_PINID='VCCIN(249)';
NODE_NAME     U2D1 AL50
 '@BASEBOARD_FAB2_LIB.BASEBOARD_FAB2(SCH_1):PAGE71_I50@CHPSET_LIB.SKX_EXT_B(CHIPS)':
 'VCCIN'<250>: CDS_PINID='VCCIN(250)';
NODE_NAME     U2D1 AL48
 '@BASEBOARD_FAB2_LIB.BASEBOARD_FAB2(SCH_1):PAGE71_I50@CHPSET_LIB.SKX_EXT_B(CHIPS)':
 'VCCIN'<251>: CDS_PINID='VCCIN(251)';
NODE_NAME     U2D1 AL46
 '@BASEBOARD_FAB2_LIB.BASEBOARD_FAB2(SCH_1):PAGE71_I50@CHPSET_LIB.SKX_EXT_B(CHIPS)':
 'VCCIN'<252>: CDS_PINID='VCCIN(252)';
NODE_NAME     U2D1 AL34
 '@BASEBOARD_FAB2_LIB.BASEBOARD_FAB2(SCH_1):PAGE71_I50@CHPSET_LIB.SKX_EXT_B(CHIPS)':
 'VCCIN'<253>: CDS_PINID='VCCIN(253)';
NODE_NAME     U2D1 AK53
 '@BASEBOARD_FAB2_LIB.BASEBOARD_FAB2(SCH_1):PAGE71_I50@CHPSET_LIB.SKX_EXT_B(CHIPS)':
 'VCCIN'<254>: CDS_PINID='VCCIN(254)';
NODE_NAME     U2D1 AK51
 '@BASEBOARD_FAB2_LIB.BASEBOARD_FAB2(SCH_1):PAGE71_I50@CHPSET_LIB.SKX_EXT_B(CHIPS)':
 'VCCIN'<255>: CDS_PINID='VCCIN(255)';
NODE_NAME     U2D1 AK49
 '@BASEBOARD_FAB2_LIB.BASEBOARD_FAB2(SCH_1):PAGE71_I50@CHPSET_LIB.SKX_EXT_B(CHIPS)':
 'VCCIN'<256>: CDS_PINID='VCCIN(256)';
NODE_NAME     U2D1 AK47
 '@BASEBOARD_FAB2_LIB.BASEBOARD_FAB2(SCH_1):PAGE71_I50@CHPSET_LIB.SKX_EXT_B(CHIPS)':
 'VCCIN'<257>: CDS_PINID='VCCIN(257)';
NODE_NAME     U2D1 AK45
 '@BASEBOARD_FAB2_LIB.BASEBOARD_FAB2(SCH_1):PAGE71_I50@CHPSET_LIB.SKX_EXT_B(CHIPS)':
 'VCCIN'<258>: CDS_PINID='VCCIN(258)';
NODE_NAME     U2D1 AK35
 '@BASEBOARD_FAB2_LIB.BASEBOARD_FAB2(SCH_1):PAGE71_I50@CHPSET_LIB.SKX_EXT_B(CHIPS)':
 'VCCIN'<259>: CDS_PINID='VCCIN(259)';
NODE_NAME     U2D1 AJ36
 '@BASEBOARD_FAB2_LIB.BASEBOARD_FAB2(SCH_1):PAGE71_I50@CHPSET_LIB.SKX_EXT_B(CHIPS)':
 'VCCIN'<260>: CDS_PINID='VCCIN(260)';
NODE_NAME     U2D1 AH41
 '@BASEBOARD_FAB2_LIB.BASEBOARD_FAB2(SCH_1):PAGE71_I50@CHPSET_LIB.SKX_EXT_B(CHIPS)':
 'VCCIN'<261>: CDS_PINID='VCCIN(261)';
NODE_NAME     U2D1 AH39
 '@BASEBOARD_FAB2_LIB.BASEBOARD_FAB2(SCH_1):PAGE71_I50@CHPSET_LIB.SKX_EXT_B(CHIPS)':
 'VCCIN'<262>: CDS_PINID='VCCIN(262)';
NODE_NAME     U2D1 AH37
 '@BASEBOARD_FAB2_LIB.BASEBOARD_FAB2(SCH_1):PAGE71_I50@CHPSET_LIB.SKX_EXT_B(CHIPS)':
 'VCCIN'<263>: CDS_PINID='VCCIN(263)';
NODE_NAME     U2D1 AG42
 '@BASEBOARD_FAB2_LIB.BASEBOARD_FAB2(SCH_1):PAGE71_I50@CHPSET_LIB.SKX_EXT_B(CHIPS)':
 'VCCIN'<264>: CDS_PINID='VCCIN(264)';
NODE_NAME     U2D1 AG40
 '@BASEBOARD_FAB2_LIB.BASEBOARD_FAB2(SCH_1):PAGE71_I50@CHPSET_LIB.SKX_EXT_B(CHIPS)':
 'VCCIN'<265>: CDS_PINID='VCCIN(265)';
NODE_NAME     U2D1 AG38
 '@BASEBOARD_FAB2_LIB.BASEBOARD_FAB2(SCH_1):PAGE71_I50@CHPSET_LIB.SKX_EXT_B(CHIPS)':
 'VCCIN'<266>: CDS_PINID='VCCIN(266)';
NODE_NAME     U2D1 AF43
 '@BASEBOARD_FAB2_LIB.BASEBOARD_FAB2(SCH_1):PAGE71_I50@CHPSET_LIB.SKX_EXT_B(CHIPS)':
 'VCCIN'<267>: CDS_PINID='VCCIN(267)';
NODE_NAME     U2D1 CY49
 '@BASEBOARD_FAB2_LIB.BASEBOARD_FAB2(SCH_1):PAGE71_I51@CHPSET_LIB.SKX_EXT_B(CHIPS)':
 'VCCIN'<0>: CDS_PINID='VCCIN(0)';
NODE_NAME     U2D1 CY47
 '@BASEBOARD_FAB2_LIB.BASEBOARD_FAB2(SCH_1):PAGE71_I51@CHPSET_LIB.SKX_EXT_B(CHIPS)':
 'VCCIN'<1>: CDS_PINID='VCCIN(1)';
NODE_NAME     U2D1 CW50
 '@BASEBOARD_FAB2_LIB.BASEBOARD_FAB2(SCH_1):PAGE71_I51@CHPSET_LIB.SKX_EXT_B(CHIPS)':
 'VCCIN'<2>: CDS_PINID='VCCIN(2)';
NODE_NAME     U2D1 CW48
 '@BASEBOARD_FAB2_LIB.BASEBOARD_FAB2(SCH_1):PAGE71_I51@CHPSET_LIB.SKX_EXT_B(CHIPS)':
 'VCCIN'<3>: CDS_PINID='VCCIN(3)';
NODE_NAME     U2D1 CW46
 '@BASEBOARD_FAB2_LIB.BASEBOARD_FAB2(SCH_1):PAGE71_I51@CHPSET_LIB.SKX_EXT_B(CHIPS)':
 'VCCIN'<4>: CDS_PINID='VCCIN(4)';
NODE_NAME     U2D1 CV51
 '@BASEBOARD_FAB2_LIB.BASEBOARD_FAB2(SCH_1):PAGE71_I51@CHPSET_LIB.SKX_EXT_B(CHIPS)':
 'VCCIN'<5>: CDS_PINID='VCCIN(5)';
NODE_NAME     U2D1 CU54
 '@BASEBOARD_FAB2_LIB.BASEBOARD_FAB2(SCH_1):PAGE71_I51@CHPSET_LIB.SKX_EXT_B(CHIPS)':
 'VCCIN'<6>: CDS_PINID='VCCIN(6)';
NODE_NAME     U2D1 CU52
 '@BASEBOARD_FAB2_LIB.BASEBOARD_FAB2(SCH_1):PAGE71_I51@CHPSET_LIB.SKX_EXT_B(CHIPS)':
 'VCCIN'<7>: CDS_PINID='VCCIN(7)';
NODE_NAME     U2D1 CU42
 '@BASEBOARD_FAB2_LIB.BASEBOARD_FAB2(SCH_1):PAGE71_I51@CHPSET_LIB.SKX_EXT_B(CHIPS)':
 'VCCIN'<8>: CDS_PINID='VCCIN(8)';
NODE_NAME     U2D1 CU40
 '@BASEBOARD_FAB2_LIB.BASEBOARD_FAB2(SCH_1):PAGE71_I51@CHPSET_LIB.SKX_EXT_B(CHIPS)':
 'VCCIN'<9>: CDS_PINID='VCCIN(9)';
NODE_NAME     U2D1 CU38
 '@BASEBOARD_FAB2_LIB.BASEBOARD_FAB2(SCH_1):PAGE71_I51@CHPSET_LIB.SKX_EXT_B(CHIPS)':
 'VCCIN'<10>: CDS_PINID='VCCIN(10)';
NODE_NAME     U2D1 CT55
 '@BASEBOARD_FAB2_LIB.BASEBOARD_FAB2(SCH_1):PAGE71_I51@CHPSET_LIB.SKX_EXT_B(CHIPS)':
 'VCCIN'<11>: CDS_PINID='VCCIN(11)';
NODE_NAME     U2D1 CT53
 '@BASEBOARD_FAB2_LIB.BASEBOARD_FAB2(SCH_1):PAGE71_I51@CHPSET_LIB.SKX_EXT_B(CHIPS)':
 'VCCIN'<12>: CDS_PINID='VCCIN(12)';
NODE_NAME     U2D1 CT41
 '@BASEBOARD_FAB2_LIB.BASEBOARD_FAB2(SCH_1):PAGE71_I51@CHPSET_LIB.SKX_EXT_B(CHIPS)':
 'VCCIN'<13>: CDS_PINID='VCCIN(13)';
NODE_NAME     U2D1 CT39
 '@BASEBOARD_FAB2_LIB.BASEBOARD_FAB2(SCH_1):PAGE71_I51@CHPSET_LIB.SKX_EXT_B(CHIPS)':
 'VCCIN'<14>: CDS_PINID='VCCIN(14)';
NODE_NAME     U2D1 CT37
 '@BASEBOARD_FAB2_LIB.BASEBOARD_FAB2(SCH_1):PAGE71_I51@CHPSET_LIB.SKX_EXT_B(CHIPS)':
 'VCCIN'<15>: CDS_PINID='VCCIN(15)';
NODE_NAME     U2D1 CR56
 '@BASEBOARD_FAB2_LIB.BASEBOARD_FAB2(SCH_1):PAGE71_I51@CHPSET_LIB.SKX_EXT_B(CHIPS)':
 'VCCIN'<16>: CDS_PINID='VCCIN(16)';
NODE_NAME     U2D1 CR54
 '@BASEBOARD_FAB2_LIB.BASEBOARD_FAB2(SCH_1):PAGE71_I51@CHPSET_LIB.SKX_EXT_B(CHIPS)':
 'VCCIN'<17>: CDS_PINID='VCCIN(17)';
NODE_NAME     U2D1 CR34
 '@BASEBOARD_FAB2_LIB.BASEBOARD_FAB2(SCH_1):PAGE71_I51@CHPSET_LIB.SKX_EXT_B(CHIPS)':
 'VCCIN'<18>: CDS_PINID='VCCIN(18)';
NODE_NAME     U2D1 CP57
 '@BASEBOARD_FAB2_LIB.BASEBOARD_FAB2(SCH_1):PAGE71_I51@CHPSET_LIB.SKX_EXT_B(CHIPS)':
 'VCCIN'<19>: CDS_PINID='VCCIN(19)';
NODE_NAME     U2D1 CP55
 '@BASEBOARD_FAB2_LIB.BASEBOARD_FAB2(SCH_1):PAGE71_I51@CHPSET_LIB.SKX_EXT_B(CHIPS)':
 'VCCIN'<20>: CDS_PINID='VCCIN(20)';
NODE_NAME     U2D1 CP33
 '@BASEBOARD_FAB2_LIB.BASEBOARD_FAB2(SCH_1):PAGE71_I51@CHPSET_LIB.SKX_EXT_B(CHIPS)':
 'VCCIN'<21>: CDS_PINID='VCCIN(21)';
NODE_NAME     U2D1 CN58
 '@BASEBOARD_FAB2_LIB.BASEBOARD_FAB2(SCH_1):PAGE71_I51@CHPSET_LIB.SKX_EXT_B(CHIPS)':
 'VCCIN'<22>: CDS_PINID='VCCIN(22)';
NODE_NAME     U2D1 CN56
 '@BASEBOARD_FAB2_LIB.BASEBOARD_FAB2(SCH_1):PAGE71_I51@CHPSET_LIB.SKX_EXT_B(CHIPS)':
 'VCCIN'<23>: CDS_PINID='VCCIN(23)';
NODE_NAME     U2D1 CM59
 '@BASEBOARD_FAB2_LIB.BASEBOARD_FAB2(SCH_1):PAGE71_I51@CHPSET_LIB.SKX_EXT_B(CHIPS)':
 'VCCIN'<24>: CDS_PINID='VCCIN(24)';
NODE_NAME     U2D1 CM57
 '@BASEBOARD_FAB2_LIB.BASEBOARD_FAB2(SCH_1):PAGE71_I51@CHPSET_LIB.SKX_EXT_B(CHIPS)':
 'VCCIN'<25>: CDS_PINID='VCCIN(25)';
NODE_NAME     U2D1 CL60
 '@BASEBOARD_FAB2_LIB.BASEBOARD_FAB2(SCH_1):PAGE71_I51@CHPSET_LIB.SKX_EXT_B(CHIPS)':
 'VCCIN'<26>: CDS_PINID='VCCIN(26)';
NODE_NAME     U2D1 CL58
 '@BASEBOARD_FAB2_LIB.BASEBOARD_FAB2(SCH_1):PAGE71_I51@CHPSET_LIB.SKX_EXT_B(CHIPS)':
 'VCCIN'<27>: CDS_PINID='VCCIN(27)';
NODE_NAME     U2D1 CK61
 '@BASEBOARD_FAB2_LIB.BASEBOARD_FAB2(SCH_1):PAGE71_I51@CHPSET_LIB.SKX_EXT_B(CHIPS)':
 'VCCIN'<28>: CDS_PINID='VCCIN(28)';
NODE_NAME     U2D1 CK59
 '@BASEBOARD_FAB2_LIB.BASEBOARD_FAB2(SCH_1):PAGE71_I51@CHPSET_LIB.SKX_EXT_B(CHIPS)':
 'VCCIN'<29>: CDS_PINID='VCCIN(29)';
NODE_NAME     U2D1 CJ60
 '@BASEBOARD_FAB2_LIB.BASEBOARD_FAB2(SCH_1):PAGE71_I51@CHPSET_LIB.SKX_EXT_B(CHIPS)':
 'VCCIN'<30>: CDS_PINID='VCCIN(30)';
NODE_NAME     U2D1 CH85
 '@BASEBOARD_FAB2_LIB.BASEBOARD_FAB2(SCH_1):PAGE71_I51@CHPSET_LIB.SKX_EXT_B(CHIPS)':
 'VCCIN'<31>: CDS_PINID='VCCIN(31)';
NODE_NAME     U2D1 CH61
 '@BASEBOARD_FAB2_LIB.BASEBOARD_FAB2(SCH_1):PAGE71_I51@CHPSET_LIB.SKX_EXT_B(CHIPS)':
 'VCCIN'<32>: CDS_PINID='VCCIN(32)';
NODE_NAME     U2D1 CG84
 '@BASEBOARD_FAB2_LIB.BASEBOARD_FAB2(SCH_1):PAGE71_I51@CHPSET_LIB.SKX_EXT_B(CHIPS)':
 'VCCIN'<33>: CDS_PINID='VCCIN(33)';
NODE_NAME     U2D1 CG60
 '@BASEBOARD_FAB2_LIB.BASEBOARD_FAB2(SCH_1):PAGE71_I51@CHPSET_LIB.SKX_EXT_B(CHIPS)':
 'VCCIN'<34>: CDS_PINID='VCCIN(34)';
NODE_NAME     U2D1 CF85
 '@BASEBOARD_FAB2_LIB.BASEBOARD_FAB2(SCH_1):PAGE71_I51@CHPSET_LIB.SKX_EXT_B(CHIPS)':
 'VCCIN'<35>: CDS_PINID='VCCIN(35)';
NODE_NAME     U2D1 CF61
 '@BASEBOARD_FAB2_LIB.BASEBOARD_FAB2(SCH_1):PAGE71_I51@CHPSET_LIB.SKX_EXT_B(CHIPS)':
 'VCCIN'<36>: CDS_PINID='VCCIN(36)';
NODE_NAME     U2D1 CE84
 '@BASEBOARD_FAB2_LIB.BASEBOARD_FAB2(SCH_1):PAGE71_I51@CHPSET_LIB.SKX_EXT_B(CHIPS)':
 'VCCIN'<37>: CDS_PINID='VCCIN(37)';
NODE_NAME     U2D1 CE60
 '@BASEBOARD_FAB2_LIB.BASEBOARD_FAB2(SCH_1):PAGE71_I51@CHPSET_LIB.SKX_EXT_B(CHIPS)':
 'VCCIN'<38>: CDS_PINID='VCCIN(38)';
NODE_NAME     U2D1 CD85
 '@BASEBOARD_FAB2_LIB.BASEBOARD_FAB2(SCH_1):PAGE71_I51@CHPSET_LIB.SKX_EXT_B(CHIPS)':
 'VCCIN'<39>: CDS_PINID='VCCIN(39)';
NODE_NAME     U2D1 CD83
 '@BASEBOARD_FAB2_LIB.BASEBOARD_FAB2(SCH_1):PAGE71_I51@CHPSET_LIB.SKX_EXT_B(CHIPS)':
 'VCCIN'<40>: CDS_PINID='VCCIN(40)';
NODE_NAME     U2D1 CD61
 '@BASEBOARD_FAB2_LIB.BASEBOARD_FAB2(SCH_1):PAGE71_I51@CHPSET_LIB.SKX_EXT_B(CHIPS)':
 'VCCIN'<41>: CDS_PINID='VCCIN(41)';
NODE_NAME     U2D1 CC84
 '@BASEBOARD_FAB2_LIB.BASEBOARD_FAB2(SCH_1):PAGE71_I51@CHPSET_LIB.SKX_EXT_B(CHIPS)':
 'VCCIN'<42>: CDS_PINID='VCCIN(42)';
NODE_NAME     U2D1 CC62
 '@BASEBOARD_FAB2_LIB.BASEBOARD_FAB2(SCH_1):PAGE71_I51@CHPSET_LIB.SKX_EXT_B(CHIPS)':
 'VCCIN'<43>: CDS_PINID='VCCIN(43)';
NODE_NAME     U2D1 CC60
 '@BASEBOARD_FAB2_LIB.BASEBOARD_FAB2(SCH_1):PAGE71_I51@CHPSET_LIB.SKX_EXT_B(CHIPS)':
 'VCCIN'<44>: CDS_PINID='VCCIN(44)';
NODE_NAME     U2D1 CB83
 '@BASEBOARD_FAB2_LIB.BASEBOARD_FAB2(SCH_1):PAGE71_I51@CHPSET_LIB.SKX_EXT_B(CHIPS)':
 'VCCIN'<45>: CDS_PINID='VCCIN(45)';
NODE_NAME     U2D1 CB81
 '@BASEBOARD_FAB2_LIB.BASEBOARD_FAB2(SCH_1):PAGE71_I51@CHPSET_LIB.SKX_EXT_B(CHIPS)':
 'VCCIN'<46>: CDS_PINID='VCCIN(46)';
NODE_NAME     U2D1 CB79
 '@BASEBOARD_FAB2_LIB.BASEBOARD_FAB2(SCH_1):PAGE71_I51@CHPSET_LIB.SKX_EXT_B(CHIPS)':
 'VCCIN'<47>: CDS_PINID='VCCIN(47)';
NODE_NAME     U2D1 CB77
 '@BASEBOARD_FAB2_LIB.BASEBOARD_FAB2(SCH_1):PAGE71_I51@CHPSET_LIB.SKX_EXT_B(CHIPS)':
 'VCCIN'<48>: CDS_PINID='VCCIN(48)';
NODE_NAME     U2D1 CB75
 '@BASEBOARD_FAB2_LIB.BASEBOARD_FAB2(SCH_1):PAGE71_I51@CHPSET_LIB.SKX_EXT_B(CHIPS)':
 'VCCIN'<49>: CDS_PINID='VCCIN(49)';
NODE_NAME     U2D1 CB73
 '@BASEBOARD_FAB2_LIB.BASEBOARD_FAB2(SCH_1):PAGE71_I51@CHPSET_LIB.SKX_EXT_B(CHIPS)':
 'VCCIN'<50>: CDS_PINID='VCCIN(50)';
NODE_NAME     U2D1 CB61
 '@BASEBOARD_FAB2_LIB.BASEBOARD_FAB2(SCH_1):PAGE71_I51@CHPSET_LIB.SKX_EXT_B(CHIPS)':
 'VCCIN'<51>: CDS_PINID='VCCIN(51)';
NODE_NAME     U2D1 CA84
 '@BASEBOARD_FAB2_LIB.BASEBOARD_FAB2(SCH_1):PAGE71_I51@CHPSET_LIB.SKX_EXT_B(CHIPS)':
 'VCCIN'<52>: CDS_PINID='VCCIN(52)';
NODE_NAME     U2D1 CA82
 '@BASEBOARD_FAB2_LIB.BASEBOARD_FAB2(SCH_1):PAGE71_I51@CHPSET_LIB.SKX_EXT_B(CHIPS)':
 'VCCIN'<53>: CDS_PINID='VCCIN(53)';
NODE_NAME     U2D1 CA80
 '@BASEBOARD_FAB2_LIB.BASEBOARD_FAB2(SCH_1):PAGE71_I51@CHPSET_LIB.SKX_EXT_B(CHIPS)':
 'VCCIN'<54>: CDS_PINID='VCCIN(54)';
NODE_NAME     U2D1 CA78
 '@BASEBOARD_FAB2_LIB.BASEBOARD_FAB2(SCH_1):PAGE71_I51@CHPSET_LIB.SKX_EXT_B(CHIPS)':
 'VCCIN'<55>: CDS_PINID='VCCIN(55)';
NODE_NAME     U2D1 CA76
 '@BASEBOARD_FAB2_LIB.BASEBOARD_FAB2(SCH_1):PAGE71_I51@CHPSET_LIB.SKX_EXT_B(CHIPS)':
 'VCCIN'<56>: CDS_PINID='VCCIN(56)';
NODE_NAME     U2D1 CA74
 '@BASEBOARD_FAB2_LIB.BASEBOARD_FAB2(SCH_1):PAGE71_I51@CHPSET_LIB.SKX_EXT_B(CHIPS)':
 'VCCIN'<57>: CDS_PINID='VCCIN(57)';
NODE_NAME     U2D1 CA72
 '@BASEBOARD_FAB2_LIB.BASEBOARD_FAB2(SCH_1):PAGE71_I51@CHPSET_LIB.SKX_EXT_B(CHIPS)':
 'VCCIN'<58>: CDS_PINID='VCCIN(58)';
NODE_NAME     U2D1 CA62
 '@BASEBOARD_FAB2_LIB.BASEBOARD_FAB2(SCH_1):PAGE71_I51@CHPSET_LIB.SKX_EXT_B(CHIPS)':
 'VCCIN'<59>: CDS_PINID='VCCIN(59)';
NODE_NAME     U2D1 CA60
 '@BASEBOARD_FAB2_LIB.BASEBOARD_FAB2(SCH_1):PAGE71_I51@CHPSET_LIB.SKX_EXT_B(CHIPS)':
 'VCCIN'<60>: CDS_PINID='VCCIN(60)';
NODE_NAME     U2D1 BY83
 '@BASEBOARD_FAB2_LIB.BASEBOARD_FAB2(SCH_1):PAGE71_I51@CHPSET_LIB.SKX_EXT_B(CHIPS)':
 'VCCIN'<61>: CDS_PINID='VCCIN(61)';
NODE_NAME     U2D1 BY81
 '@BASEBOARD_FAB2_LIB.BASEBOARD_FAB2(SCH_1):PAGE71_I51@CHPSET_LIB.SKX_EXT_B(CHIPS)':
 'VCCIN'<62>: CDS_PINID='VCCIN(62)';
NODE_NAME     U2D1 BY79
 '@BASEBOARD_FAB2_LIB.BASEBOARD_FAB2(SCH_1):PAGE71_I51@CHPSET_LIB.SKX_EXT_B(CHIPS)':
 'VCCIN'<63>: CDS_PINID='VCCIN(63)';
NODE_NAME     U2D1 BY77
 '@BASEBOARD_FAB2_LIB.BASEBOARD_FAB2(SCH_1):PAGE71_I51@CHPSET_LIB.SKX_EXT_B(CHIPS)':
 'VCCIN'<64>: CDS_PINID='VCCIN(64)';
NODE_NAME     U2D1 BY75
 '@BASEBOARD_FAB2_LIB.BASEBOARD_FAB2(SCH_1):PAGE71_I51@CHPSET_LIB.SKX_EXT_B(CHIPS)':
 'VCCIN'<65>: CDS_PINID='VCCIN(65)';
NODE_NAME     U2D1 BY73
 '@BASEBOARD_FAB2_LIB.BASEBOARD_FAB2(SCH_1):PAGE71_I51@CHPSET_LIB.SKX_EXT_B(CHIPS)':
 'VCCIN'<66>: CDS_PINID='VCCIN(66)';
NODE_NAME     U2D1 BY61
 '@BASEBOARD_FAB2_LIB.BASEBOARD_FAB2(SCH_1):PAGE71_I51@CHPSET_LIB.SKX_EXT_B(CHIPS)':
 'VCCIN'<67>: CDS_PINID='VCCIN(67)';
NODE_NAME     U2D1 BW84
 '@BASEBOARD_FAB2_LIB.BASEBOARD_FAB2(SCH_1):PAGE71_I51@CHPSET_LIB.SKX_EXT_B(CHIPS)':
 'VCCIN'<68>: CDS_PINID='VCCIN(68)';
NODE_NAME     U2D1 BW70
 '@BASEBOARD_FAB2_LIB.BASEBOARD_FAB2(SCH_1):PAGE71_I51@CHPSET_LIB.SKX_EXT_B(CHIPS)':
 'VCCIN'<69>: CDS_PINID='VCCIN(69)';
NODE_NAME     U2D1 BW68
 '@BASEBOARD_FAB2_LIB.BASEBOARD_FAB2(SCH_1):PAGE71_I51@CHPSET_LIB.SKX_EXT_B(CHIPS)':
 'VCCIN'<70>: CDS_PINID='VCCIN(70)';
NODE_NAME     U2D1 BW66
 '@BASEBOARD_FAB2_LIB.BASEBOARD_FAB2(SCH_1):PAGE71_I51@CHPSET_LIB.SKX_EXT_B(CHIPS)':
 'VCCIN'<71>: CDS_PINID='VCCIN(71)';
NODE_NAME     U2D1 BW64
 '@BASEBOARD_FAB2_LIB.BASEBOARD_FAB2(SCH_1):PAGE71_I51@CHPSET_LIB.SKX_EXT_B(CHIPS)':
 'VCCIN'<72>: CDS_PINID='VCCIN(72)';
NODE_NAME     U2D1 BW62
 '@BASEBOARD_FAB2_LIB.BASEBOARD_FAB2(SCH_1):PAGE71_I51@CHPSET_LIB.SKX_EXT_B(CHIPS)':
 'VCCIN'<73>: CDS_PINID='VCCIN(73)';
NODE_NAME     U2D1 BW60
 '@BASEBOARD_FAB2_LIB.BASEBOARD_FAB2(SCH_1):PAGE71_I51@CHPSET_LIB.SKX_EXT_B(CHIPS)':
 'VCCIN'<74>: CDS_PINID='VCCIN(74)';
NODE_NAME     U2D1 BV83
 '@BASEBOARD_FAB2_LIB.BASEBOARD_FAB2(SCH_1):PAGE71_I51@CHPSET_LIB.SKX_EXT_B(CHIPS)':
 'VCCIN'<75>: CDS_PINID='VCCIN(75)';
NODE_NAME     U2D1 BV81
 '@BASEBOARD_FAB2_LIB.BASEBOARD_FAB2(SCH_1):PAGE71_I51@CHPSET_LIB.SKX_EXT_B(CHIPS)':
 'VCCIN'<76>: CDS_PINID='VCCIN(76)';
NODE_NAME     U2D1 BV79
 '@BASEBOARD_FAB2_LIB.BASEBOARD_FAB2(SCH_1):PAGE71_I51@CHPSET_LIB.SKX_EXT_B(CHIPS)':
 'VCCIN'<77>: CDS_PINID='VCCIN(77)';
NODE_NAME     U2D1 BV77
 '@BASEBOARD_FAB2_LIB.BASEBOARD_FAB2(SCH_1):PAGE71_I51@CHPSET_LIB.SKX_EXT_B(CHIPS)':
 'VCCIN'<78>: CDS_PINID='VCCIN(78)';
NODE_NAME     U2D1 BV75
 '@BASEBOARD_FAB2_LIB.BASEBOARD_FAB2(SCH_1):PAGE71_I51@CHPSET_LIB.SKX_EXT_B(CHIPS)':
 'VCCIN'<79>: CDS_PINID='VCCIN(79)';
NODE_NAME     U2D1 BV73
 '@BASEBOARD_FAB2_LIB.BASEBOARD_FAB2(SCH_1):PAGE71_I51@CHPSET_LIB.SKX_EXT_B(CHIPS)':
 'VCCIN'<80>: CDS_PINID='VCCIN(80)';
NODE_NAME     U2D1 BV71
 '@BASEBOARD_FAB2_LIB.BASEBOARD_FAB2(SCH_1):PAGE71_I51@CHPSET_LIB.SKX_EXT_B(CHIPS)':
 'VCCIN'<81>: CDS_PINID='VCCIN(81)';
NODE_NAME     U2D1 BV69
 '@BASEBOARD_FAB2_LIB.BASEBOARD_FAB2(SCH_1):PAGE71_I51@CHPSET_LIB.SKX_EXT_B(CHIPS)':
 'VCCIN'<82>: CDS_PINID='VCCIN(82)';
NODE_NAME     U2D1 BV67
 '@BASEBOARD_FAB2_LIB.BASEBOARD_FAB2(SCH_1):PAGE71_I51@CHPSET_LIB.SKX_EXT_B(CHIPS)':
 'VCCIN'<83>: CDS_PINID='VCCIN(83)';
NODE_NAME     U2D1 BV65
 '@BASEBOARD_FAB2_LIB.BASEBOARD_FAB2(SCH_1):PAGE71_I51@CHPSET_LIB.SKX_EXT_B(CHIPS)':
 'VCCIN'<84>: CDS_PINID='VCCIN(84)';
NODE_NAME     U2D1 BV63
 '@BASEBOARD_FAB2_LIB.BASEBOARD_FAB2(SCH_1):PAGE71_I51@CHPSET_LIB.SKX_EXT_B(CHIPS)':
 'VCCIN'<85>: CDS_PINID='VCCIN(85)';
NODE_NAME     U2D1 BV61
 '@BASEBOARD_FAB2_LIB.BASEBOARD_FAB2(SCH_1):PAGE71_I51@CHPSET_LIB.SKX_EXT_B(CHIPS)':
 'VCCIN'<86>: CDS_PINID='VCCIN(86)';
NODE_NAME     U2D1 BU84
 '@BASEBOARD_FAB2_LIB.BASEBOARD_FAB2(SCH_1):PAGE71_I51@CHPSET_LIB.SKX_EXT_B(CHIPS)':
 'VCCIN'<87>: CDS_PINID='VCCIN(87)';
NODE_NAME     U2D1 BU82
 '@BASEBOARD_FAB2_LIB.BASEBOARD_FAB2(SCH_1):PAGE71_I51@CHPSET_LIB.SKX_EXT_B(CHIPS)':
 'VCCIN'<88>: CDS_PINID='VCCIN(88)';
NODE_NAME     U2D1 BU80
 '@BASEBOARD_FAB2_LIB.BASEBOARD_FAB2(SCH_1):PAGE71_I51@CHPSET_LIB.SKX_EXT_B(CHIPS)':
 'VCCIN'<89>: CDS_PINID='VCCIN(89)';
NODE_NAME     U2D1 BU78
 '@BASEBOARD_FAB2_LIB.BASEBOARD_FAB2(SCH_1):PAGE71_I51@CHPSET_LIB.SKX_EXT_B(CHIPS)':
 'VCCIN'<90>: CDS_PINID='VCCIN(90)';
NODE_NAME     U2D1 BU76
 '@BASEBOARD_FAB2_LIB.BASEBOARD_FAB2(SCH_1):PAGE71_I51@CHPSET_LIB.SKX_EXT_B(CHIPS)':
 'VCCIN'<91>: CDS_PINID='VCCIN(91)';
NODE_NAME     U2D1 BU74
 '@BASEBOARD_FAB2_LIB.BASEBOARD_FAB2(SCH_1):PAGE71_I51@CHPSET_LIB.SKX_EXT_B(CHIPS)':
 'VCCIN'<92>: CDS_PINID='VCCIN(92)';
NODE_NAME     U2D1 BU72
 '@BASEBOARD_FAB2_LIB.BASEBOARD_FAB2(SCH_1):PAGE71_I51@CHPSET_LIB.SKX_EXT_B(CHIPS)':
 'VCCIN'<93>: CDS_PINID='VCCIN(93)';
NODE_NAME     U2D1 BU70
 '@BASEBOARD_FAB2_LIB.BASEBOARD_FAB2(SCH_1):PAGE71_I51@CHPSET_LIB.SKX_EXT_B(CHIPS)':
 'VCCIN'<94>: CDS_PINID='VCCIN(94)';
NODE_NAME     U2D1 BU68
 '@BASEBOARD_FAB2_LIB.BASEBOARD_FAB2(SCH_1):PAGE71_I51@CHPSET_LIB.SKX_EXT_B(CHIPS)':
 'VCCIN'<95>: CDS_PINID='VCCIN(95)';
NODE_NAME     U2D1 BU66
 '@BASEBOARD_FAB2_LIB.BASEBOARD_FAB2(SCH_1):PAGE71_I51@CHPSET_LIB.SKX_EXT_B(CHIPS)':
 'VCCIN'<96>: CDS_PINID='VCCIN(96)';
NODE_NAME     U2D1 BU64
 '@BASEBOARD_FAB2_LIB.BASEBOARD_FAB2(SCH_1):PAGE71_I51@CHPSET_LIB.SKX_EXT_B(CHIPS)':
 'VCCIN'<97>: CDS_PINID='VCCIN(97)';
NODE_NAME     U2D1 BU62
 '@BASEBOARD_FAB2_LIB.BASEBOARD_FAB2(SCH_1):PAGE71_I51@CHPSET_LIB.SKX_EXT_B(CHIPS)':
 'VCCIN'<98>: CDS_PINID='VCCIN(98)';
NODE_NAME     U2D1 BU60
 '@BASEBOARD_FAB2_LIB.BASEBOARD_FAB2(SCH_1):PAGE71_I51@CHPSET_LIB.SKX_EXT_B(CHIPS)':
 'VCCIN'<99>: CDS_PINID='VCCIN(99)';
NODE_NAME     U2D1 BT83
 '@BASEBOARD_FAB2_LIB.BASEBOARD_FAB2(SCH_1):PAGE71_I51@CHPSET_LIB.SKX_EXT_B(CHIPS)':
 'VCCIN'<100>: CDS_PINID='VCCIN(100)';
NODE_NAME     U2D1 BT81
 '@BASEBOARD_FAB2_LIB.BASEBOARD_FAB2(SCH_1):PAGE71_I51@CHPSET_LIB.SKX_EXT_B(CHIPS)':
 'VCCIN'<101>: CDS_PINID='VCCIN(101)';
NODE_NAME     U2D1 BT79
 '@BASEBOARD_FAB2_LIB.BASEBOARD_FAB2(SCH_1):PAGE71_I51@CHPSET_LIB.SKX_EXT_B(CHIPS)':
 'VCCIN'<102>: CDS_PINID='VCCIN(102)';
NODE_NAME     U2D1 BT77
 '@BASEBOARD_FAB2_LIB.BASEBOARD_FAB2(SCH_1):PAGE71_I51@CHPSET_LIB.SKX_EXT_B(CHIPS)':
 'VCCIN'<103>: CDS_PINID='VCCIN(103)';
NODE_NAME     U2D1 BT75
 '@BASEBOARD_FAB2_LIB.BASEBOARD_FAB2(SCH_1):PAGE71_I51@CHPSET_LIB.SKX_EXT_B(CHIPS)':
 'VCCIN'<104>: CDS_PINID='VCCIN(104)';
NODE_NAME     U2D1 BT73
 '@BASEBOARD_FAB2_LIB.BASEBOARD_FAB2(SCH_1):PAGE71_I51@CHPSET_LIB.SKX_EXT_B(CHIPS)':
 'VCCIN'<105>: CDS_PINID='VCCIN(105)';
NODE_NAME     U2D1 BT71
 '@BASEBOARD_FAB2_LIB.BASEBOARD_FAB2(SCH_1):PAGE71_I51@CHPSET_LIB.SKX_EXT_B(CHIPS)':
 'VCCIN'<106>: CDS_PINID='VCCIN(106)';
NODE_NAME     U2D1 BT69
 '@BASEBOARD_FAB2_LIB.BASEBOARD_FAB2(SCH_1):PAGE71_I51@CHPSET_LIB.SKX_EXT_B(CHIPS)':
 'VCCIN'<107>: CDS_PINID='VCCIN(107)';
NODE_NAME     U2D1 BT67
 '@BASEBOARD_FAB2_LIB.BASEBOARD_FAB2(SCH_1):PAGE71_I51@CHPSET_LIB.SKX_EXT_B(CHIPS)':
 'VCCIN'<108>: CDS_PINID='VCCIN(108)';
NODE_NAME     U2D1 BT65
 '@BASEBOARD_FAB2_LIB.BASEBOARD_FAB2(SCH_1):PAGE71_I51@CHPSET_LIB.SKX_EXT_B(CHIPS)':
 'VCCIN'<109>: CDS_PINID='VCCIN(109)';
NODE_NAME     U2D1 BT63
 '@BASEBOARD_FAB2_LIB.BASEBOARD_FAB2(SCH_1):PAGE71_I51@CHPSET_LIB.SKX_EXT_B(CHIPS)':
 'VCCIN'<110>: CDS_PINID='VCCIN(110)';
NODE_NAME     U2D1 BT61
 '@BASEBOARD_FAB2_LIB.BASEBOARD_FAB2(SCH_1):PAGE71_I51@CHPSET_LIB.SKX_EXT_B(CHIPS)':
 'VCCIN'<111>: CDS_PINID='VCCIN(111)';
NODE_NAME     U2D1 BR84
 '@BASEBOARD_FAB2_LIB.BASEBOARD_FAB2(SCH_1):PAGE71_I51@CHPSET_LIB.SKX_EXT_B(CHIPS)':
 'VCCIN'<112>: CDS_PINID='VCCIN(112)';
NODE_NAME     U2D1 BR62
 '@BASEBOARD_FAB2_LIB.BASEBOARD_FAB2(SCH_1):PAGE71_I51@CHPSET_LIB.SKX_EXT_B(CHIPS)':
 'VCCIN'<113>: CDS_PINID='VCCIN(113)';
NODE_NAME     U2D1 BR60
 '@BASEBOARD_FAB2_LIB.BASEBOARD_FAB2(SCH_1):PAGE71_I51@CHPSET_LIB.SKX_EXT_B(CHIPS)':
 'VCCIN'<114>: CDS_PINID='VCCIN(114)';
NODE_NAME     U2D1 BP83
 '@BASEBOARD_FAB2_LIB.BASEBOARD_FAB2(SCH_1):PAGE71_I51@CHPSET_LIB.SKX_EXT_B(CHIPS)':
 'VCCIN'<115>: CDS_PINID='VCCIN(115)';
NODE_NAME     U2D1 BP81
 '@BASEBOARD_FAB2_LIB.BASEBOARD_FAB2(SCH_1):PAGE71_I51@CHPSET_LIB.SKX_EXT_B(CHIPS)':
 'VCCIN'<116>: CDS_PINID='VCCIN(116)';
NODE_NAME     U2D1 BP79
 '@BASEBOARD_FAB2_LIB.BASEBOARD_FAB2(SCH_1):PAGE71_I51@CHPSET_LIB.SKX_EXT_B(CHIPS)':
 'VCCIN'<117>: CDS_PINID='VCCIN(117)';
NODE_NAME     U2D1 BP77
 '@BASEBOARD_FAB2_LIB.BASEBOARD_FAB2(SCH_1):PAGE71_I51@CHPSET_LIB.SKX_EXT_B(CHIPS)':
 'VCCIN'<118>: CDS_PINID='VCCIN(118)';
NODE_NAME     U2D1 BP75
 '@BASEBOARD_FAB2_LIB.BASEBOARD_FAB2(SCH_1):PAGE71_I51@CHPSET_LIB.SKX_EXT_B(CHIPS)':
 'VCCIN'<119>: CDS_PINID='VCCIN(119)';
NODE_NAME     U2D1 BP73
 '@BASEBOARD_FAB2_LIB.BASEBOARD_FAB2(SCH_1):PAGE71_I51@CHPSET_LIB.SKX_EXT_B(CHIPS)':
 'VCCIN'<120>: CDS_PINID='VCCIN(120)';
NODE_NAME     U2D1 BP71
 '@BASEBOARD_FAB2_LIB.BASEBOARD_FAB2(SCH_1):PAGE71_I51@CHPSET_LIB.SKX_EXT_B(CHIPS)':
 'VCCIN'<121>: CDS_PINID='VCCIN(121)';
NODE_NAME     U2D1 BP69
 '@BASEBOARD_FAB2_LIB.BASEBOARD_FAB2(SCH_1):PAGE71_I51@CHPSET_LIB.SKX_EXT_B(CHIPS)':
 'VCCIN'<122>: CDS_PINID='VCCIN(122)';
NODE_NAME     U2D1 BP67
 '@BASEBOARD_FAB2_LIB.BASEBOARD_FAB2(SCH_1):PAGE71_I51@CHPSET_LIB.SKX_EXT_B(CHIPS)':
 'VCCIN'<123>: CDS_PINID='VCCIN(123)';
NODE_NAME     U2D1 BP65
 '@BASEBOARD_FAB2_LIB.BASEBOARD_FAB2(SCH_1):PAGE71_I51@CHPSET_LIB.SKX_EXT_B(CHIPS)':
 'VCCIN'<124>: CDS_PINID='VCCIN(124)';
NODE_NAME     U2D1 BP63
 '@BASEBOARD_FAB2_LIB.BASEBOARD_FAB2(SCH_1):PAGE71_I51@CHPSET_LIB.SKX_EXT_B(CHIPS)':
 'VCCIN'<125>: CDS_PINID='VCCIN(125)';
NODE_NAME     U2D1 BP61
 '@BASEBOARD_FAB2_LIB.BASEBOARD_FAB2(SCH_1):PAGE71_I51@CHPSET_LIB.SKX_EXT_B(CHIPS)':
 'VCCIN'<126>: CDS_PINID='VCCIN(126)';
NODE_NAME     U2D1 BN84
 '@BASEBOARD_FAB2_LIB.BASEBOARD_FAB2(SCH_1):PAGE71_I51@CHPSET_LIB.SKX_EXT_B(CHIPS)':
 'VCCIN'<127>: CDS_PINID='VCCIN(127)';
NODE_NAME     U2D1 BN82
 '@BASEBOARD_FAB2_LIB.BASEBOARD_FAB2(SCH_1):PAGE71_I51@CHPSET_LIB.SKX_EXT_B(CHIPS)':
 'VCCIN'<128>: CDS_PINID='VCCIN(128)';
NODE_NAME     U2D1 BN80
 '@BASEBOARD_FAB2_LIB.BASEBOARD_FAB2(SCH_1):PAGE71_I51@CHPSET_LIB.SKX_EXT_B(CHIPS)':
 'VCCIN'<129>: CDS_PINID='VCCIN(129)';
NODE_NAME     C2D12 1
 '@BASEBOARD_FAB2_LIB.BASEBOARD_FAB2(SCH_1):PAGE76_I59@DEV_DISCRETE.CAP_A(CHIPS)':
 'A': CDS_PINID='A';
NODE_NAME     C2D22 1
 '@BASEBOARD_FAB2_LIB.BASEBOARD_FAB2(SCH_1):PAGE76_I61@DEV_DISCRETE.CAP_A(CHIPS)':
 'A': CDS_PINID='A';
NODE_NAME     C2D31 1
 '@BASEBOARD_FAB2_LIB.BASEBOARD_FAB2(SCH_1):PAGE76_I63@DEV_DISCRETE.CAP_A(CHIPS)':
 'A': CDS_PINID='A';
NODE_NAME     C2D21 1
 '@BASEBOARD_FAB2_LIB.BASEBOARD_FAB2(SCH_1):PAGE76_I65@DEV_DISCRETE.CAP_A(CHIPS)':
 'A': CDS_PINID='A';
NODE_NAME     C2D27 1
 '@BASEBOARD_FAB2_LIB.BASEBOARD_FAB2(SCH_1):PAGE76_I66@DEV_DISCRETE.CAP_A(CHIPS)':
 'A': CDS_PINID='A';
NODE_NAME     C3D2 1
 '@BASEBOARD_FAB2_LIB.BASEBOARD_FAB2(SCH_1):PAGE76_I69@DEV_DISCRETE.CAP_A(CHIPS)':
 'A': CDS_PINID='A';
NODE_NAME     C2D36 1
 '@BASEBOARD_FAB2_LIB.BASEBOARD_FAB2(SCH_1):PAGE76_I70@DEV_DISCRETE.CAP_A(CHIPS)':
 'A': CDS_PINID='A';
NODE_NAME     C2D13 1
 '@BASEBOARD_FAB2_LIB.BASEBOARD_FAB2(SCH_1):PAGE76_I73@DEV_DISCRETE.CAP_A(CHIPS)':
 'A': CDS_PINID='A';
NODE_NAME     C2D19 1
 '@BASEBOARD_FAB2_LIB.BASEBOARD_FAB2(SCH_1):PAGE76_I75@DEV_DISCRETE.CAP_A(CHIPS)':
 'A': CDS_PINID='A';
NODE_NAME     C2D14 1
 '@BASEBOARD_FAB2_LIB.BASEBOARD_FAB2(SCH_1):PAGE76_I76@DEV_DISCRETE.CAP_A(CHIPS)':
 'A': CDS_PINID='A';
NODE_NAME     C2D20 1
 '@BASEBOARD_FAB2_LIB.BASEBOARD_FAB2(SCH_1):PAGE76_I79@DEV_DISCRETE.CAP_A(CHIPS)':
 'A': CDS_PINID='A';
NODE_NAME     C2D24 1
 '@BASEBOARD_FAB2_LIB.BASEBOARD_FAB2(SCH_1):PAGE76_I80@DEV_DISCRETE.CAP_A(CHIPS)':
 'A': CDS_PINID='A';
NODE_NAME     C2D25 1
 '@BASEBOARD_FAB2_LIB.BASEBOARD_FAB2(SCH_1):PAGE76_I82@DEV_DISCRETE.CAP_A(CHIPS)':
 'A': CDS_PINID='A';
NODE_NAME     C2D30 1
 '@BASEBOARD_FAB2_LIB.BASEBOARD_FAB2(SCH_1):PAGE76_I83@DEV_DISCRETE.CAP_A(CHIPS)':
 'A': CDS_PINID='A';
NODE_NAME     C2D33 1
 '@BASEBOARD_FAB2_LIB.BASEBOARD_FAB2(SCH_1):PAGE76_I85@DEV_DISCRETE.CAP_A(CHIPS)':
 'A': CDS_PINID='A';
NODE_NAME     C8P20 1
 '@BASEBOARD_FAB2_LIB.BASEBOARD_FAB2(SCH_1):PAGE76_I89@MSTR_DISCRETE.CAP(CHIPS)':
 'A': CDS_PINID='A';
NODE_NAME     C2D32 1
 '@BASEBOARD_FAB2_LIB.BASEBOARD_FAB2(SCH_1):PAGE76_I90@DEV_DISCRETE.CAP_A(CHIPS)':
 'A': CDS_PINID='A';
NODE_NAME     C8P18 1
 '@BASEBOARD_FAB2_LIB.BASEBOARD_FAB2(SCH_1):PAGE76_I92@MSTR_DISCRETE.CAP(CHIPS)':
 'A': CDS_PINID='A';
NODE_NAME     C8P19 1
 '@BASEBOARD_FAB2_LIB.BASEBOARD_FAB2(SCH_1):PAGE76_I103@MSTR_DISCRETE.CAP(CHIPS)':
 'A': CDS_PINID='A';
NODE_NAME     C8P12 1
 '@BASEBOARD_FAB2_LIB.BASEBOARD_FAB2(SCH_1):PAGE76_I107@MSTR_DISCRETE.CAP(CHIPS)':
 'A': CDS_PINID='A';
NODE_NAME     C2D26 1
 '@BASEBOARD_FAB2_LIB.BASEBOARD_FAB2(SCH_1):PAGE76_I108@DEV_DISCRETE.CAP_A(CHIPS)':
 'A': CDS_PINID='A';
NODE_NAME     C2D23 1
 '@BASEBOARD_FAB2_LIB.BASEBOARD_FAB2(SCH_1):PAGE76_I112@DEV_DISCRETE.CAP_A(CHIPS)':
 'A': CDS_PINID='A';
NODE_NAME     C2D17 1
 '@BASEBOARD_FAB2_LIB.BASEBOARD_FAB2(SCH_1):PAGE76_I114@DEV_DISCRETE.CAP_A(CHIPS)':
 'A': CDS_PINID='A';
NODE_NAME     C8P26 1
 '@BASEBOARD_FAB2_LIB.BASEBOARD_FAB2(SCH_1):PAGE76_I118@MSTR_DISCRETE.CAP(CHIPS)':
 'A': CDS_PINID='A';
NODE_NAME     C2D37 1
 '@BASEBOARD_FAB2_LIB.BASEBOARD_FAB2(SCH_1):PAGE76_I119@DEV_DISCRETE.CAP_A(CHIPS)':
 'A': CDS_PINID='A';
NODE_NAME     C2D34 1
 '@BASEBOARD_FAB2_LIB.BASEBOARD_FAB2(SCH_1):PAGE76_I122@DEV_DISCRETE.CAP_A(CHIPS)':
 'A': CDS_PINID='A';
NODE_NAME     C2D16 1
 '@BASEBOARD_FAB2_LIB.BASEBOARD_FAB2(SCH_1):PAGE76_I124@DEV_DISCRETE.CAP_A(CHIPS)':
 'A': CDS_PINID='A';
NODE_NAME     C8P29 1
 '@BASEBOARD_FAB2_LIB.BASEBOARD_FAB2(SCH_1):PAGE76_I125@MSTR_DISCRETE.CAP(CHIPS)':
 'A': CDS_PINID='A';
NODE_NAME     C8P10 1
 '@BASEBOARD_FAB2_LIB.BASEBOARD_FAB2(SCH_1):PAGE76_I127@MSTR_DISCRETE.CAP(CHIPS)':
 'A': CDS_PINID='A';
NODE_NAME     C8P16 1
 '@BASEBOARD_FAB2_LIB.BASEBOARD_FAB2(SCH_1):PAGE76_I129@MSTR_DISCRETE.CAP(CHIPS)':
 'A': CDS_PINID='A';
NODE_NAME     C8P13 1
 '@BASEBOARD_FAB2_LIB.BASEBOARD_FAB2(SCH_1):PAGE76_I132@MSTR_DISCRETE.CAP(CHIPS)':
 'A': CDS_PINID='A';
NODE_NAME     C8P28 1
 '@BASEBOARD_FAB2_LIB.BASEBOARD_FAB2(SCH_1):PAGE76_I137@MSTR_DISCRETE.CAP(CHIPS)':
 'A': CDS_PINID='A';
NODE_NAME     C8P11 1
 '@BASEBOARD_FAB2_LIB.BASEBOARD_FAB2(SCH_1):PAGE76_I139@MSTR_DISCRETE.CAP(CHIPS)':
 'A': CDS_PINID='A';
NODE_NAME     C2D15 1
 '@BASEBOARD_FAB2_LIB.BASEBOARD_FAB2(SCH_1):PAGE76_I159@DEV_DISCRETE.CAP_A(CHIPS)':
 'A': CDS_PINID='A';
NODE_NAME     C2D38 1
 '@BASEBOARD_FAB2_LIB.BASEBOARD_FAB2(SCH_1):PAGE76_I160@DEV_DISCRETE.CAP_A(CHIPS)':
 'A': CDS_PINID='A';
NODE_NAME     C2D35 1
 '@BASEBOARD_FAB2_LIB.BASEBOARD_FAB2(SCH_1):PAGE76_I161@DEV_DISCRETE.CAP_A(CHIPS)':
 'A': CDS_PINID='A';
NODE_NAME     C7P19 1
 '@BASEBOARD_FAB2_LIB.BASEBOARD_FAB2(SCH_1):PAGE76_I215@MSTR_DISCRETE.CAP(CHIPS)':
 'A': CDS_PINID='A';
NODE_NAME     C8P24 1
 '@BASEBOARD_FAB2_LIB.BASEBOARD_FAB2(SCH_1):PAGE76_I217@MSTR_DISCRETE.CAP(CHIPS)':
 'A': CDS_PINID='A';
NODE_NAME     C9R8 1
 '@BASEBOARD_FAB2_LIB.BASEBOARD_FAB2(SCH_1):PAGE207_I8@DEV_DISCRETE.CAP_A(CHIPS)':
 'A': CDS_PINID='A';
NODE_NAME     C1E3 1
 '@BASEBOARD_FAB2_LIB.BASEBOARD_FAB2(SCH_1):PAGE207_I18@DEV_DISCRETE.CAP_A(CHIPS)':
 'A': CDS_PINID='A';
NODE_NAME     EU1E2 1
 '@BASEBOARD_FAB2_LIB.BASEBOARD_FAB2(SCH_1):PAGE207_I20@MSTR_DISCRETE.IR354XX(CHIPS)':
 'VOS': CDS_PINID='VOS';
NODE_NAME     C1E9 1
 '@BASEBOARD_FAB2_LIB.BASEBOARD_FAB2(SCH_1):PAGE207_I58@DEV_DISCRETE.CAP_A(CHIPS)':
 'A': CDS_PINID='A';
NODE_NAME     C9P3 1
 '@BASEBOARD_FAB2_LIB.BASEBOARD_FAB2(SCH_1):PAGE207_I59@DEV_DISCRETE.CAP_A(CHIPS)':
 'A': CDS_PINID='A';
NODE_NAME     R1E3 1
 '@BASEBOARD_FAB2_LIB.BASEBOARD_FAB2(SCH_1):PAGE208_I7@MSTR_DISCRETE.RES(CHIPS)':
 'A': CDS_PINID='A';
NODE_NAME     C1D14 1
 '@BASEBOARD_FAB2_LIB.BASEBOARD_FAB2(SCH_1):PAGE208_I9@DEV_DISCRETE.CAP_A(CHIPS)':
 'A': CDS_PINID='A';
NODE_NAME     C9P8 1
 '@BASEBOARD_FAB2_LIB.BASEBOARD_FAB2(SCH_1):PAGE208_I12@MSTR_DISCRETE.CAPP(CHIPS)':
 'A': CDS_PINID='A';
NODE_NAME     C9P5 1
 '@BASEBOARD_FAB2_LIB.BASEBOARD_FAB2(SCH_1):PAGE208_I14@MSTR_DISCRETE.CAPP(CHIPS)':
 'A': CDS_PINID='A';
NODE_NAME     C1D3 1
 '@BASEBOARD_FAB2_LIB.BASEBOARD_FAB2(SCH_1):PAGE208_I22@DEV_DISCRETE.CAP_A(CHIPS)':
 'A': CDS_PINID='A';
NODE_NAME     C9N24 1
 '@BASEBOARD_FAB2_LIB.BASEBOARD_FAB2(SCH_1):PAGE208_I24@MSTR_DISCRETE.CAPP(CHIPS)':
 'A': CDS_PINID='A';
NODE_NAME     C9R9 1
 '@BASEBOARD_FAB2_LIB.BASEBOARD_FAB2(SCH_1):PAGE208_I25@MSTR_DISCRETE.CAPP(CHIPS)':
 'A': CDS_PINID='A';
NODE_NAME     C9R3 1
 '@BASEBOARD_FAB2_LIB.BASEBOARD_FAB2(SCH_1):PAGE208_I26@MSTR_DISCRETE.CAPP(CHIPS)':
 'A': CDS_PINID='A';
NODE_NAME     EU1D3 1
 '@BASEBOARD_FAB2_LIB.BASEBOARD_FAB2(SCH_1):PAGE208_I27@MSTR_DISCRETE.IR354XX(CHIPS)':
 'VOS': CDS_PINID='VOS';
NODE_NAME     C9P23 1
 '@BASEBOARD_FAB2_LIB.BASEBOARD_FAB2(SCH_1):PAGE208_I28@MSTR_DISCRETE.CAPP(CHIPS)':
 'A': CDS_PINID='A';
NODE_NAME     C9P18 1
 '@BASEBOARD_FAB2_LIB.BASEBOARD_FAB2(SCH_1):PAGE208_I30@MSTR_DISCRETE.CAPP(CHIPS)':
 'A': CDS_PINID='A';
NODE_NAME     C9P10 1
 '@BASEBOARD_FAB2_LIB.BASEBOARD_FAB2(SCH_1):PAGE208_I66@DEV_DISCRETE.CAP_A(CHIPS)':
 'A': CDS_PINID='A';
NODE_NAME     C9R2 1
 '@BASEBOARD_FAB2_LIB.BASEBOARD_FAB2(SCH_1):PAGE208_I67@DEV_DISCRETE.CAP_A(CHIPS)':
 'A': CDS_PINID='A';
NODE_NAME     EU1D1 1
 '@BASEBOARD_FAB2_LIB.BASEBOARD_FAB2(SCH_1):PAGE208_I71@MSTR_DISCRETE.IR354XX(CHIPS)':
 'VOS': CDS_PINID='VOS';
NODE_NAME     R1E4 2
 '@BASEBOARD_FAB2_LIB.BASEBOARD_FAB2(SCH_1):PAGE209_I15@MSTR_DISCRETE.RES(CHIPS)':
 'B': CDS_PINID='B';
NODE_NAME     C1D24 1
 '@BASEBOARD_FAB2_LIB.BASEBOARD_FAB2(SCH_1):PAGE209_I42@DEV_DISCRETE.CAP_A(CHIPS)':
 'A': CDS_PINID='A';
NODE_NAME     C9P20 1
 '@BASEBOARD_FAB2_LIB.BASEBOARD_FAB2(SCH_1):PAGE209_I55@DEV_DISCRETE.CAP_A(CHIPS)':
 'A': CDS_PINID='A';
NODE_NAME     EU1C3 1
 '@BASEBOARD_FAB2_LIB.BASEBOARD_FAB2(SCH_1):PAGE209_I56@MSTR_DISCRETE.IR354XX(CHIPS)':
 'VOS': CDS_PINID='VOS';
NODE_NAME     L1E1 2
 '@BASEBOARD_FAB2_LIB.BASEBOARD_FAB2(SCH_1):PAGE207_I107@W_HDL.IND-120NH-30-GP(CHIPS)':
 'F': CDS_PINID='F';
NODE_NAME     L1D3 2
 '@BASEBOARD_FAB2_LIB.BASEBOARD_FAB2(SCH_1):PAGE207_I108@W_HDL.IND-120NH-30-GP(CHIPS)':
 'F': CDS_PINID='F';
NODE_NAME     L1D2 2
 '@BASEBOARD_FAB2_LIB.BASEBOARD_FAB2(SCH_1):PAGE208_I116@W_HDL.IND-120NH-30-GP(CHIPS)':
 'F': CDS_PINID='F';
NODE_NAME     L1D1 2
 '@BASEBOARD_FAB2_LIB.BASEBOARD_FAB2(SCH_1):PAGE208_I117@W_HDL.IND-120NH-30-GP(CHIPS)':
 'F': CDS_PINID='F';
NODE_NAME     L1C2 2
 '@BASEBOARD_FAB2_LIB.BASEBOARD_FAB2(SCH_1):PAGE209_I80@W_HDL.IND-120NH-30-GP(CHIPS)':
 'F': CDS_PINID='F';
NODE_NAME     C8W4 1
 '@BASEBOARD_FAB2_LIB.BASEBOARD_FAB2(SCH_1):PAGE76_I245@MSTR_DISCRETE.CAP(CHIPS)':
 'A': CDS_PINID='A';
NODE_NAME     C8P21 1
 '@BASEBOARD_FAB2_LIB.BASEBOARD_FAB2(SCH_1):PAGE76_I249@MSTR_DISCRETE.CAP(CHIPS)':
 'A': CDS_PINID='A';
NODE_NAME     C8P27 1
 '@BASEBOARD_FAB2_LIB.BASEBOARD_FAB2(SCH_1):PAGE76_I250@MSTR_DISCRETE.CAP(CHIPS)':
 'A': CDS_PINID='A';
NODE_NAME     C8P25 1
 '@BASEBOARD_FAB2_LIB.BASEBOARD_FAB2(SCH_1):PAGE76_I251@MSTR_DISCRETE.CAP(CHIPS)':
 'A': CDS_PINID='A';
NODE_NAME     C8P17 1
 '@BASEBOARD_FAB2_LIB.BASEBOARD_FAB2(SCH_1):PAGE76_I252@MSTR_DISCRETE.CAP(CHIPS)':
 'A': CDS_PINID='A';
NODE_NAME     EU1D4 1
 '@BASEBOARD_FAB2_LIB.BASEBOARD_FAB2(SCH_1):PAGE207_I113@MSTR_DISCRETE.IR354XX(CHIPS)':
 'VOS': CDS_PINID='VOS';
NET_NAME
'PVCCIOMCP_CPU0'
 '@BASEBOARD_FAB2_LIB.BASEBOARD_FAB2(SCH_1):PVCCIOMCP_CPU0':
 C_SIGNAL='@baseboard_fab2_lib.baseboard_fab2(sch_1):pvcciomcp_cpu0';
NODE_NAME     U5D1 BU18
 '@BASEBOARD_FAB2_LIB.BASEBOARD_FAB2(SCH_1):PAGE36_I15@CHPSET_LIB.SKX_EXT_B(CHIPS)':
 'RSVD'<129>: CDS_PINID='RSVD(129)';
NODE_NAME     U5D1 BP17
 '@BASEBOARD_FAB2_LIB.BASEBOARD_FAB2(SCH_1):PAGE36_I15@CHPSET_LIB.SKX_EXT_B(CHIPS)':
 'RSVD'<133>: CDS_PINID='RSVD(133)';
NODE_NAME     U5D1 BN18
 '@BASEBOARD_FAB2_LIB.BASEBOARD_FAB2(SCH_1):PAGE36_I15@CHPSET_LIB.SKX_EXT_B(CHIPS)':
 'RSVD'<134>: CDS_PINID='RSVD(134)';
NODE_NAME     U5D1 BM17
 '@BASEBOARD_FAB2_LIB.BASEBOARD_FAB2(SCH_1):PAGE36_I15@CHPSET_LIB.SKX_EXT_B(CHIPS)':
 'RSVD'<136>: CDS_PINID='RSVD(136)';
NODE_NAME     U5D1 BL18
 '@BASEBOARD_FAB2_LIB.BASEBOARD_FAB2(SCH_1):PAGE36_I15@CHPSET_LIB.SKX_EXT_B(CHIPS)':
 'RSVD'<138>: CDS_PINID='RSVD(138)';
NODE_NAME     U5D1 BV15
 '@BASEBOARD_FAB2_LIB.BASEBOARD_FAB2(SCH_1):PAGE38_I34@CHPSET_LIB.SKX_EXT_B(CHIPS)':
 'CD_VCCP'<0>: CDS_PINID='CD_VCCP(0)';
NODE_NAME     U5D1 BV13
 '@BASEBOARD_FAB2_LIB.BASEBOARD_FAB2(SCH_1):PAGE38_I34@CHPSET_LIB.SKX_EXT_B(CHIPS)':
 'CD_VCCP'<1>: CDS_PINID='CD_VCCP(1)';
NODE_NAME     U5D1 BV11
 '@BASEBOARD_FAB2_LIB.BASEBOARD_FAB2(SCH_1):PAGE38_I34@CHPSET_LIB.SKX_EXT_B(CHIPS)':
 'CD_VCCP'<2>: CDS_PINID='CD_VCCP(2)';
NODE_NAME     U5D1 BU14
 '@BASEBOARD_FAB2_LIB.BASEBOARD_FAB2(SCH_1):PAGE38_I34@CHPSET_LIB.SKX_EXT_B(CHIPS)':
 'CD_VCCP'<3>: CDS_PINID='CD_VCCP(3)';
NODE_NAME     U5D1 BU12
 '@BASEBOARD_FAB2_LIB.BASEBOARD_FAB2(SCH_1):PAGE38_I34@CHPSET_LIB.SKX_EXT_B(CHIPS)':
 'CD_VCCP'<4>: CDS_PINID='CD_VCCP(4)';
NODE_NAME     U5D1 BT15
 '@BASEBOARD_FAB2_LIB.BASEBOARD_FAB2(SCH_1):PAGE38_I34@CHPSET_LIB.SKX_EXT_B(CHIPS)':
 'CD_VCCP'<5>: CDS_PINID='CD_VCCP(5)';
NODE_NAME     U5D1 BT13
 '@BASEBOARD_FAB2_LIB.BASEBOARD_FAB2(SCH_1):PAGE38_I34@CHPSET_LIB.SKX_EXT_B(CHIPS)':
 'CD_VCCP'<6>: CDS_PINID='CD_VCCP(6)';
NODE_NAME     U5D1 BT11
 '@BASEBOARD_FAB2_LIB.BASEBOARD_FAB2(SCH_1):PAGE38_I34@CHPSET_LIB.SKX_EXT_B(CHIPS)':
 'CD_VCCP'<7>: CDS_PINID='CD_VCCP(7)';
NODE_NAME     U5D1 BR14
 '@BASEBOARD_FAB2_LIB.BASEBOARD_FAB2(SCH_1):PAGE38_I34@CHPSET_LIB.SKX_EXT_B(CHIPS)':
 'CD_VCCP'<8>: CDS_PINID='CD_VCCP(8)';
NODE_NAME     U5D1 BR12
 '@BASEBOARD_FAB2_LIB.BASEBOARD_FAB2(SCH_1):PAGE38_I34@CHPSET_LIB.SKX_EXT_B(CHIPS)':
 'CD_VCCP'<9>: CDS_PINID='CD_VCCP(9)';
NODE_NAME     U5D1 BP15
 '@BASEBOARD_FAB2_LIB.BASEBOARD_FAB2(SCH_1):PAGE38_I34@CHPSET_LIB.SKX_EXT_B(CHIPS)':
 'CD_VCCP'<10>: CDS_PINID='CD_VCCP(10)';
NODE_NAME     U5D1 BP13
 '@BASEBOARD_FAB2_LIB.BASEBOARD_FAB2(SCH_1):PAGE38_I34@CHPSET_LIB.SKX_EXT_B(CHIPS)':
 'CD_VCCP'<11>: CDS_PINID='CD_VCCP(11)';
NODE_NAME     U5D1 BP11
 '@BASEBOARD_FAB2_LIB.BASEBOARD_FAB2(SCH_1):PAGE38_I34@CHPSET_LIB.SKX_EXT_B(CHIPS)':
 'CD_VCCP'<12>: CDS_PINID='CD_VCCP(12)';
NODE_NAME     U5D1 BN14
 '@BASEBOARD_FAB2_LIB.BASEBOARD_FAB2(SCH_1):PAGE38_I34@CHPSET_LIB.SKX_EXT_B(CHIPS)':
 'CD_VCCP'<13>: CDS_PINID='CD_VCCP(13)';
NODE_NAME     U5D1 BN12
 '@BASEBOARD_FAB2_LIB.BASEBOARD_FAB2(SCH_1):PAGE38_I34@CHPSET_LIB.SKX_EXT_B(CHIPS)':
 'CD_VCCP'<14>: CDS_PINID='CD_VCCP(14)';
NODE_NAME     U5D1 BM11
 '@BASEBOARD_FAB2_LIB.BASEBOARD_FAB2(SCH_1):PAGE38_I34@CHPSET_LIB.SKX_EXT_B(CHIPS)':
 'CD_VCCP'<15>: CDS_PINID='CD_VCCP(15)';
NODE_NAME     J6B1 C17
 '@BASEBOARD_FAB2_LIB.BASEBOARD_FAB2(SCH_1):PAGE194_I56@MSTR_SCONN.SCONN120_H61426002(CHIPS)':
 'IOC17': CDS_PINID='IOC17';
NODE_NAME     J6B1 C18
 '@BASEBOARD_FAB2_LIB.BASEBOARD_FAB2(SCH_1):PAGE194_I56@MSTR_SCONN.SCONN120_H61426002(CHIPS)':
 'IOC18': CDS_PINID='IOC18';
NODE_NAME     J6B1 C19
 '@BASEBOARD_FAB2_LIB.BASEBOARD_FAB2(SCH_1):PAGE194_I56@MSTR_SCONN.SCONN120_H61426002(CHIPS)':
 'IOC19': CDS_PINID='IOC19';
NODE_NAME     J6B1 D17
 '@BASEBOARD_FAB2_LIB.BASEBOARD_FAB2(SCH_1):PAGE194_I56@MSTR_SCONN.SCONN120_H61426002(CHIPS)':
 'IOD17': CDS_PINID='IOD17';
NODE_NAME     J6B1 D18
 '@BASEBOARD_FAB2_LIB.BASEBOARD_FAB2(SCH_1):PAGE194_I56@MSTR_SCONN.SCONN120_H61426002(CHIPS)':
 'IOD18': CDS_PINID='IOD18';
NODE_NAME     J6B1 D19
 '@BASEBOARD_FAB2_LIB.BASEBOARD_FAB2(SCH_1):PAGE194_I56@MSTR_SCONN.SCONN120_H61426002(CHIPS)':
 'IOD19': CDS_PINID='IOD19';
NODE_NAME     J6B1 E15
 '@BASEBOARD_FAB2_LIB.BASEBOARD_FAB2(SCH_1):PAGE194_I56@MSTR_SCONN.SCONN120_H61426002(CHIPS)':
 'IOE15': CDS_PINID='IOE15';
NODE_NAME     J6B1 E16
 '@BASEBOARD_FAB2_LIB.BASEBOARD_FAB2(SCH_1):PAGE194_I56@MSTR_SCONN.SCONN120_H61426002(CHIPS)':
 'IOE16': CDS_PINID='IOE16';
NODE_NAME     J6B1 E17
 '@BASEBOARD_FAB2_LIB.BASEBOARD_FAB2(SCH_1):PAGE194_I56@MSTR_SCONN.SCONN120_H61426002(CHIPS)':
 'IOE17': CDS_PINID='IOE17';
NODE_NAME     J6B1 E18
 '@BASEBOARD_FAB2_LIB.BASEBOARD_FAB2(SCH_1):PAGE194_I56@MSTR_SCONN.SCONN120_H61426002(CHIPS)':
 'IOE18': CDS_PINID='IOE18';
NODE_NAME     J6B1 E19
 '@BASEBOARD_FAB2_LIB.BASEBOARD_FAB2(SCH_1):PAGE194_I56@MSTR_SCONN.SCONN120_H61426002(CHIPS)':
 'IOE19': CDS_PINID='IOE19';
NODE_NAME     J6B1 F15
 '@BASEBOARD_FAB2_LIB.BASEBOARD_FAB2(SCH_1):PAGE194_I56@MSTR_SCONN.SCONN120_H61426002(CHIPS)':
 'IOF15': CDS_PINID='IOF15';
NODE_NAME     J6B1 F16
 '@BASEBOARD_FAB2_LIB.BASEBOARD_FAB2(SCH_1):PAGE194_I56@MSTR_SCONN.SCONN120_H61426002(CHIPS)':
 'IOF16': CDS_PINID='IOF16';
NODE_NAME     J6B1 F17
 '@BASEBOARD_FAB2_LIB.BASEBOARD_FAB2(SCH_1):PAGE194_I56@MSTR_SCONN.SCONN120_H61426002(CHIPS)':
 'IOF17': CDS_PINID='IOF17';
NODE_NAME     J6B1 F18
 '@BASEBOARD_FAB2_LIB.BASEBOARD_FAB2(SCH_1):PAGE194_I56@MSTR_SCONN.SCONN120_H61426002(CHIPS)':
 'IOF18': CDS_PINID='IOF18';
NODE_NAME     J6B1 F19
 '@BASEBOARD_FAB2_LIB.BASEBOARD_FAB2(SCH_1):PAGE194_I56@MSTR_SCONN.SCONN120_H61426002(CHIPS)':
 'IOF19': CDS_PINID='IOF19';
NODE_NAME     C3N40 1
 '@BASEBOARD_FAB2_LIB.BASEBOARD_FAB2(SCH_1):PAGE194_I86@DEV_DISCRETE.CAP_A(CHIPS)':
 'A': CDS_PINID='A';
NODE_NAME     C3M46 1
 '@BASEBOARD_FAB2_LIB.BASEBOARD_FAB2(SCH_1):PAGE194_I99@DEV_DISCRETE.CAP_A(CHIPS)':
 'A': CDS_PINID='A';
NODE_NAME     C3N14 1
 '@BASEBOARD_FAB2_LIB.BASEBOARD_FAB2(SCH_1):PAGE194_I101@MSTR_DISCRETE.CAPP(CHIPS)':
 'A': CDS_PINID='A';
NET_NAME
'PVCCIOMCP_CPU1'
 '@BASEBOARD_FAB2_LIB.BASEBOARD_FAB2(SCH_1):PVCCIOMCP_CPU1':
 C_SIGNAL='@baseboard_fab2_lib.baseboard_fab2(sch_1):pvcciomcp_cpu1';
NODE_NAME     U2D1 BU18
 '@BASEBOARD_FAB2_LIB.BASEBOARD_FAB2(SCH_1):PAGE70_I9@CHPSET_LIB.SKX_EXT_B(CHIPS)':
 'RSVD'<129>: CDS_PINID='RSVD(129)';
NODE_NAME     U2D1 BP17
 '@BASEBOARD_FAB2_LIB.BASEBOARD_FAB2(SCH_1):PAGE70_I9@CHPSET_LIB.SKX_EXT_B(CHIPS)':
 'RSVD'<133>: CDS_PINID='RSVD(133)';
NODE_NAME     U2D1 BN18
 '@BASEBOARD_FAB2_LIB.BASEBOARD_FAB2(SCH_1):PAGE70_I9@CHPSET_LIB.SKX_EXT_B(CHIPS)':
 'RSVD'<134>: CDS_PINID='RSVD(134)';
NODE_NAME     U2D1 BM17
 '@BASEBOARD_FAB2_LIB.BASEBOARD_FAB2(SCH_1):PAGE70_I9@CHPSET_LIB.SKX_EXT_B(CHIPS)':
 'RSVD'<136>: CDS_PINID='RSVD(136)';
NODE_NAME     U2D1 BL18
 '@BASEBOARD_FAB2_LIB.BASEBOARD_FAB2(SCH_1):PAGE70_I9@CHPSET_LIB.SKX_EXT_B(CHIPS)':
 'RSVD'<138>: CDS_PINID='RSVD(138)';
NODE_NAME     U2D1 BV15
 '@BASEBOARD_FAB2_LIB.BASEBOARD_FAB2(SCH_1):PAGE72_I33@CHPSET_LIB.SKX_EXT_B(CHIPS)':
 'CD_VCCP'<0>: CDS_PINID='CD_VCCP(0)';
NODE_NAME     U2D1 BV13
 '@BASEBOARD_FAB2_LIB.BASEBOARD_FAB2(SCH_1):PAGE72_I33@CHPSET_LIB.SKX_EXT_B(CHIPS)':
 'CD_VCCP'<1>: CDS_PINID='CD_VCCP(1)';
NODE_NAME     U2D1 BV11
 '@BASEBOARD_FAB2_LIB.BASEBOARD_FAB2(SCH_1):PAGE72_I33@CHPSET_LIB.SKX_EXT_B(CHIPS)':
 'CD_VCCP'<2>: CDS_PINID='CD_VCCP(2)';
NODE_NAME     U2D1 BU14
 '@BASEBOARD_FAB2_LIB.BASEBOARD_FAB2(SCH_1):PAGE72_I33@CHPSET_LIB.SKX_EXT_B(CHIPS)':
 'CD_VCCP'<3>: CDS_PINID='CD_VCCP(3)';
NODE_NAME     U2D1 BU12
 '@BASEBOARD_FAB2_LIB.BASEBOARD_FAB2(SCH_1):PAGE72_I33@CHPSET_LIB.SKX_EXT_B(CHIPS)':
 'CD_VCCP'<4>: CDS_PINID='CD_VCCP(4)';
NODE_NAME     U2D1 BT15
 '@BASEBOARD_FAB2_LIB.BASEBOARD_FAB2(SCH_1):PAGE72_I33@CHPSET_LIB.SKX_EXT_B(CHIPS)':
 'CD_VCCP'<5>: CDS_PINID='CD_VCCP(5)';
NODE_NAME     U2D1 BT13
 '@BASEBOARD_FAB2_LIB.BASEBOARD_FAB2(SCH_1):PAGE72_I33@CHPSET_LIB.SKX_EXT_B(CHIPS)':
 'CD_VCCP'<6>: CDS_PINID='CD_VCCP(6)';
NODE_NAME     U2D1 BT11
 '@BASEBOARD_FAB2_LIB.BASEBOARD_FAB2(SCH_1):PAGE72_I33@CHPSET_LIB.SKX_EXT_B(CHIPS)':
 'CD_VCCP'<7>: CDS_PINID='CD_VCCP(7)';
NODE_NAME     U2D1 BR14
 '@BASEBOARD_FAB2_LIB.BASEBOARD_FAB2(SCH_1):PAGE72_I33@CHPSET_LIB.SKX_EXT_B(CHIPS)':
 'CD_VCCP'<8>: CDS_PINID='CD_VCCP(8)';
NODE_NAME     U2D1 BR12
 '@BASEBOARD_FAB2_LIB.BASEBOARD_FAB2(SCH_1):PAGE72_I33@CHPSET_LIB.SKX_EXT_B(CHIPS)':
 'CD_VCCP'<9>: CDS_PINID='CD_VCCP(9)';
NODE_NAME     U2D1 BP15
 '@BASEBOARD_FAB2_LIB.BASEBOARD_FAB2(SCH_1):PAGE72_I33@CHPSET_LIB.SKX_EXT_B(CHIPS)':
 'CD_VCCP'<10>: CDS_PINID='CD_VCCP(10)';
NODE_NAME     U2D1 BP13
 '@BASEBOARD_FAB2_LIB.BASEBOARD_FAB2(SCH_1):PAGE72_I33@CHPSET_LIB.SKX_EXT_B(CHIPS)':
 'CD_VCCP'<11>: CDS_PINID='CD_VCCP(11)';
NODE_NAME     U2D1 BP11
 '@BASEBOARD_FAB2_LIB.BASEBOARD_FAB2(SCH_1):PAGE72_I33@CHPSET_LIB.SKX_EXT_B(CHIPS)':
 'CD_VCCP'<12>: CDS_PINID='CD_VCCP(12)';
NODE_NAME     U2D1 BN14
 '@BASEBOARD_FAB2_LIB.BASEBOARD_FAB2(SCH_1):PAGE72_I33@CHPSET_LIB.SKX_EXT_B(CHIPS)':
 'CD_VCCP'<13>: CDS_PINID='CD_VCCP(13)';
NODE_NAME     U2D1 BN12
 '@BASEBOARD_FAB2_LIB.BASEBOARD_FAB2(SCH_1):PAGE72_I33@CHPSET_LIB.SKX_EXT_B(CHIPS)':
 'CD_VCCP'<14>: CDS_PINID='CD_VCCP(14)';
NODE_NAME     U2D1 BM11
 '@BASEBOARD_FAB2_LIB.BASEBOARD_FAB2(SCH_1):PAGE72_I33@CHPSET_LIB.SKX_EXT_B(CHIPS)':
 'CD_VCCP'<15>: CDS_PINID='CD_VCCP(15)';
NODE_NAME     C4C1 1
 '@BASEBOARD_FAB2_LIB.BASEBOARD_FAB2(SCH_1):PAGE193_I29@MSTR_DISCRETE.CAPP(CHIPS)':
 'A': CDS_PINID='A';
NODE_NAME     C3C2 1
 '@BASEBOARD_FAB2_LIB.BASEBOARD_FAB2(SCH_1):PAGE193_I31@DEV_DISCRETE.CAP_A(CHIPS)':
 'A': CDS_PINID='A';
NODE_NAME     C3C1 1
 '@BASEBOARD_FAB2_LIB.BASEBOARD_FAB2(SCH_1):PAGE193_I38@DEV_DISCRETE.CAP_A(CHIPS)':
 'A': CDS_PINID='A';
NODE_NAME     J4B2 C17
 '@BASEBOARD_FAB2_LIB.BASEBOARD_FAB2(SCH_1):PAGE193_I46@MSTR_SCONN.SCONN120_H61426002(CHIPS)':
 'IOC17': CDS_PINID='IOC17';
NODE_NAME     J4B2 C18
 '@BASEBOARD_FAB2_LIB.BASEBOARD_FAB2(SCH_1):PAGE193_I46@MSTR_SCONN.SCONN120_H61426002(CHIPS)':
 'IOC18': CDS_PINID='IOC18';
NODE_NAME     J4B2 C19
 '@BASEBOARD_FAB2_LIB.BASEBOARD_FAB2(SCH_1):PAGE193_I46@MSTR_SCONN.SCONN120_H61426002(CHIPS)':
 'IOC19': CDS_PINID='IOC19';
NODE_NAME     J4B2 D17
 '@BASEBOARD_FAB2_LIB.BASEBOARD_FAB2(SCH_1):PAGE193_I46@MSTR_SCONN.SCONN120_H61426002(CHIPS)':
 'IOD17': CDS_PINID='IOD17';
NODE_NAME     J4B2 D18
 '@BASEBOARD_FAB2_LIB.BASEBOARD_FAB2(SCH_1):PAGE193_I46@MSTR_SCONN.SCONN120_H61426002(CHIPS)':
 'IOD18': CDS_PINID='IOD18';
NODE_NAME     J4B2 D19
 '@BASEBOARD_FAB2_LIB.BASEBOARD_FAB2(SCH_1):PAGE193_I46@MSTR_SCONN.SCONN120_H61426002(CHIPS)':
 'IOD19': CDS_PINID='IOD19';
NODE_NAME     J4B2 E15
 '@BASEBOARD_FAB2_LIB.BASEBOARD_FAB2(SCH_1):PAGE193_I46@MSTR_SCONN.SCONN120_H61426002(CHIPS)':
 'IOE15': CDS_PINID='IOE15';
NODE_NAME     J4B2 E16
 '@BASEBOARD_FAB2_LIB.BASEBOARD_FAB2(SCH_1):PAGE193_I46@MSTR_SCONN.SCONN120_H61426002(CHIPS)':
 'IOE16': CDS_PINID='IOE16';
NODE_NAME     J4B2 E17
 '@BASEBOARD_FAB2_LIB.BASEBOARD_FAB2(SCH_1):PAGE193_I46@MSTR_SCONN.SCONN120_H61426002(CHIPS)':
 'IOE17': CDS_PINID='IOE17';
NODE_NAME     J4B2 E18
 '@BASEBOARD_FAB2_LIB.BASEBOARD_FAB2(SCH_1):PAGE193_I46@MSTR_SCONN.SCONN120_H61426002(CHIPS)':
 'IOE18': CDS_PINID='IOE18';
NODE_NAME     J4B2 E19
 '@BASEBOARD_FAB2_LIB.BASEBOARD_FAB2(SCH_1):PAGE193_I46@MSTR_SCONN.SCONN120_H61426002(CHIPS)':
 'IOE19': CDS_PINID='IOE19';
NODE_NAME     J4B2 F15
 '@BASEBOARD_FAB2_LIB.BASEBOARD_FAB2(SCH_1):PAGE193_I46@MSTR_SCONN.SCONN120_H61426002(CHIPS)':
 'IOF15': CDS_PINID='IOF15';
NODE_NAME     J4B2 F16
 '@BASEBOARD_FAB2_LIB.BASEBOARD_FAB2(SCH_1):PAGE193_I46@MSTR_SCONN.SCONN120_H61426002(CHIPS)':
 'IOF16': CDS_PINID='IOF16';
NODE_NAME     J4B2 F17
 '@BASEBOARD_FAB2_LIB.BASEBOARD_FAB2(SCH_1):PAGE193_I46@MSTR_SCONN.SCONN120_H61426002(CHIPS)':
 'IOF17': CDS_PINID='IOF17';
NODE_NAME     J4B2 F18
 '@BASEBOARD_FAB2_LIB.BASEBOARD_FAB2(SCH_1):PAGE193_I46@MSTR_SCONN.SCONN120_H61426002(CHIPS)':
 'IOF18': CDS_PINID='IOF18';
NODE_NAME     J4B2 F19
 '@BASEBOARD_FAB2_LIB.BASEBOARD_FAB2(SCH_1):PAGE193_I46@MSTR_SCONN.SCONN120_H61426002(CHIPS)':
 'IOF19': CDS_PINID='IOF19';
NET_NAME
'PVCCIO_CPU0'
 '@BASEBOARD_FAB2_LIB.BASEBOARD_FAB2(SCH_1):PVCCIO_CPU0':
 C_SIGNAL='@baseboard_fab2_lib.baseboard_fab2(sch_1):pvccio_cpu0';
NODE_NAME     R6B2 1
 '@BASEBOARD_FAB2_LIB.BASEBOARD_FAB2(SCH_1):PAGE21_I159@MSTR_DISCRETE.RES(CHIPS)':
 'A': CDS_PINID='A';
NODE_NAME     R6B1 1
 '@BASEBOARD_FAB2_LIB.BASEBOARD_FAB2(SCH_1):PAGE21_I161@MSTR_DISCRETE.RES(CHIPS)':
 'A': CDS_PINID='A';
NODE_NAME     R6N2 2
 '@BASEBOARD_FAB2_LIB.BASEBOARD_FAB2(SCH_1):PAGE21_I163@MSTR_DISCRETE.RES(CHIPS)':
 'B': CDS_PINID='B';
NODE_NAME     R6N1 2
 '@BASEBOARD_FAB2_LIB.BASEBOARD_FAB2(SCH_1):PAGE21_I164@MSTR_DISCRETE.RES(CHIPS)':
 'B': CDS_PINID='B';
NODE_NAME     R5D6 1
 '@BASEBOARD_FAB2_LIB.BASEBOARD_FAB2(SCH_1):PAGE37_I312@MSTR_DISCRETE.RES(CHIPS)':
 'A': CDS_PINID='A';
NODE_NAME     U5D1 CM15
 '@BASEBOARD_FAB2_LIB.BASEBOARD_FAB2(SCH_1):PAGE38_I34@CHPSET_LIB.SKX_EXT_B(CHIPS)':
 'VCCIO'<20>: CDS_PINID='VCCIO(20)';
NODE_NAME     U5D1 CL12
 '@BASEBOARD_FAB2_LIB.BASEBOARD_FAB2(SCH_1):PAGE38_I34@CHPSET_LIB.SKX_EXT_B(CHIPS)':
 'VCCIO'<21>: CDS_PINID='VCCIO(21)';
NODE_NAME     U5D1 CK5
 '@BASEBOARD_FAB2_LIB.BASEBOARD_FAB2(SCH_1):PAGE38_I34@CHPSET_LIB.SKX_EXT_B(CHIPS)':
 'VCCIO'<22>: CDS_PINID='VCCIO(22)';
NODE_NAME     U5D1 CV7
 '@BASEBOARD_FAB2_LIB.BASEBOARD_FAB2(SCH_1):PAGE38_I34@CHPSET_LIB.SKX_EXT_B(CHIPS)':
 'VCCIO'<23>: CDS_PINID='VCCIO(23)';
NODE_NAME     U5D1 CH9
 '@BASEBOARD_FAB2_LIB.BASEBOARD_FAB2(SCH_1):PAGE38_I34@CHPSET_LIB.SKX_EXT_B(CHIPS)':
 'VCCIO'<24>: CDS_PINID='VCCIO(24)';
NODE_NAME     U5D1 D7
 '@BASEBOARD_FAB2_LIB.BASEBOARD_FAB2(SCH_1):PAGE38_I34@CHPSET_LIB.SKX_EXT_B(CHIPS)':
 'VCCIO'<25>: CDS_PINID='VCCIO(25)';
NODE_NAME     U5D1 CE18
 '@BASEBOARD_FAB2_LIB.BASEBOARD_FAB2(SCH_1):PAGE38_I34@CHPSET_LIB.SKX_EXT_B(CHIPS)':
 'VCCIO'<26>: CDS_PINID='VCCIO(26)';
NODE_NAME     U5D1 CD9
 '@BASEBOARD_FAB2_LIB.BASEBOARD_FAB2(SCH_1):PAGE38_I34@CHPSET_LIB.SKX_EXT_B(CHIPS)':
 'VCCIO'<27>: CDS_PINID='VCCIO(27)';
NODE_NAME     U5D1 CB17
 '@BASEBOARD_FAB2_LIB.BASEBOARD_FAB2(SCH_1):PAGE38_I34@CHPSET_LIB.SKX_EXT_B(CHIPS)':
 'VCCIO'<28>: CDS_PINID='VCCIO(28)';
NODE_NAME     U5D1 CB13
 '@BASEBOARD_FAB2_LIB.BASEBOARD_FAB2(SCH_1):PAGE38_I34@CHPSET_LIB.SKX_EXT_B(CHIPS)':
 'VCCIO'<29>: CDS_PINID='VCCIO(29)';
NODE_NAME     U5D1 BP25
 '@BASEBOARD_FAB2_LIB.BASEBOARD_FAB2(SCH_1):PAGE38_I34@CHPSET_LIB.SKX_EXT_B(CHIPS)':
 'VCCIO'<30>: CDS_PINID='VCCIO(30)';
NODE_NAME     U5D1 BJ24
 '@BASEBOARD_FAB2_LIB.BASEBOARD_FAB2(SCH_1):PAGE38_I34@CHPSET_LIB.SKX_EXT_B(CHIPS)':
 'VCCIO'<31>: CDS_PINID='VCCIO(31)';
NODE_NAME     U5D1 BF23
 '@BASEBOARD_FAB2_LIB.BASEBOARD_FAB2(SCH_1):PAGE38_I34@CHPSET_LIB.SKX_EXT_B(CHIPS)':
 'VCCIO'<32>: CDS_PINID='VCCIO(32)';
NODE_NAME     U5D1 DA14
 '@BASEBOARD_FAB2_LIB.BASEBOARD_FAB2(SCH_1):PAGE38_I34@CHPSET_LIB.SKX_EXT_B(CHIPS)':
 'VCCIO'<33>: CDS_PINID='VCCIO(33)';
NODE_NAME     U5D1 BB5
 '@BASEBOARD_FAB2_LIB.BASEBOARD_FAB2(SCH_1):PAGE38_I34@CHPSET_LIB.SKX_EXT_B(CHIPS)':
 'VCCIO'<34>: CDS_PINID='VCCIO(34)';
NODE_NAME     U5D1 BA24
 '@BASEBOARD_FAB2_LIB.BASEBOARD_FAB2(SCH_1):PAGE38_I34@CHPSET_LIB.SKX_EXT_B(CHIPS)':
 'VCCIO'<35>: CDS_PINID='VCCIO(35)';
NODE_NAME     U5D1 AY11
 '@BASEBOARD_FAB2_LIB.BASEBOARD_FAB2(SCH_1):PAGE38_I34@CHPSET_LIB.SKX_EXT_B(CHIPS)':
 'VCCIO'<36>: CDS_PINID='VCCIO(36)';
NODE_NAME     U5D1 AW6
 '@BASEBOARD_FAB2_LIB.BASEBOARD_FAB2(SCH_1):PAGE38_I34@CHPSET_LIB.SKX_EXT_B(CHIPS)':
 'VCCIO'<37>: CDS_PINID='VCCIO(37)';
NODE_NAME     U5D1 AT11
 '@BASEBOARD_FAB2_LIB.BASEBOARD_FAB2(SCH_1):PAGE38_I34@CHPSET_LIB.SKX_EXT_B(CHIPS)':
 'VCCIO'<38>: CDS_PINID='VCCIO(38)';
NODE_NAME     U5D1 DD7
 '@BASEBOARD_FAB2_LIB.BASEBOARD_FAB2(SCH_1):PAGE38_I34@CHPSET_LIB.SKX_EXT_B(CHIPS)':
 'VCCIO'<39>: CDS_PINID='VCCIO(39)';
NODE_NAME     U5D1 AN10
 '@BASEBOARD_FAB2_LIB.BASEBOARD_FAB2(SCH_1):PAGE38_I34@CHPSET_LIB.SKX_EXT_B(CHIPS)':
 'VCCIO'<40>: CDS_PINID='VCCIO(40)';
NODE_NAME     U5D1 DF13
 '@BASEBOARD_FAB2_LIB.BASEBOARD_FAB2(SCH_1):PAGE38_I34@CHPSET_LIB.SKX_EXT_B(CHIPS)':
 'VCCIO'<41>: CDS_PINID='VCCIO(41)';
NODE_NAME     U5D1 AH9
 '@BASEBOARD_FAB2_LIB.BASEBOARD_FAB2(SCH_1):PAGE38_I34@CHPSET_LIB.SKX_EXT_B(CHIPS)':
 'VCCIO'<42>: CDS_PINID='VCCIO(42)';
NODE_NAME     U5D1 AC4
 '@BASEBOARD_FAB2_LIB.BASEBOARD_FAB2(SCH_1):PAGE38_I34@CHPSET_LIB.SKX_EXT_B(CHIPS)':
 'VCCIO'<43>: CDS_PINID='VCCIO(43)';
NODE_NAME     U5D1 AC20
 '@BASEBOARD_FAB2_LIB.BASEBOARD_FAB2(SCH_1):PAGE38_I34@CHPSET_LIB.SKX_EXT_B(CHIPS)':
 'VCCIO'<44>: CDS_PINID='VCCIO(44)';
NODE_NAME     U5D1 AA10
 '@BASEBOARD_FAB2_LIB.BASEBOARD_FAB2(SCH_1):PAGE38_I34@CHPSET_LIB.SKX_EXT_B(CHIPS)':
 'VCCIO'<45>: CDS_PINID='VCCIO(45)';
NODE_NAME     U5D1 W6
 '@BASEBOARD_FAB2_LIB.BASEBOARD_FAB2(SCH_1):PAGE38_I34@CHPSET_LIB.SKX_EXT_B(CHIPS)':
 'VCCIO'<46>: CDS_PINID='VCCIO(46)';
NODE_NAME     U5D1 W4
 '@BASEBOARD_FAB2_LIB.BASEBOARD_FAB2(SCH_1):PAGE38_I34@CHPSET_LIB.SKX_EXT_B(CHIPS)':
 'VCCIO'<47>: CDS_PINID='VCCIO(47)';
NODE_NAME     U5D1 DF21
 '@BASEBOARD_FAB2_LIB.BASEBOARD_FAB2(SCH_1):PAGE38_I34@CHPSET_LIB.SKX_EXT_B(CHIPS)':
 'VCCIO'<48>: CDS_PINID='VCCIO(48)';
NODE_NAME     U5D1 U14
 '@BASEBOARD_FAB2_LIB.BASEBOARD_FAB2(SCH_1):PAGE38_I34@CHPSET_LIB.SKX_EXT_B(CHIPS)':
 'VCCIO'<49>: CDS_PINID='VCCIO(49)';
NODE_NAME     U5D1 T3
 '@BASEBOARD_FAB2_LIB.BASEBOARD_FAB2(SCH_1):PAGE38_I34@CHPSET_LIB.SKX_EXT_B(CHIPS)':
 'VCCIO'<50>: CDS_PINID='VCCIO(50)';
NODE_NAME     U5D1 P5
 '@BASEBOARD_FAB2_LIB.BASEBOARD_FAB2(SCH_1):PAGE38_I34@CHPSET_LIB.SKX_EXT_B(CHIPS)':
 'VCCIO'<51>: CDS_PINID='VCCIO(51)';
NODE_NAME     U5D1 M21
 '@BASEBOARD_FAB2_LIB.BASEBOARD_FAB2(SCH_1):PAGE38_I34@CHPSET_LIB.SKX_EXT_B(CHIPS)':
 'VCCIO'<52>: CDS_PINID='VCCIO(52)';
NODE_NAME     U5D1 M11
 '@BASEBOARD_FAB2_LIB.BASEBOARD_FAB2(SCH_1):PAGE38_I34@CHPSET_LIB.SKX_EXT_B(CHIPS)':
 'VCCIO'<53>: CDS_PINID='VCCIO(53)';
NODE_NAME     U5D1 DG8
 '@BASEBOARD_FAB2_LIB.BASEBOARD_FAB2(SCH_1):PAGE38_I34@CHPSET_LIB.SKX_EXT_B(CHIPS)':
 'VCCIO'<54>: CDS_PINID='VCCIO(54)';
NODE_NAME     U5D1 DH7
 '@BASEBOARD_FAB2_LIB.BASEBOARD_FAB2(SCH_1):PAGE38_I34@CHPSET_LIB.SKX_EXT_B(CHIPS)':
 'VCCIO'<55>: CDS_PINID='VCCIO(55)';
NODE_NAME     U5D1 L16
 '@BASEBOARD_FAB2_LIB.BASEBOARD_FAB2(SCH_1):PAGE38_I34@CHPSET_LIB.SKX_EXT_B(CHIPS)':
 'VCCIO'<56>: CDS_PINID='VCCIO(56)';
NODE_NAME     U5D1 L14
 '@BASEBOARD_FAB2_LIB.BASEBOARD_FAB2(SCH_1):PAGE38_I34@CHPSET_LIB.SKX_EXT_B(CHIPS)':
 'VCCIO'<57>: CDS_PINID='VCCIO(57)';
NODE_NAME     U5D1 J10
 '@BASEBOARD_FAB2_LIB.BASEBOARD_FAB2(SCH_1):PAGE38_I34@CHPSET_LIB.SKX_EXT_B(CHIPS)':
 'VCCIO'<58>: CDS_PINID='VCCIO(58)';
NODE_NAME     U5D1 H13
 '@BASEBOARD_FAB2_LIB.BASEBOARD_FAB2(SCH_1):PAGE38_I34@CHPSET_LIB.SKX_EXT_B(CHIPS)':
 'VCCIO'<59>: CDS_PINID='VCCIO(59)';
NODE_NAME     U5D1 DJ16
 '@BASEBOARD_FAB2_LIB.BASEBOARD_FAB2(SCH_1):PAGE38_I34@CHPSET_LIB.SKX_EXT_B(CHIPS)':
 'VCCIO'<60>: CDS_PINID='VCCIO(60)';
NODE_NAME     U5D1 DM17
 '@BASEBOARD_FAB2_LIB.BASEBOARD_FAB2(SCH_1):PAGE38_I34@CHPSET_LIB.SKX_EXT_B(CHIPS)':
 'VCCIO'<61>: CDS_PINID='VCCIO(61)';
NODE_NAME     U5D1 DN8
 '@BASEBOARD_FAB2_LIB.BASEBOARD_FAB2(SCH_1):PAGE38_I34@CHPSET_LIB.SKX_EXT_B(CHIPS)':
 'VCCIO'<62>: CDS_PINID='VCCIO(62)';
NODE_NAME     U5D1 DP19
 '@BASEBOARD_FAB2_LIB.BASEBOARD_FAB2(SCH_1):PAGE38_I34@CHPSET_LIB.SKX_EXT_B(CHIPS)':
 'VCCIO'<63>: CDS_PINID='VCCIO(63)';
NODE_NAME     U5D1 DR10
 '@BASEBOARD_FAB2_LIB.BASEBOARD_FAB2(SCH_1):PAGE38_I34@CHPSET_LIB.SKX_EXT_B(CHIPS)':
 'VCCIO'<64>: CDS_PINID='VCCIO(64)';
NODE_NAME     U5D1 DR2
 '@BASEBOARD_FAB2_LIB.BASEBOARD_FAB2(SCH_1):PAGE38_I34@CHPSET_LIB.SKX_EXT_B(CHIPS)':
 'VCCIO'<65>: CDS_PINID='VCCIO(65)';
NODE_NAME     U5D1 DU20
 '@BASEBOARD_FAB2_LIB.BASEBOARD_FAB2(SCH_1):PAGE38_I34@CHPSET_LIB.SKX_EXT_B(CHIPS)':
 'VCCIO'<66>: CDS_PINID='VCCIO(66)';
NODE_NAME     U5D1 EA12
 '@BASEBOARD_FAB2_LIB.BASEBOARD_FAB2(SCH_1):PAGE38_I34@CHPSET_LIB.SKX_EXT_B(CHIPS)':
 'VCCIO'<67>: CDS_PINID='VCCIO(67)';
NODE_NAME     U5D1 EB15
 '@BASEBOARD_FAB2_LIB.BASEBOARD_FAB2(SCH_1):PAGE38_I34@CHPSET_LIB.SKX_EXT_B(CHIPS)':
 'VCCIO'<68>: CDS_PINID='VCCIO(68)';
NODE_NAME     U5D1 J2
 '@BASEBOARD_FAB2_LIB.BASEBOARD_FAB2(SCH_1):PAGE38_I34@CHPSET_LIB.SKX_EXT_B(CHIPS)':
 'VCCIO'<69>: CDS_PINID='VCCIO(69)';
NODE_NAME     U5D1 K15
 '@BASEBOARD_FAB2_LIB.BASEBOARD_FAB2(SCH_1):PAGE38_I34@CHPSET_LIB.SKX_EXT_B(CHIPS)':
 'VCCIO'<70>: CDS_PINID='VCCIO(70)';
NODE_NAME     U5D1 M7
 '@BASEBOARD_FAB2_LIB.BASEBOARD_FAB2(SCH_1):PAGE38_I34@CHPSET_LIB.SKX_EXT_B(CHIPS)':
 'VCCIO'<71>: CDS_PINID='VCCIO(71)';
NODE_NAME     U5D1 M9
 '@BASEBOARD_FAB2_LIB.BASEBOARD_FAB2(SCH_1):PAGE38_I34@CHPSET_LIB.SKX_EXT_B(CHIPS)':
 'VCCIO'<72>: CDS_PINID='VCCIO(72)';
NODE_NAME     U5D1 N18
 '@BASEBOARD_FAB2_LIB.BASEBOARD_FAB2(SCH_1):PAGE38_I34@CHPSET_LIB.SKX_EXT_B(CHIPS)':
 'VCCIO'<73>: CDS_PINID='VCCIO(73)';
NODE_NAME     U5D1 W10
 '@BASEBOARD_FAB2_LIB.BASEBOARD_FAB2(SCH_1):PAGE38_I34@CHPSET_LIB.SKX_EXT_B(CHIPS)':
 'VCCIO'<74>: CDS_PINID='VCCIO(74)';
NODE_NAME     U5D1 BC26
 '@BASEBOARD_FAB2_LIB.BASEBOARD_FAB2(SCH_1):PAGE38_I34@CHPSET_LIB.SKX_EXT_B(CHIPS)':
 'VCCIO'<75>: CDS_PINID='VCCIO(75)';
NODE_NAME     U5D1 BB27
 '@BASEBOARD_FAB2_LIB.BASEBOARD_FAB2(SCH_1):PAGE38_I34@CHPSET_LIB.SKX_EXT_B(CHIPS)':
 'VCCIO'<76>: CDS_PINID='VCCIO(76)';
NODE_NAME     U5D1 BA26
 '@BASEBOARD_FAB2_LIB.BASEBOARD_FAB2(SCH_1):PAGE38_I34@CHPSET_LIB.SKX_EXT_B(CHIPS)':
 'VCCIO'<77>: CDS_PINID='VCCIO(77)';
NODE_NAME     U5D1 AY27
 '@BASEBOARD_FAB2_LIB.BASEBOARD_FAB2(SCH_1):PAGE38_I34@CHPSET_LIB.SKX_EXT_B(CHIPS)':
 'VCCIO'<78>: CDS_PINID='VCCIO(78)';
NODE_NAME     U5D1 AW26
 '@BASEBOARD_FAB2_LIB.BASEBOARD_FAB2(SCH_1):PAGE38_I34@CHPSET_LIB.SKX_EXT_B(CHIPS)':
 'VCCIO'<79>: CDS_PINID='VCCIO(79)';
NODE_NAME     U5D1 AV27
 '@BASEBOARD_FAB2_LIB.BASEBOARD_FAB2(SCH_1):PAGE38_I34@CHPSET_LIB.SKX_EXT_B(CHIPS)':
 'VCCIO'<80>: CDS_PINID='VCCIO(80)';
NODE_NAME     U5D1 CF27
 '@BASEBOARD_FAB2_LIB.BASEBOARD_FAB2(SCH_1):PAGE38_I34@CHPSET_LIB.SKX_EXT_B(CHIPS)':
 'VCCIO'<81>: CDS_PINID='VCCIO(81)';
NODE_NAME     U5D1 CD27
 '@BASEBOARD_FAB2_LIB.BASEBOARD_FAB2(SCH_1):PAGE38_I34@CHPSET_LIB.SKX_EXT_B(CHIPS)':
 'VCCIO'<82>: CDS_PINID='VCCIO(82)';
NODE_NAME     U5D1 CC26
 '@BASEBOARD_FAB2_LIB.BASEBOARD_FAB2(SCH_1):PAGE38_I34@CHPSET_LIB.SKX_EXT_B(CHIPS)':
 'VCCIO'<83>: CDS_PINID='VCCIO(83)';
NODE_NAME     U5D1 CJ28
 '@BASEBOARD_FAB2_LIB.BASEBOARD_FAB2(SCH_1):PAGE38_I34@CHPSET_LIB.SKX_EXT_B(CHIPS)':
 'VCCIO'<84>: CDS_PINID='VCCIO(84)';
NODE_NAME     U5D1 CH27
 '@BASEBOARD_FAB2_LIB.BASEBOARD_FAB2(SCH_1):PAGE38_I34@CHPSET_LIB.SKX_EXT_B(CHIPS)':
 'VCCIO'<85>: CDS_PINID='VCCIO(85)';
NODE_NAME     U5D1 BM27
 '@BASEBOARD_FAB2_LIB.BASEBOARD_FAB2(SCH_1):PAGE38_I34@CHPSET_LIB.SKX_EXT_B(CHIPS)':
 'VCCIO'<86>: CDS_PINID='VCCIO(86)';
NODE_NAME     U5D1 BL26
 '@BASEBOARD_FAB2_LIB.BASEBOARD_FAB2(SCH_1):PAGE38_I34@CHPSET_LIB.SKX_EXT_B(CHIPS)':
 'VCCIO'<87>: CDS_PINID='VCCIO(87)';
NODE_NAME     U5D1 BK27
 '@BASEBOARD_FAB2_LIB.BASEBOARD_FAB2(SCH_1):PAGE38_I34@CHPSET_LIB.SKX_EXT_B(CHIPS)':
 'VCCIO'<88>: CDS_PINID='VCCIO(88)';
NODE_NAME     U5D1 BK25
 '@BASEBOARD_FAB2_LIB.BASEBOARD_FAB2(SCH_1):PAGE38_I34@CHPSET_LIB.SKX_EXT_B(CHIPS)':
 'VCCIO'<89>: CDS_PINID='VCCIO(89)';
NODE_NAME     U5D1 BJ26
 '@BASEBOARD_FAB2_LIB.BASEBOARD_FAB2(SCH_1):PAGE38_I34@CHPSET_LIB.SKX_EXT_B(CHIPS)':
 'VCCIO'<90>: CDS_PINID='VCCIO(90)';
NODE_NAME     U5D1 BH27
 '@BASEBOARD_FAB2_LIB.BASEBOARD_FAB2(SCH_1):PAGE38_I34@CHPSET_LIB.SKX_EXT_B(CHIPS)':
 'VCCIO'<91>: CDS_PINID='VCCIO(91)';
NODE_NAME     U5D1 BH25
 '@BASEBOARD_FAB2_LIB.BASEBOARD_FAB2(SCH_1):PAGE38_I34@CHPSET_LIB.SKX_EXT_B(CHIPS)':
 'VCCIO'<92>: CDS_PINID='VCCIO(92)';
NODE_NAME     U5D1 BG26
 '@BASEBOARD_FAB2_LIB.BASEBOARD_FAB2(SCH_1):PAGE38_I34@CHPSET_LIB.SKX_EXT_B(CHIPS)':
 'VCCIO'<93>: CDS_PINID='VCCIO(93)';
NODE_NAME     U5D1 BF27
 '@BASEBOARD_FAB2_LIB.BASEBOARD_FAB2(SCH_1):PAGE38_I34@CHPSET_LIB.SKX_EXT_B(CHIPS)':
 'VCCIO'<94>: CDS_PINID='VCCIO(94)';
NODE_NAME     U5D1 AE36
 '@BASEBOARD_FAB2_LIB.BASEBOARD_FAB2(SCH_1):PAGE38_I34@CHPSET_LIB.SKX_EXT_B(CHIPS)':
 'VCCIO'<95>: CDS_PINID='VCCIO(95)';
NODE_NAME     U5D1 AD37
 '@BASEBOARD_FAB2_LIB.BASEBOARD_FAB2(SCH_1):PAGE38_I34@CHPSET_LIB.SKX_EXT_B(CHIPS)':
 'VCCIO'<96>: CDS_PINID='VCCIO(96)';
NODE_NAME     U5D1 AC36
 '@BASEBOARD_FAB2_LIB.BASEBOARD_FAB2(SCH_1):PAGE38_I34@CHPSET_LIB.SKX_EXT_B(CHIPS)':
 'VCCIO'<97>: CDS_PINID='VCCIO(97)';
NODE_NAME     U5D1 AF35
 '@BASEBOARD_FAB2_LIB.BASEBOARD_FAB2(SCH_1):PAGE38_I34@CHPSET_LIB.SKX_EXT_B(CHIPS)':
 'VCCIO'<98>: CDS_PINID='VCCIO(98)';
NODE_NAME     U5D1 AD35
 '@BASEBOARD_FAB2_LIB.BASEBOARD_FAB2(SCH_1):PAGE38_I34@CHPSET_LIB.SKX_EXT_B(CHIPS)':
 'VCCIO'<99>: CDS_PINID='VCCIO(99)';
NODE_NAME     U5D1 AE34
 '@BASEBOARD_FAB2_LIB.BASEBOARD_FAB2(SCH_1):PAGE38_I34@CHPSET_LIB.SKX_EXT_B(CHIPS)':
 'VCCIO'<100>: CDS_PINID='VCCIO(100)';
NODE_NAME     U5D1 AG34
 '@BASEBOARD_FAB2_LIB.BASEBOARD_FAB2(SCH_1):PAGE38_I34@CHPSET_LIB.SKX_EXT_B(CHIPS)':
 'VCCIO'<101>: CDS_PINID='VCCIO(101)';
NODE_NAME     U5D1 AM29
 '@BASEBOARD_FAB2_LIB.BASEBOARD_FAB2(SCH_1):PAGE38_I34@CHPSET_LIB.SKX_EXT_B(CHIPS)':
 'VCCIO'<102>: CDS_PINID='VCCIO(102)';
NODE_NAME     U5D1 AL28
 '@BASEBOARD_FAB2_LIB.BASEBOARD_FAB2(SCH_1):PAGE38_I34@CHPSET_LIB.SKX_EXT_B(CHIPS)':
 'VCCIO'<103>: CDS_PINID='VCCIO(103)';
NODE_NAME     U5D1 AR28
 '@BASEBOARD_FAB2_LIB.BASEBOARD_FAB2(SCH_1):PAGE38_I34@CHPSET_LIB.SKX_EXT_B(CHIPS)':
 'VCCIO'<104>: CDS_PINID='VCCIO(104)';
NODE_NAME     U5D1 EE10
 '@BASEBOARD_FAB2_LIB.BASEBOARD_FAB2(SCH_1):PAGE39_I127@CHPSET_LIB.SKX_EXT_B(CHIPS)':
 'VCCIO'<0>: CDS_PINID='VCCIO(0)';
NODE_NAME     U5D1 AE10
 '@BASEBOARD_FAB2_LIB.BASEBOARD_FAB2(SCH_1):PAGE39_I127@CHPSET_LIB.SKX_EXT_B(CHIPS)':
 'VCCIO'<1>: CDS_PINID='VCCIO(1)';
NODE_NAME     U5D1 AF5
 '@BASEBOARD_FAB2_LIB.BASEBOARD_FAB2(SCH_1):PAGE39_I127@CHPSET_LIB.SKX_EXT_B(CHIPS)':
 'VCCIO'<2>: CDS_PINID='VCCIO(2)';
NODE_NAME     U5D1 DV11
 '@BASEBOARD_FAB2_LIB.BASEBOARD_FAB2(SCH_1):PAGE39_I127@CHPSET_LIB.SKX_EXT_B(CHIPS)':
 'VCCIO'<3>: CDS_PINID='VCCIO(3)';
NODE_NAME     U5D1 AM5
 '@BASEBOARD_FAB2_LIB.BASEBOARD_FAB2(SCH_1):PAGE39_I127@CHPSET_LIB.SKX_EXT_B(CHIPS)':
 'VCCIO'<4>: CDS_PINID='VCCIO(4)';
NODE_NAME     U5D1 AT5
 '@BASEBOARD_FAB2_LIB.BASEBOARD_FAB2(SCH_1):PAGE39_I127@CHPSET_LIB.SKX_EXT_B(CHIPS)':
 'VCCIO'<5>: CDS_PINID='VCCIO(5)';
NODE_NAME     U5D1 AT7
 '@BASEBOARD_FAB2_LIB.BASEBOARD_FAB2(SCH_1):PAGE39_I127@CHPSET_LIB.SKX_EXT_B(CHIPS)':
 'VCCIO'<6>: CDS_PINID='VCCIO(6)';
NODE_NAME     U5D1 BE24
 '@BASEBOARD_FAB2_LIB.BASEBOARD_FAB2(SCH_1):PAGE39_I127@CHPSET_LIB.SKX_EXT_B(CHIPS)':
 'VCCIO'<7>: CDS_PINID='VCCIO(7)';
NODE_NAME     U5D1 DK21
 '@BASEBOARD_FAB2_LIB.BASEBOARD_FAB2(SCH_1):PAGE39_I127@CHPSET_LIB.SKX_EXT_B(CHIPS)':
 'VCCIO'<8>: CDS_PINID='VCCIO(8)';
NODE_NAME     U5D1 CF5
 '@BASEBOARD_FAB2_LIB.BASEBOARD_FAB2(SCH_1):PAGE39_I127@CHPSET_LIB.SKX_EXT_B(CHIPS)':
 'VCCIO'<9>: CDS_PINID='VCCIO(9)';
NODE_NAME     U5D1 CG14
 '@BASEBOARD_FAB2_LIB.BASEBOARD_FAB2(SCH_1):PAGE39_I127@CHPSET_LIB.SKX_EXT_B(CHIPS)':
 'VCCIO'<10>: CDS_PINID='VCCIO(10)';
NODE_NAME     U5D1 CL20
 '@BASEBOARD_FAB2_LIB.BASEBOARD_FAB2(SCH_1):PAGE39_I127@CHPSET_LIB.SKX_EXT_B(CHIPS)':
 'VCCIO'<11>: CDS_PINID='VCCIO(11)';
NODE_NAME     U5D1 CP13
 '@BASEBOARD_FAB2_LIB.BASEBOARD_FAB2(SCH_1):PAGE39_I127@CHPSET_LIB.SKX_EXT_B(CHIPS)':
 'VCCIO'<12>: CDS_PINID='VCCIO(12)';
NODE_NAME     U5D1 DE14
 '@BASEBOARD_FAB2_LIB.BASEBOARD_FAB2(SCH_1):PAGE39_I127@CHPSET_LIB.SKX_EXT_B(CHIPS)':
 'VCCIO'<13>: CDS_PINID='VCCIO(13)';
NODE_NAME     U5D1 DC18
 '@BASEBOARD_FAB2_LIB.BASEBOARD_FAB2(SCH_1):PAGE39_I127@CHPSET_LIB.SKX_EXT_B(CHIPS)':
 'VCCIO'<14>: CDS_PINID='VCCIO(14)';
NODE_NAME     U5D1 CY17
 '@BASEBOARD_FAB2_LIB.BASEBOARD_FAB2(SCH_1):PAGE39_I127@CHPSET_LIB.SKX_EXT_B(CHIPS)':
 'VCCIO'<15>: CDS_PINID='VCCIO(15)';
NODE_NAME     U5D1 CU18
 '@BASEBOARD_FAB2_LIB.BASEBOARD_FAB2(SCH_1):PAGE39_I127@CHPSET_LIB.SKX_EXT_B(CHIPS)':
 'VCCIO'<16>: CDS_PINID='VCCIO(16)';
NODE_NAME     U5D1 CV21
 '@BASEBOARD_FAB2_LIB.BASEBOARD_FAB2(SCH_1):PAGE39_I127@CHPSET_LIB.SKX_EXT_B(CHIPS)':
 'VCCIO'<17>: CDS_PINID='VCCIO(17)';
NODE_NAME     U5D1 CU12
 '@BASEBOARD_FAB2_LIB.BASEBOARD_FAB2(SCH_1):PAGE39_I127@CHPSET_LIB.SKX_EXT_B(CHIPS)':
 'VCCIO'<18>: CDS_PINID='VCCIO(18)';
NODE_NAME     U5D1 CN6
 '@BASEBOARD_FAB2_LIB.BASEBOARD_FAB2(SCH_1):PAGE39_I127@CHPSET_LIB.SKX_EXT_B(CHIPS)':
 'VCCIO'<19>: CDS_PINID='VCCIO(19)';
NODE_NAME     C4P1 1
 '@BASEBOARD_FAB2_LIB.BASEBOARD_FAB2(SCH_1):PAGE42_I10@MSTR_DISCRETE.CAP(CHIPS)':
 'A': CDS_PINID='A';
NODE_NAME     C4P9 1
 '@BASEBOARD_FAB2_LIB.BASEBOARD_FAB2(SCH_1):PAGE42_I12@MSTR_DISCRETE.CAP(CHIPS)':
 'A': CDS_PINID='A';
NODE_NAME     C4P10 1
 '@BASEBOARD_FAB2_LIB.BASEBOARD_FAB2(SCH_1):PAGE42_I17@MSTR_DISCRETE.CAP(CHIPS)':
 'A': CDS_PINID='A';
NODE_NAME     C6D7 1
 '@BASEBOARD_FAB2_LIB.BASEBOARD_FAB2(SCH_1):PAGE42_I72@DEV_DISCRETE.CAP_A(CHIPS)':
 'A': CDS_PINID='A';
NODE_NAME     C6D4 1
 '@BASEBOARD_FAB2_LIB.BASEBOARD_FAB2(SCH_1):PAGE42_I74@DEV_DISCRETE.CAP_A(CHIPS)':
 'A': CDS_PINID='A';
NODE_NAME     C6D3 1
 '@BASEBOARD_FAB2_LIB.BASEBOARD_FAB2(SCH_1):PAGE42_I80@DEV_DISCRETE.CAP_A(CHIPS)':
 'A': CDS_PINID='A';
NODE_NAME     C6D6 1
 '@BASEBOARD_FAB2_LIB.BASEBOARD_FAB2(SCH_1):PAGE42_I81@DEV_DISCRETE.CAP_A(CHIPS)':
 'A': CDS_PINID='A';
NODE_NAME     C6D9 1
 '@BASEBOARD_FAB2_LIB.BASEBOARD_FAB2(SCH_1):PAGE42_I145@DEV_DISCRETE.CAP_A(CHIPS)':
 'A': CDS_PINID='A';
NODE_NAME     C6D10 1
 '@BASEBOARD_FAB2_LIB.BASEBOARD_FAB2(SCH_1):PAGE42_I147@DEV_DISCRETE.CAP_A(CHIPS)':
 'A': CDS_PINID='A';
NODE_NAME     C4P6 1
 '@BASEBOARD_FAB2_LIB.BASEBOARD_FAB2(SCH_1):PAGE42_I164@DEV_DISCRETE.CAP_A(CHIPS)':
 'A': CDS_PINID='A';
NODE_NAME     C4P8 1
 '@BASEBOARD_FAB2_LIB.BASEBOARD_FAB2(SCH_1):PAGE42_I178@DEV_DISCRETE.CAP_A(CHIPS)':
 'A': CDS_PINID='A';
NODE_NAME     R5D3 1
 '@BASEBOARD_FAB2_LIB.BASEBOARD_FAB2(SCH_1):PAGE90_I29@MSTR_DISCRETE.RES(CHIPS)':
 'A': CDS_PINID='A';
NODE_NAME     R6D7 1
 '@BASEBOARD_FAB2_LIB.BASEBOARD_FAB2(SCH_1):PAGE90_I31@MSTR_DISCRETE.RES(CHIPS)':
 'A': CDS_PINID='A';
NODE_NAME     R6D13 1
 '@BASEBOARD_FAB2_LIB.BASEBOARD_FAB2(SCH_1):PAGE90_I33@MSTR_DISCRETE.RES(CHIPS)':
 'A': CDS_PINID='A';
NODE_NAME     R6D15 1
 '@BASEBOARD_FAB2_LIB.BASEBOARD_FAB2(SCH_1):PAGE90_I48@MSTR_DISCRETE.RES(CHIPS)':
 'A': CDS_PINID='A';
NODE_NAME     R6D10 1
 '@BASEBOARD_FAB2_LIB.BASEBOARD_FAB2(SCH_1):PAGE90_I49@MSTR_DISCRETE.RES(CHIPS)':
 'A': CDS_PINID='A';
NODE_NAME     R4P14 1
 '@BASEBOARD_FAB2_LIB.BASEBOARD_FAB2(SCH_1):PAGE90_I53@MSTR_DISCRETE.RES(CHIPS)':
 'A': CDS_PINID='A';
NODE_NAME     R7E2 1
 '@BASEBOARD_FAB2_LIB.BASEBOARD_FAB2(SCH_1):PAGE92_I19@MSTR_DISCRETE.RES(CHIPS)':
 'A': CDS_PINID='A';
NODE_NAME     R6D9 1
 '@BASEBOARD_FAB2_LIB.BASEBOARD_FAB2(SCH_1):PAGE92_I64@MSTR_DISCRETE.RES(CHIPS)':
 'A': CDS_PINID='A';
NODE_NAME     R7P27 1
 '@BASEBOARD_FAB2_LIB.BASEBOARD_FAB2(SCH_1):PAGE92_I65@MSTR_DISCRETE.RES(CHIPS)':
 'A': CDS_PINID='A';
NODE_NAME     R2T37 1
 '@BASEBOARD_FAB2_LIB.BASEBOARD_FAB2(SCH_1):PAGE92_I94@MSTR_DISCRETE.RES(CHIPS)':
 'A': CDS_PINID='A';
NODE_NAME     R7P18 1
 '@BASEBOARD_FAB2_LIB.BASEBOARD_FAB2(SCH_1):PAGE92_I100@MSTR_DISCRETE.RES(CHIPS)':
 'A': CDS_PINID='A';
NODE_NAME     R4R2 1
 '@BASEBOARD_FAB2_LIB.BASEBOARD_FAB2(SCH_1):PAGE92_I101@MSTR_DISCRETE.RES(CHIPS)':
 'A': CDS_PINID='A';
NODE_NAME     R2T19 1
 '@BASEBOARD_FAB2_LIB.BASEBOARD_FAB2(SCH_1):PAGE93_I63@MSTR_DISCRETE.RES(CHIPS)':
 'A': CDS_PINID='A';
NODE_NAME     R4R3 1
 '@BASEBOARD_FAB2_LIB.BASEBOARD_FAB2(SCH_1):PAGE93_I79@MSTR_DISCRETE.RES(CHIPS)':
 'A': CDS_PINID='A';
NODE_NAME     R2T26 1
 '@BASEBOARD_FAB2_LIB.BASEBOARD_FAB2(SCH_1):PAGE93_I87@MSTR_DISCRETE.RES(CHIPS)':
 'A': CDS_PINID='A';
NODE_NAME     R2T72 1
 '@BASEBOARD_FAB2_LIB.BASEBOARD_FAB2(SCH_1):PAGE93_I143@MSTR_DISCRETE.RES(CHIPS)':
 'A': CDS_PINID='A';
NODE_NAME     R6D12 1
 '@BASEBOARD_FAB2_LIB.BASEBOARD_FAB2(SCH_1):PAGE96_I2@MSTR_DISCRETE.RES(CHIPS)':
 'A': CDS_PINID='A';
NODE_NAME     R6D8 1
 '@BASEBOARD_FAB2_LIB.BASEBOARD_FAB2(SCH_1):PAGE96_I3@MSTR_DISCRETE.RES(CHIPS)':
 'A': CDS_PINID='A';
NODE_NAME     R4R4 1
 '@BASEBOARD_FAB2_LIB.BASEBOARD_FAB2(SCH_1):PAGE97_I42@MSTR_DISCRETE.RES(CHIPS)':
 'A': CDS_PINID='A';
NODE_NAME     R7P20 1
 '@BASEBOARD_FAB2_LIB.BASEBOARD_FAB2(SCH_1):PAGE97_I44@MSTR_DISCRETE.RES(CHIPS)':
 'A': CDS_PINID='A';
NODE_NAME     R4P21 1
 '@BASEBOARD_FAB2_LIB.BASEBOARD_FAB2(SCH_1):PAGE97_I72@MSTR_DISCRETE.RES(CHIPS)':
 'A': CDS_PINID='A';
NODE_NAME     C6F2 1
 '@BASEBOARD_FAB2_LIB.BASEBOARD_FAB2(SCH_1):PAGE99_I2@DEV_DISCRETE.CAP_A(CHIPS)':
 'A': CDS_PINID='A';
NODE_NAME     U6F1 1
 '@BASEBOARD_FAB2_LIB.BASEBOARD_FAB2(SCH_1):PAGE99_I15@MSTR_DIGITAL.PCA9617(CHIPS)':
 'VCCA': CDS_PINID='VCCA';
NODE_NAME     R4T6 1
 '@BASEBOARD_FAB2_LIB.BASEBOARD_FAB2(SCH_1):PAGE99_I17@MSTR_DISCRETE.RES(CHIPS)':
 'A': CDS_PINID='A';
NODE_NAME     R4T5 1
 '@BASEBOARD_FAB2_LIB.BASEBOARD_FAB2(SCH_1):PAGE99_I19@MSTR_DISCRETE.RES(CHIPS)':
 'A': CDS_PINID='A';
NODE_NAME     C7E1 1
 '@BASEBOARD_FAB2_LIB.BASEBOARD_FAB2(SCH_1):PAGE99_I23@DEV_DISCRETE.CAP_A(CHIPS)':
 'A': CDS_PINID='A';
NODE_NAME     U7E1 1
 '@BASEBOARD_FAB2_LIB.BASEBOARD_FAB2(SCH_1):PAGE99_I61@MSTR_DIGITAL.PCA9617(CHIPS)':
 'VCCA': CDS_PINID='VCCA';
NODE_NAME     R3R13 1
 '@BASEBOARD_FAB2_LIB.BASEBOARD_FAB2(SCH_1):PAGE99_I65@MSTR_DISCRETE.RES(CHIPS)':
 'A': CDS_PINID='A';
NODE_NAME     R3P60 1
 '@BASEBOARD_FAB2_LIB.BASEBOARD_FAB2(SCH_1):PAGE99_I67@MSTR_DISCRETE.RES(CHIPS)':
 'A': CDS_PINID='A';
NODE_NAME     R9A4 2
 '@BASEBOARD_FAB2_LIB.BASEBOARD_FAB2(SCH_1):PAGE111_I55@MSTR_DISCRETE.RES(CHIPS)':
 'B': CDS_PINID='B';
NODE_NAME     R1L17 2
 '@BASEBOARD_FAB2_LIB.BASEBOARD_FAB2(SCH_1):PAGE111_I56@MSTR_DISCRETE.RES(CHIPS)':
 'B': CDS_PINID='B';
NODE_NAME     R6P46 1
 '@BASEBOARD_FAB2_LIB.BASEBOARD_FAB2(SCH_1):PAGE112_I49@MSTR_DISCRETE.RES(CHIPS)':
 'A': CDS_PINID='A';
NODE_NAME     R7P30 1
 '@BASEBOARD_FAB2_LIB.BASEBOARD_FAB2(SCH_1):PAGE112_I50@MSTR_DISCRETE.RES(CHIPS)':
 'A': CDS_PINID='A';
NODE_NAME     R1M3 1
 '@BASEBOARD_FAB2_LIB.BASEBOARD_FAB2(SCH_1):PAGE112_I51@MSTR_DISCRETE.RES(CHIPS)':
 'A': CDS_PINID='A';
NODE_NAME     R4P15 1
 '@BASEBOARD_FAB2_LIB.BASEBOARD_FAB2(SCH_1):PAGE112_I53@MSTR_DISCRETE.RES(CHIPS)':
 'A': CDS_PINID='A';
NODE_NAME     R1M4 1
 '@BASEBOARD_FAB2_LIB.BASEBOARD_FAB2(SCH_1):PAGE112_I54@MSTR_DISCRETE.RES(CHIPS)':
 'A': CDS_PINID='A';
NODE_NAME     R4P12 1
 '@BASEBOARD_FAB2_LIB.BASEBOARD_FAB2(SCH_1):PAGE112_I57@MSTR_DISCRETE.RES(CHIPS)':
 'A': CDS_PINID='A';
NODE_NAME     R4P23 1
 '@BASEBOARD_FAB2_LIB.BASEBOARD_FAB2(SCH_1):PAGE112_I58@MSTR_DISCRETE.RES(CHIPS)':
 'A': CDS_PINID='A';
NODE_NAME     R4P24 1
 '@BASEBOARD_FAB2_LIB.BASEBOARD_FAB2(SCH_1):PAGE112_I59@MSTR_DISCRETE.RES(CHIPS)':
 'A': CDS_PINID='A';
NODE_NAME     R1L15 1
 '@BASEBOARD_FAB2_LIB.BASEBOARD_FAB2(SCH_1):PAGE112_I60@MSTR_DISCRETE.RES(CHIPS)':
 'A': CDS_PINID='A';
NODE_NAME     R6T9 1
 '@BASEBOARD_FAB2_LIB.BASEBOARD_FAB2(SCH_1):PAGE112_I120@MSTR_DISCRETE.RES(CHIPS)':
 'A': CDS_PINID='A';
NODE_NAME     R6T8 1
 '@BASEBOARD_FAB2_LIB.BASEBOARD_FAB2(SCH_1):PAGE112_I121@MSTR_DISCRETE.RES(CHIPS)':
 'A': CDS_PINID='A';
NODE_NAME     R2U40 1
 '@BASEBOARD_FAB2_LIB.BASEBOARD_FAB2(SCH_1):PAGE152_I53@MSTR_DISCRETE.RES(CHIPS)':
 'A': CDS_PINID='A';
NODE_NAME     R2U41 1
 '@BASEBOARD_FAB2_LIB.BASEBOARD_FAB2(SCH_1):PAGE152_I54@MSTR_DISCRETE.RES(CHIPS)':
 'A': CDS_PINID='A';
NODE_NAME     R4P17 2
 '@BASEBOARD_FAB2_LIB.BASEBOARD_FAB2(SCH_1):PAGE152_I58@MSTR_DISCRETE.RES(CHIPS)':
 'B': CDS_PINID='B';
NODE_NAME     R4P20 2
 '@BASEBOARD_FAB2_LIB.BASEBOARD_FAB2(SCH_1):PAGE152_I59@MSTR_DISCRETE.RES(CHIPS)':
 'B': CDS_PINID='B';
NODE_NAME     R7C17 1
 '@BASEBOARD_FAB2_LIB.BASEBOARD_FAB2(SCH_1):PAGE166_I28@MSTR_DISCRETE.RES(CHIPS)':
 'A': CDS_PINID='A';
NODE_NAME     J6B1 F1
 '@BASEBOARD_FAB2_LIB.BASEBOARD_FAB2(SCH_1):PAGE194_I56@MSTR_SCONN.SCONN120_H61426002(CHIPS)':
 'IOF1': CDS_PINID='IOF1';
NODE_NAME     R6P16 1
 '@BASEBOARD_FAB2_LIB.BASEBOARD_FAB2(SCH_1):PAGE201_I132@MSTR_DISCRETE.RES(CHIPS)':
 'A': CDS_PINID='A';
NODE_NAME     C3N35 1
 '@BASEBOARD_FAB2_LIB.BASEBOARD_FAB2(SCH_1):PAGE212_I18@MSTR_DISCRETE.CAPP(CHIPS)':
 'A': CDS_PINID='A';
NODE_NAME     C7C6 1
 '@BASEBOARD_FAB2_LIB.BASEBOARD_FAB2(SCH_1):PAGE212_I23@DEV_DISCRETE.CAP_A(CHIPS)':
 'A': CDS_PINID='A';
NODE_NAME     R3N21 2
 '@BASEBOARD_FAB2_LIB.BASEBOARD_FAB2(SCH_1):PAGE212_I74@MSTR_DISCRETE.RES(CHIPS)':
 'B': CDS_PINID='B';
NODE_NAME     C7C10 1
 '@BASEBOARD_FAB2_LIB.BASEBOARD_FAB2(SCH_1):PAGE212_I77@DEV_DISCRETE.CAP_A(CHIPS)':
 'A': CDS_PINID='A';
NODE_NAME     R7C3 1
 '@BASEBOARD_FAB2_LIB.BASEBOARD_FAB2(SCH_1):PAGE212_I78@MSTR_DISCRETE.RES(CHIPS)':
 'A': CDS_PINID='A';
NODE_NAME     EU7C1 1
 '@BASEBOARD_FAB2_LIB.BASEBOARD_FAB2(SCH_1):PAGE212_I101@MSTR_DISCRETE.IR354XX(CHIPS)':
 'VOS': CDS_PINID='VOS';
NODE_NAME     C1T21 1
 '@BASEBOARD_FAB2_LIB.BASEBOARD_FAB2(SCH_1):PAGE148_I20@DEV_DISCRETE.CAP_A(CHIPS)':
 'A': CDS_PINID='A';
NODE_NAME     R9W19 1
 '@BASEBOARD_FAB2_LIB.BASEBOARD_FAB2(SCH_1):PAGE248_I26@MSTR_DISCRETE.RES(CHIPS)':
 'A': CDS_PINID='A';
NODE_NAME     R9W18 1
 '@BASEBOARD_FAB2_LIB.BASEBOARD_FAB2(SCH_1):PAGE248_I27@MSTR_DISCRETE.RES(CHIPS)':
 'A': CDS_PINID='A';
NODE_NAME     C9W8 1
 '@BASEBOARD_FAB2_LIB.BASEBOARD_FAB2(SCH_1):PAGE248_I30@DEV_DISCRETE.CAP_A(CHIPS)':
 'A': CDS_PINID='A';
NODE_NAME     U1W2 1
 '@BASEBOARD_FAB2_LIB.BASEBOARD_FAB2(SCH_1):PAGE248_I49@W_HDL.TCA9517DGKR-GP(CHIPS)':
 'VCCA': CDS_PINID='VCCA';
NODE_NAME     R5D4 1
 '@BASEBOARD_FAB2_LIB.BASEBOARD_FAB2(SCH_1):PAGE90_I96@MSTR_DISCRETE.RES(CHIPS)':
 'A': CDS_PINID='A';
NODE_NAME     L7C2 2
 '@BASEBOARD_FAB2_LIB.BASEBOARD_FAB2(SCH_1):PAGE212_I141@W_HDL.IND-150NH-56-GP(CHIPS)':
 'F': CDS_PINID='F';
NODE_NAME     R3U2 1
 '@BASEBOARD_FAB2_LIB.BASEBOARD_FAB2(SCH_1):PAGE215_I58@MSTR_DISCRETE.RES(CHIPS)':
 'A': CDS_PINID='A';
NODE_NAME     R3L11 1
 '@BASEBOARD_FAB2_LIB.BASEBOARD_FAB2(SCH_1):PAGE218_I67@MSTR_DISCRETE.RES(CHIPS)':
 'A': CDS_PINID='A';
NODE_NAME     R25W155 1
 '@BASEBOARD_FAB2_LIB.BASEBOARD_FAB2(SCH_1):PAGE148_I29@MSTR_DISCRETE.RES(CHIPS)':
 'A': CDS_PINID='A';
NODE_NAME     R4E9 1
 '@BASEBOARD_FAB2_LIB.BASEBOARD_FAB2(SCH_1):PAGE201_I189@MSTR_DISCRETE.RES(CHIPS)':
 'A': CDS_PINID='A';
NODE_NAME     R4E10 1
 '@BASEBOARD_FAB2_LIB.BASEBOARD_FAB2(SCH_1):PAGE201_I190@MSTR_DISCRETE.RES(CHIPS)':
 'A': CDS_PINID='A';
NODE_NAME     R3P17 1
 '@BASEBOARD_FAB2_LIB.BASEBOARD_FAB2(SCH_1):PAGE211_I99@MSTR_DISCRETE.RES(CHIPS)':
 'A': CDS_PINID='A';
NODE_NAME     R3P13 1
 '@BASEBOARD_FAB2_LIB.BASEBOARD_FAB2(SCH_1):PAGE211_I100@MSTR_DISCRETE.RES(CHIPS)':
 'A': CDS_PINID='A';
NODE_NAME     R3T11 1
 '@BASEBOARD_FAB2_LIB.BASEBOARD_FAB2(SCH_1):PAGE215_I70@MSTR_DISCRETE.RES(CHIPS)':
 'A': CDS_PINID='A';
NODE_NAME     R3L13 1
 '@BASEBOARD_FAB2_LIB.BASEBOARD_FAB2(SCH_1):PAGE218_I70@MSTR_DISCRETE.RES(CHIPS)':
 'A': CDS_PINID='A';
NODE_NAME     R7W4 1
 '@BASEBOARD_FAB2_LIB.BASEBOARD_FAB2(SCH_1):PAGE92_I106@MSTR_DISCRETE.RES(CHIPS)':
 'A': CDS_PINID='A';
NODE_NAME     R3W10 1
 '@BASEBOARD_FAB2_LIB.BASEBOARD_FAB2(SCH_1):PAGE92_I108@MSTR_DISCRETE.RES(CHIPS)':
 'A': CDS_PINID='A';
NODE_NAME     R2W2 1
 '@BASEBOARD_FAB2_LIB.BASEBOARD_FAB2(SCH_1):PAGE93_I147@MSTR_DISCRETE.RES(CHIPS)':
 'A': CDS_PINID='A';
NODE_NAME     R1W35 1
 '@BASEBOARD_FAB2_LIB.BASEBOARD_FAB2(SCH_1):PAGE152_I105@MSTR_DISCRETE.RES(CHIPS)':
 'A': CDS_PINID='A';
NODE_NAME     C3N26 1
 '@BASEBOARD_FAB2_LIB.BASEBOARD_FAB2(SCH_1):PAGE212_I145@MSTR_DISCRETE.CAPP(CHIPS)':
 'A': CDS_PINID='A';
NODE_NAME     C3N38 1
 '@BASEBOARD_FAB2_LIB.BASEBOARD_FAB2(SCH_1):PAGE212_I146@MSTR_DISCRETE.CAPP(CHIPS)':
 'A': CDS_PINID='A';
NET_NAME
'PVCCIO_CPU0_R'
 '@BASEBOARD_FAB2_LIB.BASEBOARD_FAB2(SCH_1):PVCCIO_CPU0_R':
 C_SIGNAL='@baseboard_fab2_lib.baseboard_fab2(sch_1):pvccio_cpu0_r';
NODE_NAME     U25W4 AA17
 '@BASEBOARD_FAB2_LIB.BASEBOARD_FAB2(SCH_1):PAGE148_I28@W_HDL.AST2520A1-GP-GP(CHIPS)':
 'PECIVDD': CDS_PINID='PECIVDD';
NODE_NAME     R25W155 2
 '@BASEBOARD_FAB2_LIB.BASEBOARD_FAB2(SCH_1):PAGE148_I29@MSTR_DISCRETE.RES(CHIPS)':
 'B': CDS_PINID='B';
NET_NAME
'PVCCIO_CPU1'
 '@BASEBOARD_FAB2_LIB.BASEBOARD_FAB2(SCH_1):PVCCIO_CPU1':
 C_SIGNAL='@baseboard_fab2_lib.baseboard_fab2(sch_1):pvccio_cpu1';
NODE_NAME     R9N1 1
 '@BASEBOARD_FAB2_LIB.BASEBOARD_FAB2(SCH_1):PAGE55_I4@MSTR_DISCRETE.RES(CHIPS)':
 'A': CDS_PINID='A';
NODE_NAME     R9N2 1
 '@BASEBOARD_FAB2_LIB.BASEBOARD_FAB2(SCH_1):PAGE55_I7@MSTR_DISCRETE.RES(CHIPS)':
 'A': CDS_PINID='A';
NODE_NAME     R3B2 2
 '@BASEBOARD_FAB2_LIB.BASEBOARD_FAB2(SCH_1):PAGE55_I19@MSTR_DISCRETE.RES(CHIPS)':
 'B': CDS_PINID='B';
NODE_NAME     R3B4 2
 '@BASEBOARD_FAB2_LIB.BASEBOARD_FAB2(SCH_1):PAGE55_I21@MSTR_DISCRETE.RES(CHIPS)':
 'B': CDS_PINID='B';
NODE_NAME     R3D32 1
 '@BASEBOARD_FAB2_LIB.BASEBOARD_FAB2(SCH_1):PAGE71_I53@MSTR_DISCRETE.RES(CHIPS)':
 'A': CDS_PINID='A';
NODE_NAME     U2D1 CM15
 '@BASEBOARD_FAB2_LIB.BASEBOARD_FAB2(SCH_1):PAGE72_I33@CHPSET_LIB.SKX_EXT_B(CHIPS)':
 'VCCIO'<20>: CDS_PINID='VCCIO(20)';
NODE_NAME     U2D1 CL12
 '@BASEBOARD_FAB2_LIB.BASEBOARD_FAB2(SCH_1):PAGE72_I33@CHPSET_LIB.SKX_EXT_B(CHIPS)':
 'VCCIO'<21>: CDS_PINID='VCCIO(21)';
NODE_NAME     U2D1 CK5
 '@BASEBOARD_FAB2_LIB.BASEBOARD_FAB2(SCH_1):PAGE72_I33@CHPSET_LIB.SKX_EXT_B(CHIPS)':
 'VCCIO'<22>: CDS_PINID='VCCIO(22)';
NODE_NAME     U2D1 CV7
 '@BASEBOARD_FAB2_LIB.BASEBOARD_FAB2(SCH_1):PAGE72_I33@CHPSET_LIB.SKX_EXT_B(CHIPS)':
 'VCCIO'<23>: CDS_PINID='VCCIO(23)';
NODE_NAME     U2D1 CH9
 '@BASEBOARD_FAB2_LIB.BASEBOARD_FAB2(SCH_1):PAGE72_I33@CHPSET_LIB.SKX_EXT_B(CHIPS)':
 'VCCIO'<24>: CDS_PINID='VCCIO(24)';
NODE_NAME     U2D1 D7
 '@BASEBOARD_FAB2_LIB.BASEBOARD_FAB2(SCH_1):PAGE72_I33@CHPSET_LIB.SKX_EXT_B(CHIPS)':
 'VCCIO'<25>: CDS_PINID='VCCIO(25)';
NODE_NAME     U2D1 CE18
 '@BASEBOARD_FAB2_LIB.BASEBOARD_FAB2(SCH_1):PAGE72_I33@CHPSET_LIB.SKX_EXT_B(CHIPS)':
 'VCCIO'<26>: CDS_PINID='VCCIO(26)';
NODE_NAME     U2D1 CD9
 '@BASEBOARD_FAB2_LIB.BASEBOARD_FAB2(SCH_1):PAGE72_I33@CHPSET_LIB.SKX_EXT_B(CHIPS)':
 'VCCIO'<27>: CDS_PINID='VCCIO(27)';
NODE_NAME     U2D1 CB17
 '@BASEBOARD_FAB2_LIB.BASEBOARD_FAB2(SCH_1):PAGE72_I33@CHPSET_LIB.SKX_EXT_B(CHIPS)':
 'VCCIO'<28>: CDS_PINID='VCCIO(28)';
NODE_NAME     U2D1 CB13
 '@BASEBOARD_FAB2_LIB.BASEBOARD_FAB2(SCH_1):PAGE72_I33@CHPSET_LIB.SKX_EXT_B(CHIPS)':
 'VCCIO'<29>: CDS_PINID='VCCIO(29)';
NODE_NAME     U2D1 BP25
 '@BASEBOARD_FAB2_LIB.BASEBOARD_FAB2(SCH_1):PAGE72_I33@CHPSET_LIB.SKX_EXT_B(CHIPS)':
 'VCCIO'<30>: CDS_PINID='VCCIO(30)';
NODE_NAME     U2D1 BJ24
 '@BASEBOARD_FAB2_LIB.BASEBOARD_FAB2(SCH_1):PAGE72_I33@CHPSET_LIB.SKX_EXT_B(CHIPS)':
 'VCCIO'<31>: CDS_PINID='VCCIO(31)';
NODE_NAME     U2D1 BF23
 '@BASEBOARD_FAB2_LIB.BASEBOARD_FAB2(SCH_1):PAGE72_I33@CHPSET_LIB.SKX_EXT_B(CHIPS)':
 'VCCIO'<32>: CDS_PINID='VCCIO(32)';
NODE_NAME     U2D1 DA14
 '@BASEBOARD_FAB2_LIB.BASEBOARD_FAB2(SCH_1):PAGE72_I33@CHPSET_LIB.SKX_EXT_B(CHIPS)':
 'VCCIO'<33>: CDS_PINID='VCCIO(33)';
NODE_NAME     U2D1 BB5
 '@BASEBOARD_FAB2_LIB.BASEBOARD_FAB2(SCH_1):PAGE72_I33@CHPSET_LIB.SKX_EXT_B(CHIPS)':
 'VCCIO'<34>: CDS_PINID='VCCIO(34)';
NODE_NAME     U2D1 BA24
 '@BASEBOARD_FAB2_LIB.BASEBOARD_FAB2(SCH_1):PAGE72_I33@CHPSET_LIB.SKX_EXT_B(CHIPS)':
 'VCCIO'<35>: CDS_PINID='VCCIO(35)';
NODE_NAME     U2D1 AY11
 '@BASEBOARD_FAB2_LIB.BASEBOARD_FAB2(SCH_1):PAGE72_I33@CHPSET_LIB.SKX_EXT_B(CHIPS)':
 'VCCIO'<36>: CDS_PINID='VCCIO(36)';
NODE_NAME     U2D1 AW6
 '@BASEBOARD_FAB2_LIB.BASEBOARD_FAB2(SCH_1):PAGE72_I33@CHPSET_LIB.SKX_EXT_B(CHIPS)':
 'VCCIO'<37>: CDS_PINID='VCCIO(37)';
NODE_NAME     U2D1 AT11
 '@BASEBOARD_FAB2_LIB.BASEBOARD_FAB2(SCH_1):PAGE72_I33@CHPSET_LIB.SKX_EXT_B(CHIPS)':
 'VCCIO'<38>: CDS_PINID='VCCIO(38)';
NODE_NAME     U2D1 DD7
 '@BASEBOARD_FAB2_LIB.BASEBOARD_FAB2(SCH_1):PAGE72_I33@CHPSET_LIB.SKX_EXT_B(CHIPS)':
 'VCCIO'<39>: CDS_PINID='VCCIO(39)';
NODE_NAME     U2D1 AN10
 '@BASEBOARD_FAB2_LIB.BASEBOARD_FAB2(SCH_1):PAGE72_I33@CHPSET_LIB.SKX_EXT_B(CHIPS)':
 'VCCIO'<40>: CDS_PINID='VCCIO(40)';
NODE_NAME     U2D1 DF13
 '@BASEBOARD_FAB2_LIB.BASEBOARD_FAB2(SCH_1):PAGE72_I33@CHPSET_LIB.SKX_EXT_B(CHIPS)':
 'VCCIO'<41>: CDS_PINID='VCCIO(41)';
NODE_NAME     U2D1 AH9
 '@BASEBOARD_FAB2_LIB.BASEBOARD_FAB2(SCH_1):PAGE72_I33@CHPSET_LIB.SKX_EXT_B(CHIPS)':
 'VCCIO'<42>: CDS_PINID='VCCIO(42)';
NODE_NAME     U2D1 AC4
 '@BASEBOARD_FAB2_LIB.BASEBOARD_FAB2(SCH_1):PAGE72_I33@CHPSET_LIB.SKX_EXT_B(CHIPS)':
 'VCCIO'<43>: CDS_PINID='VCCIO(43)';
NODE_NAME     U2D1 AC20
 '@BASEBOARD_FAB2_LIB.BASEBOARD_FAB2(SCH_1):PAGE72_I33@CHPSET_LIB.SKX_EXT_B(CHIPS)':
 'VCCIO'<44>: CDS_PINID='VCCIO(44)';
NODE_NAME     U2D1 AA10
 '@BASEBOARD_FAB2_LIB.BASEBOARD_FAB2(SCH_1):PAGE72_I33@CHPSET_LIB.SKX_EXT_B(CHIPS)':
 'VCCIO'<45>: CDS_PINID='VCCIO(45)';
NODE_NAME     U2D1 W6
 '@BASEBOARD_FAB2_LIB.BASEBOARD_FAB2(SCH_1):PAGE72_I33@CHPSET_LIB.SKX_EXT_B(CHIPS)':
 'VCCIO'<46>: CDS_PINID='VCCIO(46)';
NODE_NAME     U2D1 W4
 '@BASEBOARD_FAB2_LIB.BASEBOARD_FAB2(SCH_1):PAGE72_I33@CHPSET_LIB.SKX_EXT_B(CHIPS)':
 'VCCIO'<47>: CDS_PINID='VCCIO(47)';
NODE_NAME     U2D1 DF21
 '@BASEBOARD_FAB2_LIB.BASEBOARD_FAB2(SCH_1):PAGE72_I33@CHPSET_LIB.SKX_EXT_B(CHIPS)':
 'VCCIO'<48>: CDS_PINID='VCCIO(48)';
NODE_NAME     U2D1 U14
 '@BASEBOARD_FAB2_LIB.BASEBOARD_FAB2(SCH_1):PAGE72_I33@CHPSET_LIB.SKX_EXT_B(CHIPS)':
 'VCCIO'<49>: CDS_PINID='VCCIO(49)';
NODE_NAME     U2D1 T3
 '@BASEBOARD_FAB2_LIB.BASEBOARD_FAB2(SCH_1):PAGE72_I33@CHPSET_LIB.SKX_EXT_B(CHIPS)':
 'VCCIO'<50>: CDS_PINID='VCCIO(50)';
NODE_NAME     U2D1 P5
 '@BASEBOARD_FAB2_LIB.BASEBOARD_FAB2(SCH_1):PAGE72_I33@CHPSET_LIB.SKX_EXT_B(CHIPS)':
 'VCCIO'<51>: CDS_PINID='VCCIO(51)';
NODE_NAME     U2D1 M21
 '@BASEBOARD_FAB2_LIB.BASEBOARD_FAB2(SCH_1):PAGE72_I33@CHPSET_LIB.SKX_EXT_B(CHIPS)':
 'VCCIO'<52>: CDS_PINID='VCCIO(52)';
NODE_NAME     U2D1 M11
 '@BASEBOARD_FAB2_LIB.BASEBOARD_FAB2(SCH_1):PAGE72_I33@CHPSET_LIB.SKX_EXT_B(CHIPS)':
 'VCCIO'<53>: CDS_PINID='VCCIO(53)';
NODE_NAME     U2D1 DG8
 '@BASEBOARD_FAB2_LIB.BASEBOARD_FAB2(SCH_1):PAGE72_I33@CHPSET_LIB.SKX_EXT_B(CHIPS)':
 'VCCIO'<54>: CDS_PINID='VCCIO(54)';
NODE_NAME     U2D1 DH7
 '@BASEBOARD_FAB2_LIB.BASEBOARD_FAB2(SCH_1):PAGE72_I33@CHPSET_LIB.SKX_EXT_B(CHIPS)':
 'VCCIO'<55>: CDS_PINID='VCCIO(55)';
NODE_NAME     U2D1 L16
 '@BASEBOARD_FAB2_LIB.BASEBOARD_FAB2(SCH_1):PAGE72_I33@CHPSET_LIB.SKX_EXT_B(CHIPS)':
 'VCCIO'<56>: CDS_PINID='VCCIO(56)';
NODE_NAME     U2D1 L14
 '@BASEBOARD_FAB2_LIB.BASEBOARD_FAB2(SCH_1):PAGE72_I33@CHPSET_LIB.SKX_EXT_B(CHIPS)':
 'VCCIO'<57>: CDS_PINID='VCCIO(57)';
NODE_NAME     U2D1 J10
 '@BASEBOARD_FAB2_LIB.BASEBOARD_FAB2(SCH_1):PAGE72_I33@CHPSET_LIB.SKX_EXT_B(CHIPS)':
 'VCCIO'<58>: CDS_PINID='VCCIO(58)';
NODE_NAME     U2D1 H13
 '@BASEBOARD_FAB2_LIB.BASEBOARD_FAB2(SCH_1):PAGE72_I33@CHPSET_LIB.SKX_EXT_B(CHIPS)':
 'VCCIO'<59>: CDS_PINID='VCCIO(59)';
NODE_NAME     U2D1 DJ16
 '@BASEBOARD_FAB2_LIB.BASEBOARD_FAB2(SCH_1):PAGE72_I33@CHPSET_LIB.SKX_EXT_B(CHIPS)':
 'VCCIO'<60>: CDS_PINID='VCCIO(60)';
NODE_NAME     U2D1 DM17
 '@BASEBOARD_FAB2_LIB.BASEBOARD_FAB2(SCH_1):PAGE72_I33@CHPSET_LIB.SKX_EXT_B(CHIPS)':
 'VCCIO'<61>: CDS_PINID='VCCIO(61)';
NODE_NAME     U2D1 DN8
 '@BASEBOARD_FAB2_LIB.BASEBOARD_FAB2(SCH_1):PAGE72_I33@CHPSET_LIB.SKX_EXT_B(CHIPS)':
 'VCCIO'<62>: CDS_PINID='VCCIO(62)';
NODE_NAME     U2D1 DP19
 '@BASEBOARD_FAB2_LIB.BASEBOARD_FAB2(SCH_1):PAGE72_I33@CHPSET_LIB.SKX_EXT_B(CHIPS)':
 'VCCIO'<63>: CDS_PINID='VCCIO(63)';
NODE_NAME     U2D1 DR10
 '@BASEBOARD_FAB2_LIB.BASEBOARD_FAB2(SCH_1):PAGE72_I33@CHPSET_LIB.SKX_EXT_B(CHIPS)':
 'VCCIO'<64>: CDS_PINID='VCCIO(64)';
NODE_NAME     U2D1 DR2
 '@BASEBOARD_FAB2_LIB.BASEBOARD_FAB2(SCH_1):PAGE72_I33@CHPSET_LIB.SKX_EXT_B(CHIPS)':
 'VCCIO'<65>: CDS_PINID='VCCIO(65)';
NODE_NAME     U2D1 DU20
 '@BASEBOARD_FAB2_LIB.BASEBOARD_FAB2(SCH_1):PAGE72_I33@CHPSET_LIB.SKX_EXT_B(CHIPS)':
 'VCCIO'<66>: CDS_PINID='VCCIO(66)';
NODE_NAME     U2D1 EA12
 '@BASEBOARD_FAB2_LIB.BASEBOARD_FAB2(SCH_1):PAGE72_I33@CHPSET_LIB.SKX_EXT_B(CHIPS)':
 'VCCIO'<67>: CDS_PINID='VCCIO(67)';
NODE_NAME     U2D1 EB15
 '@BASEBOARD_FAB2_LIB.BASEBOARD_FAB2(SCH_1):PAGE72_I33@CHPSET_LIB.SKX_EXT_B(CHIPS)':
 'VCCIO'<68>: CDS_PINID='VCCIO(68)';
NODE_NAME     U2D1 J2
 '@BASEBOARD_FAB2_LIB.BASEBOARD_FAB2(SCH_1):PAGE72_I33@CHPSET_LIB.SKX_EXT_B(CHIPS)':
 'VCCIO'<69>: CDS_PINID='VCCIO(69)';
NODE_NAME     U2D1 K15
 '@BASEBOARD_FAB2_LIB.BASEBOARD_FAB2(SCH_1):PAGE72_I33@CHPSET_LIB.SKX_EXT_B(CHIPS)':
 'VCCIO'<70>: CDS_PINID='VCCIO(70)';
NODE_NAME     U2D1 M7
 '@BASEBOARD_FAB2_LIB.BASEBOARD_FAB2(SCH_1):PAGE72_I33@CHPSET_LIB.SKX_EXT_B(CHIPS)':
 'VCCIO'<71>: CDS_PINID='VCCIO(71)';
NODE_NAME     U2D1 M9
 '@BASEBOARD_FAB2_LIB.BASEBOARD_FAB2(SCH_1):PAGE72_I33@CHPSET_LIB.SKX_EXT_B(CHIPS)':
 'VCCIO'<72>: CDS_PINID='VCCIO(72)';
NODE_NAME     U2D1 N18
 '@BASEBOARD_FAB2_LIB.BASEBOARD_FAB2(SCH_1):PAGE72_I33@CHPSET_LIB.SKX_EXT_B(CHIPS)':
 'VCCIO'<73>: CDS_PINID='VCCIO(73)';
NODE_NAME     U2D1 W10
 '@BASEBOARD_FAB2_LIB.BASEBOARD_FAB2(SCH_1):PAGE72_I33@CHPSET_LIB.SKX_EXT_B(CHIPS)':
 'VCCIO'<74>: CDS_PINID='VCCIO(74)';
NODE_NAME     U2D1 BC26
 '@BASEBOARD_FAB2_LIB.BASEBOARD_FAB2(SCH_1):PAGE72_I33@CHPSET_LIB.SKX_EXT_B(CHIPS)':
 'VCCIO'<75>: CDS_PINID='VCCIO(75)';
NODE_NAME     U2D1 BB27
 '@BASEBOARD_FAB2_LIB.BASEBOARD_FAB2(SCH_1):PAGE72_I33@CHPSET_LIB.SKX_EXT_B(CHIPS)':
 'VCCIO'<76>: CDS_PINID='VCCIO(76)';
NODE_NAME     U2D1 BA26
 '@BASEBOARD_FAB2_LIB.BASEBOARD_FAB2(SCH_1):PAGE72_I33@CHPSET_LIB.SKX_EXT_B(CHIPS)':
 'VCCIO'<77>: CDS_PINID='VCCIO(77)';
NODE_NAME     U2D1 AY27
 '@BASEBOARD_FAB2_LIB.BASEBOARD_FAB2(SCH_1):PAGE72_I33@CHPSET_LIB.SKX_EXT_B(CHIPS)':
 'VCCIO'<78>: CDS_PINID='VCCIO(78)';
NODE_NAME     U2D1 AW26
 '@BASEBOARD_FAB2_LIB.BASEBOARD_FAB2(SCH_1):PAGE72_I33@CHPSET_LIB.SKX_EXT_B(CHIPS)':
 'VCCIO'<79>: CDS_PINID='VCCIO(79)';
NODE_NAME     U2D1 AV27
 '@BASEBOARD_FAB2_LIB.BASEBOARD_FAB2(SCH_1):PAGE72_I33@CHPSET_LIB.SKX_EXT_B(CHIPS)':
 'VCCIO'<80>: CDS_PINID='VCCIO(80)';
NODE_NAME     U2D1 CF27
 '@BASEBOARD_FAB2_LIB.BASEBOARD_FAB2(SCH_1):PAGE72_I33@CHPSET_LIB.SKX_EXT_B(CHIPS)':
 'VCCIO'<81>: CDS_PINID='VCCIO(81)';
NODE_NAME     U2D1 CD27
 '@BASEBOARD_FAB2_LIB.BASEBOARD_FAB2(SCH_1):PAGE72_I33@CHPSET_LIB.SKX_EXT_B(CHIPS)':
 'VCCIO'<82>: CDS_PINID='VCCIO(82)';
NODE_NAME     U2D1 CC26
 '@BASEBOARD_FAB2_LIB.BASEBOARD_FAB2(SCH_1):PAGE72_I33@CHPSET_LIB.SKX_EXT_B(CHIPS)':
 'VCCIO'<83>: CDS_PINID='VCCIO(83)';
NODE_NAME     U2D1 CJ28
 '@BASEBOARD_FAB2_LIB.BASEBOARD_FAB2(SCH_1):PAGE72_I33@CHPSET_LIB.SKX_EXT_B(CHIPS)':
 'VCCIO'<84>: CDS_PINID='VCCIO(84)';
NODE_NAME     U2D1 CH27
 '@BASEBOARD_FAB2_LIB.BASEBOARD_FAB2(SCH_1):PAGE72_I33@CHPSET_LIB.SKX_EXT_B(CHIPS)':
 'VCCIO'<85>: CDS_PINID='VCCIO(85)';
NODE_NAME     U2D1 BM27
 '@BASEBOARD_FAB2_LIB.BASEBOARD_FAB2(SCH_1):PAGE72_I33@CHPSET_LIB.SKX_EXT_B(CHIPS)':
 'VCCIO'<86>: CDS_PINID='VCCIO(86)';
NODE_NAME     U2D1 BL26
 '@BASEBOARD_FAB2_LIB.BASEBOARD_FAB2(SCH_1):PAGE72_I33@CHPSET_LIB.SKX_EXT_B(CHIPS)':
 'VCCIO'<87>: CDS_PINID='VCCIO(87)';
NODE_NAME     U2D1 BK27
 '@BASEBOARD_FAB2_LIB.BASEBOARD_FAB2(SCH_1):PAGE72_I33@CHPSET_LIB.SKX_EXT_B(CHIPS)':
 'VCCIO'<88>: CDS_PINID='VCCIO(88)';
NODE_NAME     U2D1 BK25
 '@BASEBOARD_FAB2_LIB.BASEBOARD_FAB2(SCH_1):PAGE72_I33@CHPSET_LIB.SKX_EXT_B(CHIPS)':
 'VCCIO'<89>: CDS_PINID='VCCIO(89)';
NODE_NAME     U2D1 BJ26
 '@BASEBOARD_FAB2_LIB.BASEBOARD_FAB2(SCH_1):PAGE72_I33@CHPSET_LIB.SKX_EXT_B(CHIPS)':
 'VCCIO'<90>: CDS_PINID='VCCIO(90)';
NODE_NAME     U2D1 BH27
 '@BASEBOARD_FAB2_LIB.BASEBOARD_FAB2(SCH_1):PAGE72_I33@CHPSET_LIB.SKX_EXT_B(CHIPS)':
 'VCCIO'<91>: CDS_PINID='VCCIO(91)';
NODE_NAME     U2D1 BH25
 '@BASEBOARD_FAB2_LIB.BASEBOARD_FAB2(SCH_1):PAGE72_I33@CHPSET_LIB.SKX_EXT_B(CHIPS)':
 'VCCIO'<92>: CDS_PINID='VCCIO(92)';
NODE_NAME     U2D1 BG26
 '@BASEBOARD_FAB2_LIB.BASEBOARD_FAB2(SCH_1):PAGE72_I33@CHPSET_LIB.SKX_EXT_B(CHIPS)':
 'VCCIO'<93>: CDS_PINID='VCCIO(93)';
NODE_NAME     U2D1 BF27
 '@BASEBOARD_FAB2_LIB.BASEBOARD_FAB2(SCH_1):PAGE72_I33@CHPSET_LIB.SKX_EXT_B(CHIPS)':
 'VCCIO'<94>: CDS_PINID='VCCIO(94)';
NODE_NAME     U2D1 AE36
 '@BASEBOARD_FAB2_LIB.BASEBOARD_FAB2(SCH_1):PAGE72_I33@CHPSET_LIB.SKX_EXT_B(CHIPS)':
 'VCCIO'<95>: CDS_PINID='VCCIO(95)';
NODE_NAME     U2D1 AD37
 '@BASEBOARD_FAB2_LIB.BASEBOARD_FAB2(SCH_1):PAGE72_I33@CHPSET_LIB.SKX_EXT_B(CHIPS)':
 'VCCIO'<96>: CDS_PINID='VCCIO(96)';
NODE_NAME     U2D1 AC36
 '@BASEBOARD_FAB2_LIB.BASEBOARD_FAB2(SCH_1):PAGE72_I33@CHPSET_LIB.SKX_EXT_B(CHIPS)':
 'VCCIO'<97>: CDS_PINID='VCCIO(97)';
NODE_NAME     U2D1 AF35
 '@BASEBOARD_FAB2_LIB.BASEBOARD_FAB2(SCH_1):PAGE72_I33@CHPSET_LIB.SKX_EXT_B(CHIPS)':
 'VCCIO'<98>: CDS_PINID='VCCIO(98)';
NODE_NAME     U2D1 AD35
 '@BASEBOARD_FAB2_LIB.BASEBOARD_FAB2(SCH_1):PAGE72_I33@CHPSET_LIB.SKX_EXT_B(CHIPS)':
 'VCCIO'<99>: CDS_PINID='VCCIO(99)';
NODE_NAME     U2D1 AE34
 '@BASEBOARD_FAB2_LIB.BASEBOARD_FAB2(SCH_1):PAGE72_I33@CHPSET_LIB.SKX_EXT_B(CHIPS)':
 'VCCIO'<100>: CDS_PINID='VCCIO(100)';
NODE_NAME     U2D1 AG34
 '@BASEBOARD_FAB2_LIB.BASEBOARD_FAB2(SCH_1):PAGE72_I33@CHPSET_LIB.SKX_EXT_B(CHIPS)':
 'VCCIO'<101>: CDS_PINID='VCCIO(101)';
NODE_NAME     U2D1 AM29
 '@BASEBOARD_FAB2_LIB.BASEBOARD_FAB2(SCH_1):PAGE72_I33@CHPSET_LIB.SKX_EXT_B(CHIPS)':
 'VCCIO'<102>: CDS_PINID='VCCIO(102)';
NODE_NAME     U2D1 AL28
 '@BASEBOARD_FAB2_LIB.BASEBOARD_FAB2(SCH_1):PAGE72_I33@CHPSET_LIB.SKX_EXT_B(CHIPS)':
 'VCCIO'<103>: CDS_PINID='VCCIO(103)';
NODE_NAME     U2D1 AR28
 '@BASEBOARD_FAB2_LIB.BASEBOARD_FAB2(SCH_1):PAGE72_I33@CHPSET_LIB.SKX_EXT_B(CHIPS)':
 'VCCIO'<104>: CDS_PINID='VCCIO(104)';
NODE_NAME     U2D1 EE10
 '@BASEBOARD_FAB2_LIB.BASEBOARD_FAB2(SCH_1):PAGE73_I107@CHPSET_LIB.SKX_EXT_B(CHIPS)':
 'VCCIO'<0>: CDS_PINID='VCCIO(0)';
NODE_NAME     U2D1 AE10
 '@BASEBOARD_FAB2_LIB.BASEBOARD_FAB2(SCH_1):PAGE73_I107@CHPSET_LIB.SKX_EXT_B(CHIPS)':
 'VCCIO'<1>: CDS_PINID='VCCIO(1)';
NODE_NAME     U2D1 AF5
 '@BASEBOARD_FAB2_LIB.BASEBOARD_FAB2(SCH_1):PAGE73_I107@CHPSET_LIB.SKX_EXT_B(CHIPS)':
 'VCCIO'<2>: CDS_PINID='VCCIO(2)';
NODE_NAME     U2D1 DV11
 '@BASEBOARD_FAB2_LIB.BASEBOARD_FAB2(SCH_1):PAGE73_I107@CHPSET_LIB.SKX_EXT_B(CHIPS)':
 'VCCIO'<3>: CDS_PINID='VCCIO(3)';
NODE_NAME     U2D1 AM5
 '@BASEBOARD_FAB2_LIB.BASEBOARD_FAB2(SCH_1):PAGE73_I107@CHPSET_LIB.SKX_EXT_B(CHIPS)':
 'VCCIO'<4>: CDS_PINID='VCCIO(4)';
NODE_NAME     U2D1 AT5
 '@BASEBOARD_FAB2_LIB.BASEBOARD_FAB2(SCH_1):PAGE73_I107@CHPSET_LIB.SKX_EXT_B(CHIPS)':
 'VCCIO'<5>: CDS_PINID='VCCIO(5)';
NODE_NAME     U2D1 AT7
 '@BASEBOARD_FAB2_LIB.BASEBOARD_FAB2(SCH_1):PAGE73_I107@CHPSET_LIB.SKX_EXT_B(CHIPS)':
 'VCCIO'<6>: CDS_PINID='VCCIO(6)';
NODE_NAME     U2D1 BE24
 '@BASEBOARD_FAB2_LIB.BASEBOARD_FAB2(SCH_1):PAGE73_I107@CHPSET_LIB.SKX_EXT_B(CHIPS)':
 'VCCIO'<7>: CDS_PINID='VCCIO(7)';
NODE_NAME     U2D1 DK21
 '@BASEBOARD_FAB2_LIB.BASEBOARD_FAB2(SCH_1):PAGE73_I107@CHPSET_LIB.SKX_EXT_B(CHIPS)':
 'VCCIO'<8>: CDS_PINID='VCCIO(8)';
NODE_NAME     U2D1 CF5
 '@BASEBOARD_FAB2_LIB.BASEBOARD_FAB2(SCH_1):PAGE73_I107@CHPSET_LIB.SKX_EXT_B(CHIPS)':
 'VCCIO'<9>: CDS_PINID='VCCIO(9)';
NODE_NAME     U2D1 CG14
 '@BASEBOARD_FAB2_LIB.BASEBOARD_FAB2(SCH_1):PAGE73_I107@CHPSET_LIB.SKX_EXT_B(CHIPS)':
 'VCCIO'<10>: CDS_PINID='VCCIO(10)';
NODE_NAME     U2D1 CL20
 '@BASEBOARD_FAB2_LIB.BASEBOARD_FAB2(SCH_1):PAGE73_I107@CHPSET_LIB.SKX_EXT_B(CHIPS)':
 'VCCIO'<11>: CDS_PINID='VCCIO(11)';
NODE_NAME     U2D1 CP13
 '@BASEBOARD_FAB2_LIB.BASEBOARD_FAB2(SCH_1):PAGE73_I107@CHPSET_LIB.SKX_EXT_B(CHIPS)':
 'VCCIO'<12>: CDS_PINID='VCCIO(12)';
NODE_NAME     U2D1 DE14
 '@BASEBOARD_FAB2_LIB.BASEBOARD_FAB2(SCH_1):PAGE73_I107@CHPSET_LIB.SKX_EXT_B(CHIPS)':
 'VCCIO'<13>: CDS_PINID='VCCIO(13)';
NODE_NAME     U2D1 DC18
 '@BASEBOARD_FAB2_LIB.BASEBOARD_FAB2(SCH_1):PAGE73_I107@CHPSET_LIB.SKX_EXT_B(CHIPS)':
 'VCCIO'<14>: CDS_PINID='VCCIO(14)';
NODE_NAME     U2D1 CY17
 '@BASEBOARD_FAB2_LIB.BASEBOARD_FAB2(SCH_1):PAGE73_I107@CHPSET_LIB.SKX_EXT_B(CHIPS)':
 'VCCIO'<15>: CDS_PINID='VCCIO(15)';
NODE_NAME     U2D1 CU18
 '@BASEBOARD_FAB2_LIB.BASEBOARD_FAB2(SCH_1):PAGE73_I107@CHPSET_LIB.SKX_EXT_B(CHIPS)':
 'VCCIO'<16>: CDS_PINID='VCCIO(16)';
NODE_NAME     U2D1 CV21
 '@BASEBOARD_FAB2_LIB.BASEBOARD_FAB2(SCH_1):PAGE73_I107@CHPSET_LIB.SKX_EXT_B(CHIPS)':
 'VCCIO'<17>: CDS_PINID='VCCIO(17)';
NODE_NAME     U2D1 CU12
 '@BASEBOARD_FAB2_LIB.BASEBOARD_FAB2(SCH_1):PAGE73_I107@CHPSET_LIB.SKX_EXT_B(CHIPS)':
 'VCCIO'<18>: CDS_PINID='VCCIO(18)';
NODE_NAME     U2D1 CN6
 '@BASEBOARD_FAB2_LIB.BASEBOARD_FAB2(SCH_1):PAGE73_I107@CHPSET_LIB.SKX_EXT_B(CHIPS)':
 'VCCIO'<19>: CDS_PINID='VCCIO(19)';
NODE_NAME     C3D9 1
 '@BASEBOARD_FAB2_LIB.BASEBOARD_FAB2(SCH_1):PAGE76_I15@DEV_DISCRETE.CAP_A(CHIPS)':
 'A': CDS_PINID='A';
NODE_NAME     C3D8 1
 '@BASEBOARD_FAB2_LIB.BASEBOARD_FAB2(SCH_1):PAGE76_I18@DEV_DISCRETE.CAP_A(CHIPS)':
 'A': CDS_PINID='A';
NODE_NAME     C7P17 1
 '@BASEBOARD_FAB2_LIB.BASEBOARD_FAB2(SCH_1):PAGE76_I29@MSTR_DISCRETE.CAP(CHIPS)':
 'A': CDS_PINID='A';
NODE_NAME     C7P18 1
 '@BASEBOARD_FAB2_LIB.BASEBOARD_FAB2(SCH_1):PAGE76_I51@MSTR_DISCRETE.CAP(CHIPS)':
 'A': CDS_PINID='A';
NODE_NAME     C7P3 1
 '@BASEBOARD_FAB2_LIB.BASEBOARD_FAB2(SCH_1):PAGE76_I52@MSTR_DISCRETE.CAP(CHIPS)':
 'A': CDS_PINID='A';
NODE_NAME     C3D23 1
 '@BASEBOARD_FAB2_LIB.BASEBOARD_FAB2(SCH_1):PAGE76_I172@DEV_DISCRETE.CAP_A(CHIPS)':
 'A': CDS_PINID='A';
NODE_NAME     C3D15 1
 '@BASEBOARD_FAB2_LIB.BASEBOARD_FAB2(SCH_1):PAGE76_I174@DEV_DISCRETE.CAP_A(CHIPS)':
 'A': CDS_PINID='A';
NODE_NAME     C3D24 1
 '@BASEBOARD_FAB2_LIB.BASEBOARD_FAB2(SCH_1):PAGE76_I175@DEV_DISCRETE.CAP_A(CHIPS)':
 'A': CDS_PINID='A';
NODE_NAME     C3D16 1
 '@BASEBOARD_FAB2_LIB.BASEBOARD_FAB2(SCH_1):PAGE76_I176@DEV_DISCRETE.CAP_A(CHIPS)':
 'A': CDS_PINID='A';
NODE_NAME     C7P12 1
 '@BASEBOARD_FAB2_LIB.BASEBOARD_FAB2(SCH_1):PAGE76_I179@DEV_DISCRETE.CAP_A(CHIPS)':
 'A': CDS_PINID='A';
NODE_NAME     C7P16 1
 '@BASEBOARD_FAB2_LIB.BASEBOARD_FAB2(SCH_1):PAGE76_I206@DEV_DISCRETE.CAP_A(CHIPS)':
 'A': CDS_PINID='A';
NODE_NAME     R3D22 1
 '@BASEBOARD_FAB2_LIB.BASEBOARD_FAB2(SCH_1):PAGE90_I17@MSTR_DISCRETE.RES(CHIPS)':
 'A': CDS_PINID='A';
NODE_NAME     R3D16 1
 '@BASEBOARD_FAB2_LIB.BASEBOARD_FAB2(SCH_1):PAGE90_I24@MSTR_DISCRETE.RES(CHIPS)':
 'A': CDS_PINID='A';
NODE_NAME     R3D23 1
 '@BASEBOARD_FAB2_LIB.BASEBOARD_FAB2(SCH_1):PAGE90_I25@MSTR_DISCRETE.RES(CHIPS)':
 'A': CDS_PINID='A';
NODE_NAME     R3D26 1
 '@BASEBOARD_FAB2_LIB.BASEBOARD_FAB2(SCH_1):PAGE90_I28@MSTR_DISCRETE.RES(CHIPS)':
 'A': CDS_PINID='A';
NODE_NAME     R3D24 1
 '@BASEBOARD_FAB2_LIB.BASEBOARD_FAB2(SCH_1):PAGE90_I59@MSTR_DISCRETE.RES(CHIPS)':
 'A': CDS_PINID='A';
NODE_NAME     R3D17 1
 '@BASEBOARD_FAB2_LIB.BASEBOARD_FAB2(SCH_1):PAGE90_I60@MSTR_DISCRETE.RES(CHIPS)':
 'A': CDS_PINID='A';
NODE_NAME     R7P22 1
 '@BASEBOARD_FAB2_LIB.BASEBOARD_FAB2(SCH_1):PAGE90_I76@MSTR_DISCRETE.RES(CHIPS)':
 'A': CDS_PINID='A';
NODE_NAME     R3P41 1
 '@BASEBOARD_FAB2_LIB.BASEBOARD_FAB2(SCH_1):PAGE92_I9@MSTR_DISCRETE.RES(CHIPS)':
 'A': CDS_PINID='A';
NODE_NAME     R7P28 1
 '@BASEBOARD_FAB2_LIB.BASEBOARD_FAB2(SCH_1):PAGE93_I106@MSTR_DISCRETE.RES(CHIPS)':
 'A': CDS_PINID='A';
NODE_NAME     R2T73 1
 '@BASEBOARD_FAB2_LIB.BASEBOARD_FAB2(SCH_1):PAGE93_I144@MSTR_DISCRETE.RES(CHIPS)':
 'A': CDS_PINID='A';
NODE_NAME     R3D20 1
 '@BASEBOARD_FAB2_LIB.BASEBOARD_FAB2(SCH_1):PAGE96_I25@MSTR_DISCRETE.RES(CHIPS)':
 'A': CDS_PINID='A';
NODE_NAME     R3D15 1
 '@BASEBOARD_FAB2_LIB.BASEBOARD_FAB2(SCH_1):PAGE96_I26@MSTR_DISCRETE.RES(CHIPS)':
 'A': CDS_PINID='A';
NODE_NAME     R4C10 1
 '@BASEBOARD_FAB2_LIB.BASEBOARD_FAB2(SCH_1):PAGE97_I76@MSTR_DISCRETE.RES(CHIPS)':
 'A': CDS_PINID='A';
NODE_NAME     C4G22 1
 '@BASEBOARD_FAB2_LIB.BASEBOARD_FAB2(SCH_1):PAGE99_I27@DEV_DISCRETE.CAP_A(CHIPS)':
 'A': CDS_PINID='A';
NODE_NAME     C3B4 1
 '@BASEBOARD_FAB2_LIB.BASEBOARD_FAB2(SCH_1):PAGE99_I47@DEV_DISCRETE.CAP_A(CHIPS)':
 'A': CDS_PINID='A';
NODE_NAME     U4G1 1
 '@BASEBOARD_FAB2_LIB.BASEBOARD_FAB2(SCH_1):PAGE99_I63@MSTR_DIGITAL.PCA9617(CHIPS)':
 'VCCA': CDS_PINID='VCCA';
NODE_NAME     R6T1 1
 '@BASEBOARD_FAB2_LIB.BASEBOARD_FAB2(SCH_1):PAGE99_I70@MSTR_DISCRETE.RES(CHIPS)':
 'A': CDS_PINID='A';
NODE_NAME     R6T2 1
 '@BASEBOARD_FAB2_LIB.BASEBOARD_FAB2(SCH_1):PAGE99_I72@MSTR_DISCRETE.RES(CHIPS)':
 'A': CDS_PINID='A';
NODE_NAME     U3B1 1
 '@BASEBOARD_FAB2_LIB.BASEBOARD_FAB2(SCH_1):PAGE99_I75@MSTR_DIGITAL.PCA9617(CHIPS)':
 'VCCA': CDS_PINID='VCCA';
NODE_NAME     R7M7 1
 '@BASEBOARD_FAB2_LIB.BASEBOARD_FAB2(SCH_1):PAGE99_I77@MSTR_DISCRETE.RES(CHIPS)':
 'A': CDS_PINID='A';
NODE_NAME     R7M2 1
 '@BASEBOARD_FAB2_LIB.BASEBOARD_FAB2(SCH_1):PAGE99_I79@MSTR_DISCRETE.RES(CHIPS)':
 'A': CDS_PINID='A';
NODE_NAME     R6T7 1
 '@BASEBOARD_FAB2_LIB.BASEBOARD_FAB2(SCH_1):PAGE112_I55@MSTR_DISCRETE.RES(CHIPS)':
 'A': CDS_PINID='A';
NODE_NAME     R6T6 1
 '@BASEBOARD_FAB2_LIB.BASEBOARD_FAB2(SCH_1):PAGE112_I56@MSTR_DISCRETE.RES(CHIPS)':
 'A': CDS_PINID='A';
NODE_NAME     R1U41 1
 '@BASEBOARD_FAB2_LIB.BASEBOARD_FAB2(SCH_1):PAGE152_I56@MSTR_DISCRETE.RES(CHIPS)':
 'A': CDS_PINID='A';
NODE_NAME     R1U35 1
 '@BASEBOARD_FAB2_LIB.BASEBOARD_FAB2(SCH_1):PAGE152_I57@MSTR_DISCRETE.RES(CHIPS)':
 'A': CDS_PINID='A';
NODE_NAME     R7P5 2
 '@BASEBOARD_FAB2_LIB.BASEBOARD_FAB2(SCH_1):PAGE152_I61@MSTR_DISCRETE.RES(CHIPS)':
 'B': CDS_PINID='B';
NODE_NAME     R7P21 2
 '@BASEBOARD_FAB2_LIB.BASEBOARD_FAB2(SCH_1):PAGE152_I62@MSTR_DISCRETE.RES(CHIPS)':
 'B': CDS_PINID='B';
NODE_NAME     R9M18 1
 '@BASEBOARD_FAB2_LIB.BASEBOARD_FAB2(SCH_1):PAGE163_I6@MSTR_DISCRETE.RES(CHIPS)':
 'A': CDS_PINID='A';
NODE_NAME     R9M19 1
 '@BASEBOARD_FAB2_LIB.BASEBOARD_FAB2(SCH_1):PAGE163_I7@MSTR_DISCRETE.RES(CHIPS)':
 'A': CDS_PINID='A';
NODE_NAME     C9M8 1
 '@BASEBOARD_FAB2_LIB.BASEBOARD_FAB2(SCH_1):PAGE163_I10@DEV_DISCRETE.CAP_A(CHIPS)':
 'A': CDS_PINID='A';
NODE_NAME     J4B2 F1
 '@BASEBOARD_FAB2_LIB.BASEBOARD_FAB2(SCH_1):PAGE193_I46@MSTR_SCONN.SCONN120_H61426002(CHIPS)':
 'IOF1': CDS_PINID='IOF1';
NODE_NAME     R9P1 1
 '@BASEBOARD_FAB2_LIB.BASEBOARD_FAB2(SCH_1):PAGE206_I4@MSTR_DISCRETE.RES(CHIPS)':
 'A': CDS_PINID='A';
NODE_NAME     R9P2 1
 '@BASEBOARD_FAB2_LIB.BASEBOARD_FAB2(SCH_1):PAGE206_I53@MSTR_DISCRETE.RES(CHIPS)':
 'A': CDS_PINID='A';
NODE_NAME     R9N14 1
 '@BASEBOARD_FAB2_LIB.BASEBOARD_FAB2(SCH_1):PAGE206_I120@MSTR_DISCRETE.RES(CHIPS)':
 'A': CDS_PINID='A';
NODE_NAME     R6P35 1
 '@BASEBOARD_FAB2_LIB.BASEBOARD_FAB2(SCH_1):PAGE213_I27@MSTR_DISCRETE.RES(CHIPS)':
 'A': CDS_PINID='A';
NODE_NAME     R6P33 1
 '@BASEBOARD_FAB2_LIB.BASEBOARD_FAB2(SCH_1):PAGE213_I30@MSTR_DISCRETE.RES(CHIPS)':
 'A': CDS_PINID='A';
NODE_NAME     C6R5 1
 '@BASEBOARD_FAB2_LIB.BASEBOARD_FAB2(SCH_1):PAGE214_I24@MSTR_DISCRETE.CAPP(CHIPS)':
 'A': CDS_PINID='A';
NODE_NAME     C7R1 1
 '@BASEBOARD_FAB2_LIB.BASEBOARD_FAB2(SCH_1):PAGE214_I65@DEV_DISCRETE.CAP_A(CHIPS)':
 'A': CDS_PINID='A';
NODE_NAME     R3E1 2
 '@BASEBOARD_FAB2_LIB.BASEBOARD_FAB2(SCH_1):PAGE214_I105@MSTR_DISCRETE.RES(CHIPS)':
 'B': CDS_PINID='B';
NODE_NAME     C3E1 1
 '@BASEBOARD_FAB2_LIB.BASEBOARD_FAB2(SCH_1):PAGE214_I108@DEV_DISCRETE.CAP_A(CHIPS)':
 'A': CDS_PINID='A';
NODE_NAME     R7R1 1
 '@BASEBOARD_FAB2_LIB.BASEBOARD_FAB2(SCH_1):PAGE214_I109@MSTR_DISCRETE.RES(CHIPS)':
 'A': CDS_PINID='A';
NODE_NAME     EU4E2 1
 '@BASEBOARD_FAB2_LIB.BASEBOARD_FAB2(SCH_1):PAGE214_I126@MSTR_DISCRETE.IR354XX(CHIPS)':
 'VOS': CDS_PINID='VOS';
NODE_NAME     U1B2 1
 '@BASEBOARD_FAB2_LIB.BASEBOARD_FAB2(SCH_1):PAGE163_I28@W_HDL.TCA9517DGKR-GP(CHIPS)':
 'VCCA': CDS_PINID='VCCA';
NODE_NAME     L4E2 2
 '@BASEBOARD_FAB2_LIB.BASEBOARD_FAB2(SCH_1):PAGE214_I174@W_HDL.IND-150NH-56-GP(CHIPS)':
 'F': CDS_PINID='F';
NODE_NAME     R9U3 1
 '@BASEBOARD_FAB2_LIB.BASEBOARD_FAB2(SCH_1):PAGE223_I57@MSTR_DISCRETE.RES(CHIPS)':
 'A': CDS_PINID='A';
NODE_NAME     R9M7 1
 '@BASEBOARD_FAB2_LIB.BASEBOARD_FAB2(SCH_1):PAGE226_I57@MSTR_DISCRETE.RES(CHIPS)':
 'A': CDS_PINID='A';
NODE_NAME     R9M6 1
 '@BASEBOARD_FAB2_LIB.BASEBOARD_FAB2(SCH_1):PAGE226_I70@MSTR_DISCRETE.RES(CHIPS)':
 'A': CDS_PINID='A';
NODE_NAME     R9U4 1
 '@BASEBOARD_FAB2_LIB.BASEBOARD_FAB2(SCH_1):PAGE223_I70@MSTR_DISCRETE.RES(CHIPS)':
 'A': CDS_PINID='A';
NODE_NAME     C6R12 1
 '@BASEBOARD_FAB2_LIB.BASEBOARD_FAB2(SCH_1):PAGE214_I177@MSTR_DISCRETE.CAPP(CHIPS)':
 'A': CDS_PINID='A';
NODE_NAME     C4E7 1
 '@BASEBOARD_FAB2_LIB.BASEBOARD_FAB2(SCH_1):PAGE214_I178@MSTR_DISCRETE.CAPP(CHIPS)':
 'A': CDS_PINID='A';
NET_NAME
'PVCCMCP_CPU0'
 '@BASEBOARD_FAB2_LIB.BASEBOARD_FAB2(SCH_1):PVCCMCP_CPU0':
 C_SIGNAL='@baseboard_fab2_lib.baseboard_fab2(sch_1):pvccmcp_cpu0';
NODE_NAME     U5D1 AP25
 '@BASEBOARD_FAB2_LIB.BASEBOARD_FAB2(SCH_1):PAGE22_I204@CHPSET_LIB.SKX_EXT_B(CHIPS)':
 'RSVD'<196>: CDS_PINID='RSVD(196)';
NODE_NAME     U5D1 AP23
 '@BASEBOARD_FAB2_LIB.BASEBOARD_FAB2(SCH_1):PAGE22_I204@CHPSET_LIB.SKX_EXT_B(CHIPS)':
 'RSVD'<197>: CDS_PINID='RSVD(197)';
NODE_NAME     U5D1 AN26
 '@BASEBOARD_FAB2_LIB.BASEBOARD_FAB2(SCH_1):PAGE22_I204@CHPSET_LIB.SKX_EXT_B(CHIPS)':
 'RSVD'<200>: CDS_PINID='RSVD(200)';
NODE_NAME     U5D1 AN24
 '@BASEBOARD_FAB2_LIB.BASEBOARD_FAB2(SCH_1):PAGE22_I204@CHPSET_LIB.SKX_EXT_B(CHIPS)':
 'RSVD'<201>: CDS_PINID='RSVD(201)';
NODE_NAME     U5D1 AN22
 '@BASEBOARD_FAB2_LIB.BASEBOARD_FAB2(SCH_1):PAGE22_I204@CHPSET_LIB.SKX_EXT_B(CHIPS)':
 'RSVD'<202>: CDS_PINID='RSVD(202)';
NODE_NAME     U5D1 AN18
 '@BASEBOARD_FAB2_LIB.BASEBOARD_FAB2(SCH_1):PAGE22_I204@CHPSET_LIB.SKX_EXT_B(CHIPS)':
 'RSVD'<203>: CDS_PINID='RSVD(203)';
NODE_NAME     U5D1 AM25
 '@BASEBOARD_FAB2_LIB.BASEBOARD_FAB2(SCH_1):PAGE22_I204@CHPSET_LIB.SKX_EXT_B(CHIPS)':
 'RSVD'<207>: CDS_PINID='RSVD(207)';
NODE_NAME     U5D1 AM21
 '@BASEBOARD_FAB2_LIB.BASEBOARD_FAB2(SCH_1):PAGE22_I204@CHPSET_LIB.SKX_EXT_B(CHIPS)':
 'RSVD'<209>: CDS_PINID='RSVD(209)';
NODE_NAME     U5D1 AT25
 '@BASEBOARD_FAB2_LIB.BASEBOARD_FAB2(SCH_1):PAGE29_I61@CHPSET_LIB.SKX_EXT_B(CHIPS)':
 'RSVD'<187>: CDS_PINID='RSVD(187)';
NODE_NAME     U5D1 AT23
 '@BASEBOARD_FAB2_LIB.BASEBOARD_FAB2(SCH_1):PAGE29_I61@CHPSET_LIB.SKX_EXT_B(CHIPS)':
 'RSVD'<188>: CDS_PINID='RSVD(188)';
NODE_NAME     U5D1 AR26
 '@BASEBOARD_FAB2_LIB.BASEBOARD_FAB2(SCH_1):PAGE29_I61@CHPSET_LIB.SKX_EXT_B(CHIPS)':
 'RSVD'<191>: CDS_PINID='RSVD(191)';
NODE_NAME     U5D1 AR22
 '@BASEBOARD_FAB2_LIB.BASEBOARD_FAB2(SCH_1):PAGE29_I61@CHPSET_LIB.SKX_EXT_B(CHIPS)':
 'RSVD'<192>: CDS_PINID='RSVD(192)';
NODE_NAME     U5D1 AR20
 '@BASEBOARD_FAB2_LIB.BASEBOARD_FAB2(SCH_1):PAGE29_I61@CHPSET_LIB.SKX_EXT_B(CHIPS)':
 'RSVD'<193>: CDS_PINID='RSVD(193)';
NODE_NAME     U5D1 CH23
 '@BASEBOARD_FAB2_LIB.BASEBOARD_FAB2(SCH_1):PAGE36_I15@CHPSET_LIB.SKX_EXT_B(CHIPS)':
 'RSVD'<92>: CDS_PINID='RSVD(92)';
NODE_NAME     U5D1 CH21
 '@BASEBOARD_FAB2_LIB.BASEBOARD_FAB2(SCH_1):PAGE36_I15@CHPSET_LIB.SKX_EXT_B(CHIPS)':
 'RSVD'<93>: CDS_PINID='RSVD(93)';
NODE_NAME     U5D1 CG26
 '@BASEBOARD_FAB2_LIB.BASEBOARD_FAB2(SCH_1):PAGE36_I15@CHPSET_LIB.SKX_EXT_B(CHIPS)':
 'RSVD'<96>: CDS_PINID='RSVD(96)';
NODE_NAME     U5D1 CG20
 '@BASEBOARD_FAB2_LIB.BASEBOARD_FAB2(SCH_1):PAGE36_I15@CHPSET_LIB.SKX_EXT_B(CHIPS)':
 'RSVD'<98>: CDS_PINID='RSVD(98)';
NODE_NAME     U5D1 CF23
 '@BASEBOARD_FAB2_LIB.BASEBOARD_FAB2(SCH_1):PAGE36_I15@CHPSET_LIB.SKX_EXT_B(CHIPS)':
 'RSVD'<102>: CDS_PINID='RSVD(102)';
NODE_NAME     U5D1 CF21
 '@BASEBOARD_FAB2_LIB.BASEBOARD_FAB2(SCH_1):PAGE36_I15@CHPSET_LIB.SKX_EXT_B(CHIPS)':
 'RSVD'<103>: CDS_PINID='RSVD(103)';
NODE_NAME     U5D1 CF19
 '@BASEBOARD_FAB2_LIB.BASEBOARD_FAB2(SCH_1):PAGE36_I15@CHPSET_LIB.SKX_EXT_B(CHIPS)':
 'RSVD'<104>: CDS_PINID='RSVD(104)';
NODE_NAME     U5D1 CE22
 '@BASEBOARD_FAB2_LIB.BASEBOARD_FAB2(SCH_1):PAGE36_I15@CHPSET_LIB.SKX_EXT_B(CHIPS)':
 'RSVD'<107>: CDS_PINID='RSVD(107)';
NODE_NAME     U5D1 CD21
 '@BASEBOARD_FAB2_LIB.BASEBOARD_FAB2(SCH_1):PAGE36_I15@CHPSET_LIB.SKX_EXT_B(CHIPS)':
 'RSVD'<109>: CDS_PINID='RSVD(109)';
NODE_NAME     U5D1 CD19
 '@BASEBOARD_FAB2_LIB.BASEBOARD_FAB2(SCH_1):PAGE36_I15@CHPSET_LIB.SKX_EXT_B(CHIPS)':
 'RSVD'<110>: CDS_PINID='RSVD(110)';
NODE_NAME     U5D1 CC20
 '@BASEBOARD_FAB2_LIB.BASEBOARD_FAB2(SCH_1):PAGE36_I15@CHPSET_LIB.SKX_EXT_B(CHIPS)':
 'RSVD'<112>: CDS_PINID='RSVD(112)';
NODE_NAME     U5D1 CB21
 '@BASEBOARD_FAB2_LIB.BASEBOARD_FAB2(SCH_1):PAGE36_I15@CHPSET_LIB.SKX_EXT_B(CHIPS)':
 'RSVD'<115>: CDS_PINID='RSVD(115)';
NODE_NAME     U5D1 CB19
 '@BASEBOARD_FAB2_LIB.BASEBOARD_FAB2(SCH_1):PAGE36_I15@CHPSET_LIB.SKX_EXT_B(CHIPS)':
 'RSVD'<116>: CDS_PINID='RSVD(116)';
NODE_NAME     U5D1 CA22
 '@BASEBOARD_FAB2_LIB.BASEBOARD_FAB2(SCH_1):PAGE36_I15@CHPSET_LIB.SKX_EXT_B(CHIPS)':
 'RSVD'<118>: CDS_PINID='RSVD(118)';
NODE_NAME     U5D1 BY19
 '@BASEBOARD_FAB2_LIB.BASEBOARD_FAB2(SCH_1):PAGE36_I15@CHPSET_LIB.SKX_EXT_B(CHIPS)':
 'RSVD'<120>: CDS_PINID='RSVD(120)';
NODE_NAME     U5D1 BW20
 '@BASEBOARD_FAB2_LIB.BASEBOARD_FAB2(SCH_1):PAGE36_I15@CHPSET_LIB.SKX_EXT_B(CHIPS)':
 'RSVD'<122>: CDS_PINID='RSVD(122)';
NODE_NAME     U5D1 BV21
 '@BASEBOARD_FAB2_LIB.BASEBOARD_FAB2(SCH_1):PAGE36_I15@CHPSET_LIB.SKX_EXT_B(CHIPS)':
 'RSVD'<125>: CDS_PINID='RSVD(125)';
NODE_NAME     U5D1 BV19
 '@BASEBOARD_FAB2_LIB.BASEBOARD_FAB2(SCH_1):PAGE36_I15@CHPSET_LIB.SKX_EXT_B(CHIPS)':
 'RSVD'<126>: CDS_PINID='RSVD(126)';
NODE_NAME     U5D1 BU22
 '@BASEBOARD_FAB2_LIB.BASEBOARD_FAB2(SCH_1):PAGE36_I15@CHPSET_LIB.SKX_EXT_B(CHIPS)':
 'RSVD'<127>: CDS_PINID='RSVD(127)';
NODE_NAME     U5D1 BU20
 '@BASEBOARD_FAB2_LIB.BASEBOARD_FAB2(SCH_1):PAGE36_I15@CHPSET_LIB.SKX_EXT_B(CHIPS)':
 'RSVD'<128>: CDS_PINID='RSVD(128)';
NODE_NAME     U5D1 BR24
 '@BASEBOARD_FAB2_LIB.BASEBOARD_FAB2(SCH_1):PAGE36_I15@CHPSET_LIB.SKX_EXT_B(CHIPS)':
 'RSVD'<130>: CDS_PINID='RSVD(130)';
NODE_NAME     U5D1 BR22
 '@BASEBOARD_FAB2_LIB.BASEBOARD_FAB2(SCH_1):PAGE36_I15@CHPSET_LIB.SKX_EXT_B(CHIPS)':
 'RSVD'<131>: CDS_PINID='RSVD(131)';
NODE_NAME     U5D1 BP21
 '@BASEBOARD_FAB2_LIB.BASEBOARD_FAB2(SCH_1):PAGE36_I15@CHPSET_LIB.SKX_EXT_B(CHIPS)':
 'RSVD'<132>: CDS_PINID='RSVD(132)';
NODE_NAME     U5D1 BM19
 '@BASEBOARD_FAB2_LIB.BASEBOARD_FAB2(SCH_1):PAGE36_I15@CHPSET_LIB.SKX_EXT_B(CHIPS)':
 'RSVD'<135>: CDS_PINID='RSVD(135)';
NODE_NAME     U5D1 BL20
 '@BASEBOARD_FAB2_LIB.BASEBOARD_FAB2(SCH_1):PAGE36_I15@CHPSET_LIB.SKX_EXT_B(CHIPS)':
 'RSVD'<137>: CDS_PINID='RSVD(137)';
NODE_NAME     U5D1 BK17
 '@BASEBOARD_FAB2_LIB.BASEBOARD_FAB2(SCH_1):PAGE36_I15@CHPSET_LIB.SKX_EXT_B(CHIPS)':
 'RSVD'<139>: CDS_PINID='RSVD(139)';
NODE_NAME     U5D1 BJ20
 '@BASEBOARD_FAB2_LIB.BASEBOARD_FAB2(SCH_1):PAGE36_I15@CHPSET_LIB.SKX_EXT_B(CHIPS)':
 'RSVD'<140>: CDS_PINID='RSVD(140)';
NODE_NAME     U5D1 BJ18
 '@BASEBOARD_FAB2_LIB.BASEBOARD_FAB2(SCH_1):PAGE36_I15@CHPSET_LIB.SKX_EXT_B(CHIPS)':
 'RSVD'<141>: CDS_PINID='RSVD(141)';
NODE_NAME     U5D1 BJ16
 '@BASEBOARD_FAB2_LIB.BASEBOARD_FAB2(SCH_1):PAGE36_I15@CHPSET_LIB.SKX_EXT_B(CHIPS)':
 'RSVD'<142>: CDS_PINID='RSVD(142)';
NODE_NAME     U5D1 BH19
 '@BASEBOARD_FAB2_LIB.BASEBOARD_FAB2(SCH_1):PAGE36_I15@CHPSET_LIB.SKX_EXT_B(CHIPS)':
 'RSVD'<143>: CDS_PINID='RSVD(143)';
NODE_NAME     U5D1 CL24
 '@BASEBOARD_FAB2_LIB.BASEBOARD_FAB2(SCH_1):PAGE36_I16@CHPSET_LIB.SKX_EXT_B(CHIPS)':
 'RSVD'<81>: CDS_PINID='RSVD(81)';
NODE_NAME     U5D1 CK25
 '@BASEBOARD_FAB2_LIB.BASEBOARD_FAB2(SCH_1):PAGE36_I16@CHPSET_LIB.SKX_EXT_B(CHIPS)':
 'RSVD'<83>: CDS_PINID='RSVD(83)';
NODE_NAME     U5D1 CK23
 '@BASEBOARD_FAB2_LIB.BASEBOARD_FAB2(SCH_1):PAGE36_I16@CHPSET_LIB.SKX_EXT_B(CHIPS)':
 'RSVD'<84>: CDS_PINID='RSVD(84)';
NODE_NAME     U5D1 CJ26
 '@BASEBOARD_FAB2_LIB.BASEBOARD_FAB2(SCH_1):PAGE36_I16@CHPSET_LIB.SKX_EXT_B(CHIPS)':
 'RSVD'<86>: CDS_PINID='RSVD(86)';
NODE_NAME     U5D1 CJ24
 '@BASEBOARD_FAB2_LIB.BASEBOARD_FAB2(SCH_1):PAGE36_I16@CHPSET_LIB.SKX_EXT_B(CHIPS)':
 'RSVD'<87>: CDS_PINID='RSVD(87)';
NODE_NAME     U5D1 CJ22
 '@BASEBOARD_FAB2_LIB.BASEBOARD_FAB2(SCH_1):PAGE36_I16@CHPSET_LIB.SKX_EXT_B(CHIPS)':
 'RSVD'<88>: CDS_PINID='RSVD(88)';
NODE_NAME     U5D1 CJ20
 '@BASEBOARD_FAB2_LIB.BASEBOARD_FAB2(SCH_1):PAGE36_I16@CHPSET_LIB.SKX_EXT_B(CHIPS)':
 'RSVD'<89>: CDS_PINID='RSVD(89)';
NODE_NAME     U5D1 BL14
 '@BASEBOARD_FAB2_LIB.BASEBOARD_FAB2(SCH_1):PAGE38_I34@CHPSET_LIB.SKX_EXT_B(CHIPS)':
 'CD_VCC_CORE'<0>: CDS_PINID='CD_VCC_CORE(0)';
NODE_NAME     U5D1 BK15
 '@BASEBOARD_FAB2_LIB.BASEBOARD_FAB2(SCH_1):PAGE38_I34@CHPSET_LIB.SKX_EXT_B(CHIPS)':
 'CD_VCC_CORE'<1>: CDS_PINID='CD_VCC_CORE(1)';
NODE_NAME     U5D1 BK13
 '@BASEBOARD_FAB2_LIB.BASEBOARD_FAB2(SCH_1):PAGE38_I34@CHPSET_LIB.SKX_EXT_B(CHIPS)':
 'CD_VCC_CORE'<2>: CDS_PINID='CD_VCC_CORE(2)';
NODE_NAME     U5D1 BJ14
 '@BASEBOARD_FAB2_LIB.BASEBOARD_FAB2(SCH_1):PAGE38_I34@CHPSET_LIB.SKX_EXT_B(CHIPS)':
 'CD_VCC_CORE'<3>: CDS_PINID='CD_VCC_CORE(3)';
NODE_NAME     U5D1 BJ12
 '@BASEBOARD_FAB2_LIB.BASEBOARD_FAB2(SCH_1):PAGE38_I34@CHPSET_LIB.SKX_EXT_B(CHIPS)':
 'CD_VCC_CORE'<4>: CDS_PINID='CD_VCC_CORE(4)';
NODE_NAME     U5D1 BH13
 '@BASEBOARD_FAB2_LIB.BASEBOARD_FAB2(SCH_1):PAGE38_I34@CHPSET_LIB.SKX_EXT_B(CHIPS)':
 'CD_VCC_CORE'<5>: CDS_PINID='CD_VCC_CORE(5)';
NODE_NAME     U5D1 BG14
 '@BASEBOARD_FAB2_LIB.BASEBOARD_FAB2(SCH_1):PAGE38_I34@CHPSET_LIB.SKX_EXT_B(CHIPS)':
 'CD_VCC_CORE'<6>: CDS_PINID='CD_VCC_CORE(6)';
NODE_NAME     U5D1 BG12
 '@BASEBOARD_FAB2_LIB.BASEBOARD_FAB2(SCH_1):PAGE38_I34@CHPSET_LIB.SKX_EXT_B(CHIPS)':
 'CD_VCC_CORE'<7>: CDS_PINID='CD_VCC_CORE(7)';
NODE_NAME     U5D1 BF13
 '@BASEBOARD_FAB2_LIB.BASEBOARD_FAB2(SCH_1):PAGE38_I34@CHPSET_LIB.SKX_EXT_B(CHIPS)':
 'CD_VCC_CORE'<8>: CDS_PINID='CD_VCC_CORE(8)';
NODE_NAME     U5D1 BF11
 '@BASEBOARD_FAB2_LIB.BASEBOARD_FAB2(SCH_1):PAGE38_I34@CHPSET_LIB.SKX_EXT_B(CHIPS)':
 'CD_VCC_CORE'<9>: CDS_PINID='CD_VCC_CORE(9)';
NODE_NAME     U5D1 BE14
 '@BASEBOARD_FAB2_LIB.BASEBOARD_FAB2(SCH_1):PAGE38_I34@CHPSET_LIB.SKX_EXT_B(CHIPS)':
 'CD_VCC_CORE'<10>: CDS_PINID='CD_VCC_CORE(10)';
NODE_NAME     U5D1 BE12
 '@BASEBOARD_FAB2_LIB.BASEBOARD_FAB2(SCH_1):PAGE38_I34@CHPSET_LIB.SKX_EXT_B(CHIPS)':
 'CD_VCC_CORE'<11>: CDS_PINID='CD_VCC_CORE(11)';
NODE_NAME     U5D1 BD13
 '@BASEBOARD_FAB2_LIB.BASEBOARD_FAB2(SCH_1):PAGE38_I34@CHPSET_LIB.SKX_EXT_B(CHIPS)':
 'CD_VCC_CORE'<12>: CDS_PINID='CD_VCC_CORE(12)';
NODE_NAME     U5D1 DA24
 '@BASEBOARD_FAB2_LIB.BASEBOARD_FAB2(SCH_1):PAGE39_I127@CHPSET_LIB.SKX_EXT_B(CHIPS)':
 'RSVD'<52>: CDS_PINID='RSVD(52)';
NODE_NAME     U5D1 CY25
 '@BASEBOARD_FAB2_LIB.BASEBOARD_FAB2(SCH_1):PAGE39_I127@CHPSET_LIB.SKX_EXT_B(CHIPS)':
 'RSVD'<58>: CDS_PINID='RSVD(58)';
NODE_NAME     U5D1 CW24
 '@BASEBOARD_FAB2_LIB.BASEBOARD_FAB2(SCH_1):PAGE39_I127@CHPSET_LIB.SKX_EXT_B(CHIPS)':
 'RSVD'<62>: CDS_PINID='RSVD(62)';
NODE_NAME     U5D1 CV23
 '@BASEBOARD_FAB2_LIB.BASEBOARD_FAB2(SCH_1):PAGE39_I127@CHPSET_LIB.SKX_EXT_B(CHIPS)':
 'RSVD'<65>: CDS_PINID='RSVD(65)';
NODE_NAME     U5D1 CU24
 '@BASEBOARD_FAB2_LIB.BASEBOARD_FAB2(SCH_1):PAGE39_I127@CHPSET_LIB.SKX_EXT_B(CHIPS)':
 'RSVD'<68>: CDS_PINID='RSVD(68)';
NODE_NAME     U5D1 CT23
 '@BASEBOARD_FAB2_LIB.BASEBOARD_FAB2(SCH_1):PAGE39_I127@CHPSET_LIB.SKX_EXT_B(CHIPS)':
 'RSVD'<71>: CDS_PINID='RSVD(71)';
NODE_NAME     U5D1 CP23
 '@BASEBOARD_FAB2_LIB.BASEBOARD_FAB2(SCH_1):PAGE39_I127@CHPSET_LIB.SKX_EXT_B(CHIPS)':
 'RSVD'<74>: CDS_PINID='RSVD(74)';
NODE_NAME     U5D1 CN24
 '@BASEBOARD_FAB2_LIB.BASEBOARD_FAB2(SCH_1):PAGE39_I127@CHPSET_LIB.SKX_EXT_B(CHIPS)':
 'RSVD'<76>: CDS_PINID='RSVD(76)';
NODE_NAME     U5D1 CM25
 '@BASEBOARD_FAB2_LIB.BASEBOARD_FAB2(SCH_1):PAGE39_I127@CHPSET_LIB.SKX_EXT_B(CHIPS)':
 'RSVD'<78>: CDS_PINID='RSVD(78)';
NODE_NAME     U5D1 CM23
 '@BASEBOARD_FAB2_LIB.BASEBOARD_FAB2(SCH_1):PAGE39_I127@CHPSET_LIB.SKX_EXT_B(CHIPS)':
 'RSVD'<79>: CDS_PINID='RSVD(79)';
NODE_NAME     U5D1 CL26
 '@BASEBOARD_FAB2_LIB.BASEBOARD_FAB2(SCH_1):PAGE39_I127@CHPSET_LIB.SKX_EXT_B(CHIPS)':
 'RSVD'<80>: CDS_PINID='RSVD(80)';
NODE_NAME     C6D8 1
 '@BASEBOARD_FAB2_LIB.BASEBOARD_FAB2(SCH_1):PAGE42_I68@DEV_DISCRETE.CAP_A(CHIPS)':
 'A': CDS_PINID='A';
NODE_NAME     C5D38 1
 '@BASEBOARD_FAB2_LIB.BASEBOARD_FAB2(SCH_1):PAGE42_I69@DEV_DISCRETE.CAP_A(CHIPS)':
 'A': CDS_PINID='A';
NODE_NAME     C5D37 1
 '@BASEBOARD_FAB2_LIB.BASEBOARD_FAB2(SCH_1):PAGE42_I70@DEV_DISCRETE.CAP_A(CHIPS)':
 'A': CDS_PINID='A';
NODE_NAME     C6D5 1
 '@BASEBOARD_FAB2_LIB.BASEBOARD_FAB2(SCH_1):PAGE42_I75@DEV_DISCRETE.CAP_A(CHIPS)':
 'A': CDS_PINID='A';
NODE_NAME     C6D2 1
 '@BASEBOARD_FAB2_LIB.BASEBOARD_FAB2(SCH_1):PAGE42_I77@DEV_DISCRETE.CAP_A(CHIPS)':
 'A': CDS_PINID='A';
NODE_NAME     C5D51 1
 '@BASEBOARD_FAB2_LIB.BASEBOARD_FAB2(SCH_1):PAGE42_I83@DEV_DISCRETE.CAP_A(CHIPS)':
 'A': CDS_PINID='A';
NODE_NAME     C5D21 1
 '@BASEBOARD_FAB2_LIB.BASEBOARD_FAB2(SCH_1):PAGE42_I88@DEV_DISCRETE.CAP_A(CHIPS)':
 'A': CDS_PINID='A';
NODE_NAME     C5D50 1
 '@BASEBOARD_FAB2_LIB.BASEBOARD_FAB2(SCH_1):PAGE42_I89@DEV_DISCRETE.CAP_A(CHIPS)':
 'A': CDS_PINID='A';
NODE_NAME     C5D48 1
 '@BASEBOARD_FAB2_LIB.BASEBOARD_FAB2(SCH_1):PAGE42_I90@DEV_DISCRETE.CAP_A(CHIPS)':
 'A': CDS_PINID='A';
NODE_NAME     C5D23 1
 '@BASEBOARD_FAB2_LIB.BASEBOARD_FAB2(SCH_1):PAGE42_I98@DEV_DISCRETE.CAP_A(CHIPS)':
 'A': CDS_PINID='A';
NODE_NAME     C5D36 1
 '@BASEBOARD_FAB2_LIB.BASEBOARD_FAB2(SCH_1):PAGE42_I151@DEV_DISCRETE.CAP_A(CHIPS)':
 'A': CDS_PINID='A';
NODE_NAME     C5D49 1
 '@BASEBOARD_FAB2_LIB.BASEBOARD_FAB2(SCH_1):PAGE42_I152@DEV_DISCRETE.CAP_A(CHIPS)':
 'A': CDS_PINID='A';
NODE_NAME     C5D22 1
 '@BASEBOARD_FAB2_LIB.BASEBOARD_FAB2(SCH_1):PAGE42_I153@DEV_DISCRETE.CAP_A(CHIPS)':
 'A': CDS_PINID='A';
NODE_NAME     C5D20 1
 '@BASEBOARD_FAB2_LIB.BASEBOARD_FAB2(SCH_1):PAGE42_I173@DEV_DISCRETE.CAP_A(CHIPS)':
 'A': CDS_PINID='A';
NODE_NAME     C5D33 1
 '@BASEBOARD_FAB2_LIB.BASEBOARD_FAB2(SCH_1):PAGE42_I174@DEV_DISCRETE.CAP_A(CHIPS)':
 'A': CDS_PINID='A';
NODE_NAME     C5D34 1
 '@BASEBOARD_FAB2_LIB.BASEBOARD_FAB2(SCH_1):PAGE42_I175@DEV_DISCRETE.CAP_A(CHIPS)':
 'A': CDS_PINID='A';
NODE_NAME     C5D35 1
 '@BASEBOARD_FAB2_LIB.BASEBOARD_FAB2(SCH_1):PAGE42_I176@DEV_DISCRETE.CAP_A(CHIPS)':
 'A': CDS_PINID='A';
NODE_NAME     C5D53 1
 '@BASEBOARD_FAB2_LIB.BASEBOARD_FAB2(SCH_1):PAGE42_I179@DEV_DISCRETE.CAP_A(CHIPS)':
 'A': CDS_PINID='A';
NODE_NAME     C5D52 1
 '@BASEBOARD_FAB2_LIB.BASEBOARD_FAB2(SCH_1):PAGE42_I180@DEV_DISCRETE.CAP_A(CHIPS)':
 'A': CDS_PINID='A';
NODE_NAME     C4R1 1
 '@BASEBOARD_FAB2_LIB.BASEBOARD_FAB2(SCH_1):PAGE194_I29@MSTR_DISCRETE.CAPP(CHIPS)':
 'A': CDS_PINID='A';
NODE_NAME     C3R4 1
 '@BASEBOARD_FAB2_LIB.BASEBOARD_FAB2(SCH_1):PAGE194_I31@MSTR_DISCRETE.CAPP(CHIPS)':
 'A': CDS_PINID='A';
NODE_NAME     J6E1 A1
 '@BASEBOARD_FAB2_LIB.BASEBOARD_FAB2(SCH_1):PAGE194_I55@MSTR_SCONN.SCONN120_H61426002(CHIPS)':
 'IOA1': CDS_PINID='IOA1';
NODE_NAME     J6E1 A2
 '@BASEBOARD_FAB2_LIB.BASEBOARD_FAB2(SCH_1):PAGE194_I55@MSTR_SCONN.SCONN120_H61426002(CHIPS)':
 'IOA2': CDS_PINID='IOA2';
NODE_NAME     J6E1 A3
 '@BASEBOARD_FAB2_LIB.BASEBOARD_FAB2(SCH_1):PAGE194_I55@MSTR_SCONN.SCONN120_H61426002(CHIPS)':
 'IOA3': CDS_PINID='IOA3';
NODE_NAME     J6E1 A5
 '@BASEBOARD_FAB2_LIB.BASEBOARD_FAB2(SCH_1):PAGE194_I55@MSTR_SCONN.SCONN120_H61426002(CHIPS)':
 'IOA5': CDS_PINID='IOA5';
NODE_NAME     J6E1 A6
 '@BASEBOARD_FAB2_LIB.BASEBOARD_FAB2(SCH_1):PAGE194_I55@MSTR_SCONN.SCONN120_H61426002(CHIPS)':
 'IOA6': CDS_PINID='IOA6';
NODE_NAME     J6E1 A7
 '@BASEBOARD_FAB2_LIB.BASEBOARD_FAB2(SCH_1):PAGE194_I55@MSTR_SCONN.SCONN120_H61426002(CHIPS)':
 'IOA7': CDS_PINID='IOA7';
NODE_NAME     J6E1 A8
 '@BASEBOARD_FAB2_LIB.BASEBOARD_FAB2(SCH_1):PAGE194_I55@MSTR_SCONN.SCONN120_H61426002(CHIPS)':
 'IOA8': CDS_PINID='IOA8';
NODE_NAME     J6E1 A9
 '@BASEBOARD_FAB2_LIB.BASEBOARD_FAB2(SCH_1):PAGE194_I55@MSTR_SCONN.SCONN120_H61426002(CHIPS)':
 'IOA9': CDS_PINID='IOA9';
NODE_NAME     J6E1 A10
 '@BASEBOARD_FAB2_LIB.BASEBOARD_FAB2(SCH_1):PAGE194_I55@MSTR_SCONN.SCONN120_H61426002(CHIPS)':
 'IOA10': CDS_PINID='IOA10';
NODE_NAME     J6E1 A11
 '@BASEBOARD_FAB2_LIB.BASEBOARD_FAB2(SCH_1):PAGE194_I55@MSTR_SCONN.SCONN120_H61426002(CHIPS)':
 'IOA11': CDS_PINID='IOA11';
NODE_NAME     J6E1 A12
 '@BASEBOARD_FAB2_LIB.BASEBOARD_FAB2(SCH_1):PAGE194_I55@MSTR_SCONN.SCONN120_H61426002(CHIPS)':
 'IOA12': CDS_PINID='IOA12';
NODE_NAME     J6E1 A13
 '@BASEBOARD_FAB2_LIB.BASEBOARD_FAB2(SCH_1):PAGE194_I55@MSTR_SCONN.SCONN120_H61426002(CHIPS)':
 'IOA13': CDS_PINID='IOA13';
NODE_NAME     J6E1 A14
 '@BASEBOARD_FAB2_LIB.BASEBOARD_FAB2(SCH_1):PAGE194_I55@MSTR_SCONN.SCONN120_H61426002(CHIPS)':
 'IOA14': CDS_PINID='IOA14';
NODE_NAME     J6E1 A15
 '@BASEBOARD_FAB2_LIB.BASEBOARD_FAB2(SCH_1):PAGE194_I55@MSTR_SCONN.SCONN120_H61426002(CHIPS)':
 'IOA15': CDS_PINID='IOA15';
NODE_NAME     J6E1 A16
 '@BASEBOARD_FAB2_LIB.BASEBOARD_FAB2(SCH_1):PAGE194_I55@MSTR_SCONN.SCONN120_H61426002(CHIPS)':
 'IOA16': CDS_PINID='IOA16';
NODE_NAME     J6E1 A17
 '@BASEBOARD_FAB2_LIB.BASEBOARD_FAB2(SCH_1):PAGE194_I55@MSTR_SCONN.SCONN120_H61426002(CHIPS)':
 'IOA17': CDS_PINID='IOA17';
NODE_NAME     J6E1 A18
 '@BASEBOARD_FAB2_LIB.BASEBOARD_FAB2(SCH_1):PAGE194_I55@MSTR_SCONN.SCONN120_H61426002(CHIPS)':
 'IOA18': CDS_PINID='IOA18';
NODE_NAME     J6E1 B1
 '@BASEBOARD_FAB2_LIB.BASEBOARD_FAB2(SCH_1):PAGE194_I55@MSTR_SCONN.SCONN120_H61426002(CHIPS)':
 'IOB1': CDS_PINID='IOB1';
NODE_NAME     J6E1 B2
 '@BASEBOARD_FAB2_LIB.BASEBOARD_FAB2(SCH_1):PAGE194_I55@MSTR_SCONN.SCONN120_H61426002(CHIPS)':
 'IOB2': CDS_PINID='IOB2';
NODE_NAME     J6E1 B3
 '@BASEBOARD_FAB2_LIB.BASEBOARD_FAB2(SCH_1):PAGE194_I55@MSTR_SCONN.SCONN120_H61426002(CHIPS)':
 'IOB3': CDS_PINID='IOB3';
NODE_NAME     J6E1 B5
 '@BASEBOARD_FAB2_LIB.BASEBOARD_FAB2(SCH_1):PAGE194_I55@MSTR_SCONN.SCONN120_H61426002(CHIPS)':
 'IOB5': CDS_PINID='IOB5';
NODE_NAME     J6E1 B6
 '@BASEBOARD_FAB2_LIB.BASEBOARD_FAB2(SCH_1):PAGE194_I55@MSTR_SCONN.SCONN120_H61426002(CHIPS)':
 'IOB6': CDS_PINID='IOB6';
NODE_NAME     J6E1 B7
 '@BASEBOARD_FAB2_LIB.BASEBOARD_FAB2(SCH_1):PAGE194_I55@MSTR_SCONN.SCONN120_H61426002(CHIPS)':
 'IOB7': CDS_PINID='IOB7';
NODE_NAME     J6E1 B8
 '@BASEBOARD_FAB2_LIB.BASEBOARD_FAB2(SCH_1):PAGE194_I55@MSTR_SCONN.SCONN120_H61426002(CHIPS)':
 'IOB8': CDS_PINID='IOB8';
NODE_NAME     J6E1 B9
 '@BASEBOARD_FAB2_LIB.BASEBOARD_FAB2(SCH_1):PAGE194_I55@MSTR_SCONN.SCONN120_H61426002(CHIPS)':
 'IOB9': CDS_PINID='IOB9';
NODE_NAME     J6E1 B10
 '@BASEBOARD_FAB2_LIB.BASEBOARD_FAB2(SCH_1):PAGE194_I55@MSTR_SCONN.SCONN120_H61426002(CHIPS)':
 'IOB10': CDS_PINID='IOB10';
NODE_NAME     J6E1 B11
 '@BASEBOARD_FAB2_LIB.BASEBOARD_FAB2(SCH_1):PAGE194_I55@MSTR_SCONN.SCONN120_H61426002(CHIPS)':
 'IOB11': CDS_PINID='IOB11';
NODE_NAME     J6E1 B12
 '@BASEBOARD_FAB2_LIB.BASEBOARD_FAB2(SCH_1):PAGE194_I55@MSTR_SCONN.SCONN120_H61426002(CHIPS)':
 'IOB12': CDS_PINID='IOB12';
NODE_NAME     J6E1 B13
 '@BASEBOARD_FAB2_LIB.BASEBOARD_FAB2(SCH_1):PAGE194_I55@MSTR_SCONN.SCONN120_H61426002(CHIPS)':
 'IOB13': CDS_PINID='IOB13';
NODE_NAME     J6E1 B14
 '@BASEBOARD_FAB2_LIB.BASEBOARD_FAB2(SCH_1):PAGE194_I55@MSTR_SCONN.SCONN120_H61426002(CHIPS)':
 'IOB14': CDS_PINID='IOB14';
NODE_NAME     J6E1 B15
 '@BASEBOARD_FAB2_LIB.BASEBOARD_FAB2(SCH_1):PAGE194_I55@MSTR_SCONN.SCONN120_H61426002(CHIPS)':
 'IOB15': CDS_PINID='IOB15';
NODE_NAME     J6E1 B16
 '@BASEBOARD_FAB2_LIB.BASEBOARD_FAB2(SCH_1):PAGE194_I55@MSTR_SCONN.SCONN120_H61426002(CHIPS)':
 'IOB16': CDS_PINID='IOB16';
NODE_NAME     J6E1 B17
 '@BASEBOARD_FAB2_LIB.BASEBOARD_FAB2(SCH_1):PAGE194_I55@MSTR_SCONN.SCONN120_H61426002(CHIPS)':
 'IOB17': CDS_PINID='IOB17';
NODE_NAME     J6E1 B18
 '@BASEBOARD_FAB2_LIB.BASEBOARD_FAB2(SCH_1):PAGE194_I55@MSTR_SCONN.SCONN120_H61426002(CHIPS)':
 'IOB18': CDS_PINID='IOB18';
NODE_NAME     J6E1 C1
 '@BASEBOARD_FAB2_LIB.BASEBOARD_FAB2(SCH_1):PAGE194_I55@MSTR_SCONN.SCONN120_H61426002(CHIPS)':
 'IOC1': CDS_PINID='IOC1';
NODE_NAME     J6E1 C2
 '@BASEBOARD_FAB2_LIB.BASEBOARD_FAB2(SCH_1):PAGE194_I55@MSTR_SCONN.SCONN120_H61426002(CHIPS)':
 'IOC2': CDS_PINID='IOC2';
NODE_NAME     J6E1 C3
 '@BASEBOARD_FAB2_LIB.BASEBOARD_FAB2(SCH_1):PAGE194_I55@MSTR_SCONN.SCONN120_H61426002(CHIPS)':
 'IOC3': CDS_PINID='IOC3';
NODE_NAME     J6E1 C4
 '@BASEBOARD_FAB2_LIB.BASEBOARD_FAB2(SCH_1):PAGE194_I55@MSTR_SCONN.SCONN120_H61426002(CHIPS)':
 'IOC4': CDS_PINID='IOC4';
NODE_NAME     J6E1 C5
 '@BASEBOARD_FAB2_LIB.BASEBOARD_FAB2(SCH_1):PAGE194_I55@MSTR_SCONN.SCONN120_H61426002(CHIPS)':
 'IOC5': CDS_PINID='IOC5';
NODE_NAME     J6E1 C6
 '@BASEBOARD_FAB2_LIB.BASEBOARD_FAB2(SCH_1):PAGE194_I55@MSTR_SCONN.SCONN120_H61426002(CHIPS)':
 'IOC6': CDS_PINID='IOC6';
NODE_NAME     J6E1 C7
 '@BASEBOARD_FAB2_LIB.BASEBOARD_FAB2(SCH_1):PAGE194_I55@MSTR_SCONN.SCONN120_H61426002(CHIPS)':
 'IOC7': CDS_PINID='IOC7';
NODE_NAME     J6E1 C8
 '@BASEBOARD_FAB2_LIB.BASEBOARD_FAB2(SCH_1):PAGE194_I55@MSTR_SCONN.SCONN120_H61426002(CHIPS)':
 'IOC8': CDS_PINID='IOC8';
NODE_NAME     J6E1 C9
 '@BASEBOARD_FAB2_LIB.BASEBOARD_FAB2(SCH_1):PAGE194_I55@MSTR_SCONN.SCONN120_H61426002(CHIPS)':
 'IOC9': CDS_PINID='IOC9';
NODE_NAME     J6E1 C10
 '@BASEBOARD_FAB2_LIB.BASEBOARD_FAB2(SCH_1):PAGE194_I55@MSTR_SCONN.SCONN120_H61426002(CHIPS)':
 'IOC10': CDS_PINID='IOC10';
NODE_NAME     J6E1 C11
 '@BASEBOARD_FAB2_LIB.BASEBOARD_FAB2(SCH_1):PAGE194_I55@MSTR_SCONN.SCONN120_H61426002(CHIPS)':
 'IOC11': CDS_PINID='IOC11';
NODE_NAME     J6E1 C12
 '@BASEBOARD_FAB2_LIB.BASEBOARD_FAB2(SCH_1):PAGE194_I55@MSTR_SCONN.SCONN120_H61426002(CHIPS)':
 'IOC12': CDS_PINID='IOC12';
NODE_NAME     J6E1 C13
 '@BASEBOARD_FAB2_LIB.BASEBOARD_FAB2(SCH_1):PAGE194_I55@MSTR_SCONN.SCONN120_H61426002(CHIPS)':
 'IOC13': CDS_PINID='IOC13';
NODE_NAME     J6E1 C14
 '@BASEBOARD_FAB2_LIB.BASEBOARD_FAB2(SCH_1):PAGE194_I55@MSTR_SCONN.SCONN120_H61426002(CHIPS)':
 'IOC14': CDS_PINID='IOC14';
NODE_NAME     J6E1 C15
 '@BASEBOARD_FAB2_LIB.BASEBOARD_FAB2(SCH_1):PAGE194_I55@MSTR_SCONN.SCONN120_H61426002(CHIPS)':
 'IOC15': CDS_PINID='IOC15';
NODE_NAME     J6E1 C16
 '@BASEBOARD_FAB2_LIB.BASEBOARD_FAB2(SCH_1):PAGE194_I55@MSTR_SCONN.SCONN120_H61426002(CHIPS)':
 'IOC16': CDS_PINID='IOC16';
NODE_NAME     J6E1 C17
 '@BASEBOARD_FAB2_LIB.BASEBOARD_FAB2(SCH_1):PAGE194_I55@MSTR_SCONN.SCONN120_H61426002(CHIPS)':
 'IOC17': CDS_PINID='IOC17';
NODE_NAME     J6E1 C18
 '@BASEBOARD_FAB2_LIB.BASEBOARD_FAB2(SCH_1):PAGE194_I55@MSTR_SCONN.SCONN120_H61426002(CHIPS)':
 'IOC18': CDS_PINID='IOC18';
NODE_NAME     C5W1 1
 '@BASEBOARD_FAB2_LIB.BASEBOARD_FAB2(SCH_1):PAGE42_I217@DEV_DISCRETE.CAP_A(CHIPS)':
 'A': CDS_PINID='A';
NODE_NAME     C5W2 1
 '@BASEBOARD_FAB2_LIB.BASEBOARD_FAB2(SCH_1):PAGE42_I218@DEV_DISCRETE.CAP_A(CHIPS)':
 'A': CDS_PINID='A';
NODE_NAME     C5P29 1
 '@BASEBOARD_FAB2_LIB.BASEBOARD_FAB2(SCH_1):PAGE42_I220@MSTR_DISCRETE.CAP(CHIPS)':
 'A': CDS_PINID='A';
NODE_NAME     C5P30 1
 '@BASEBOARD_FAB2_LIB.BASEBOARD_FAB2(SCH_1):PAGE42_I221@MSTR_DISCRETE.CAP(CHIPS)':
 'A': CDS_PINID='A';
NODE_NAME     C5P19 1
 '@BASEBOARD_FAB2_LIB.BASEBOARD_FAB2(SCH_1):PAGE42_I222@MSTR_DISCRETE.CAP(CHIPS)':
 'A': CDS_PINID='A';
NODE_NAME     C4P4 1
 '@BASEBOARD_FAB2_LIB.BASEBOARD_FAB2(SCH_1):PAGE42_I223@MSTR_DISCRETE.CAP(CHIPS)':
 'A': CDS_PINID='A';
NODE_NAME     C4P7 1
 '@BASEBOARD_FAB2_LIB.BASEBOARD_FAB2(SCH_1):PAGE42_I224@MSTR_DISCRETE.CAP(CHIPS)':
 'A': CDS_PINID='A';
NODE_NAME     C4P3 1
 '@BASEBOARD_FAB2_LIB.BASEBOARD_FAB2(SCH_1):PAGE42_I225@MSTR_DISCRETE.CAP(CHIPS)':
 'A': CDS_PINID='A';
NODE_NAME     C5P10 1
 '@BASEBOARD_FAB2_LIB.BASEBOARD_FAB2(SCH_1):PAGE42_I226@MSTR_DISCRETE.CAP(CHIPS)':
 'A': CDS_PINID='A';
NODE_NAME     C5P11 1
 '@BASEBOARD_FAB2_LIB.BASEBOARD_FAB2(SCH_1):PAGE42_I227@MSTR_DISCRETE.CAP(CHIPS)':
 'A': CDS_PINID='A';
NODE_NAME     C5P18 1
 '@BASEBOARD_FAB2_LIB.BASEBOARD_FAB2(SCH_1):PAGE42_I228@MSTR_DISCRETE.CAP(CHIPS)':
 'A': CDS_PINID='A';
NODE_NAME     C5P28 1
 '@BASEBOARD_FAB2_LIB.BASEBOARD_FAB2(SCH_1):PAGE42_I229@MSTR_DISCRETE.CAP(CHIPS)':
 'A': CDS_PINID='A';
NODE_NAME     C4P2 1
 '@BASEBOARD_FAB2_LIB.BASEBOARD_FAB2(SCH_1):PAGE42_I230@MSTR_DISCRETE.CAP(CHIPS)':
 'A': CDS_PINID='A';
NODE_NAME     C5P31 1
 '@BASEBOARD_FAB2_LIB.BASEBOARD_FAB2(SCH_1):PAGE42_I231@MSTR_DISCRETE.CAP(CHIPS)':
 'A': CDS_PINID='A';
NODE_NAME     C5P13 1
 '@BASEBOARD_FAB2_LIB.BASEBOARD_FAB2(SCH_1):PAGE42_I232@MSTR_DISCRETE.CAP(CHIPS)':
 'A': CDS_PINID='A';
NODE_NAME     C4P5 1
 '@BASEBOARD_FAB2_LIB.BASEBOARD_FAB2(SCH_1):PAGE42_I233@MSTR_DISCRETE.CAP(CHIPS)':
 'A': CDS_PINID='A';
NODE_NAME     C5P20 1
 '@BASEBOARD_FAB2_LIB.BASEBOARD_FAB2(SCH_1):PAGE42_I234@MSTR_DISCRETE.CAP(CHIPS)':
 'A': CDS_PINID='A';
NODE_NAME     C5P21 1
 '@BASEBOARD_FAB2_LIB.BASEBOARD_FAB2(SCH_1):PAGE42_I235@MSTR_DISCRETE.CAP(CHIPS)':
 'A': CDS_PINID='A';
NODE_NAME     C5P12 1
 '@BASEBOARD_FAB2_LIB.BASEBOARD_FAB2(SCH_1):PAGE42_I236@MSTR_DISCRETE.CAP(CHIPS)':
 'A': CDS_PINID='A';
NET_NAME
'PVCCMCP_CPU1'
 '@BASEBOARD_FAB2_LIB.BASEBOARD_FAB2(SCH_1):PVCCMCP_CPU1':
 C_SIGNAL='@baseboard_fab2_lib.baseboard_fab2(sch_1):pvccmcp_cpu1';
NODE_NAME     U2D1 AP25
 '@BASEBOARD_FAB2_LIB.BASEBOARD_FAB2(SCH_1):PAGE56_I169@CHPSET_LIB.SKX_EXT_B(CHIPS)':
 'RSVD'<196>: CDS_PINID='RSVD(196)';
NODE_NAME     U2D1 AP23
 '@BASEBOARD_FAB2_LIB.BASEBOARD_FAB2(SCH_1):PAGE56_I169@CHPSET_LIB.SKX_EXT_B(CHIPS)':
 'RSVD'<197>: CDS_PINID='RSVD(197)';
NODE_NAME     U2D1 AN26
 '@BASEBOARD_FAB2_LIB.BASEBOARD_FAB2(SCH_1):PAGE56_I169@CHPSET_LIB.SKX_EXT_B(CHIPS)':
 'RSVD'<200>: CDS_PINID='RSVD(200)';
NODE_NAME     U2D1 AN24
 '@BASEBOARD_FAB2_LIB.BASEBOARD_FAB2(SCH_1):PAGE56_I169@CHPSET_LIB.SKX_EXT_B(CHIPS)':
 'RSVD'<201>: CDS_PINID='RSVD(201)';
NODE_NAME     U2D1 AN22
 '@BASEBOARD_FAB2_LIB.BASEBOARD_FAB2(SCH_1):PAGE56_I169@CHPSET_LIB.SKX_EXT_B(CHIPS)':
 'RSVD'<202>: CDS_PINID='RSVD(202)';
NODE_NAME     U2D1 AN18
 '@BASEBOARD_FAB2_LIB.BASEBOARD_FAB2(SCH_1):PAGE56_I169@CHPSET_LIB.SKX_EXT_B(CHIPS)':
 'RSVD'<203>: CDS_PINID='RSVD(203)';
NODE_NAME     U2D1 AM25
 '@BASEBOARD_FAB2_LIB.BASEBOARD_FAB2(SCH_1):PAGE56_I169@CHPSET_LIB.SKX_EXT_B(CHIPS)':
 'RSVD'<207>: CDS_PINID='RSVD(207)';
NODE_NAME     U2D1 AM21
 '@BASEBOARD_FAB2_LIB.BASEBOARD_FAB2(SCH_1):PAGE56_I169@CHPSET_LIB.SKX_EXT_B(CHIPS)':
 'RSVD'<209>: CDS_PINID='RSVD(209)';
NODE_NAME     U2D1 AT25
 '@BASEBOARD_FAB2_LIB.BASEBOARD_FAB2(SCH_1):PAGE63_I23@CHPSET_LIB.SKX_EXT_B(CHIPS)':
 'RSVD'<187>: CDS_PINID='RSVD(187)';
NODE_NAME     U2D1 AT23
 '@BASEBOARD_FAB2_LIB.BASEBOARD_FAB2(SCH_1):PAGE63_I23@CHPSET_LIB.SKX_EXT_B(CHIPS)':
 'RSVD'<188>: CDS_PINID='RSVD(188)';
NODE_NAME     U2D1 AR26
 '@BASEBOARD_FAB2_LIB.BASEBOARD_FAB2(SCH_1):PAGE63_I23@CHPSET_LIB.SKX_EXT_B(CHIPS)':
 'RSVD'<191>: CDS_PINID='RSVD(191)';
NODE_NAME     U2D1 AR22
 '@BASEBOARD_FAB2_LIB.BASEBOARD_FAB2(SCH_1):PAGE63_I23@CHPSET_LIB.SKX_EXT_B(CHIPS)':
 'RSVD'<192>: CDS_PINID='RSVD(192)';
NODE_NAME     U2D1 AR20
 '@BASEBOARD_FAB2_LIB.BASEBOARD_FAB2(SCH_1):PAGE63_I23@CHPSET_LIB.SKX_EXT_B(CHIPS)':
 'RSVD'<193>: CDS_PINID='RSVD(193)';
NODE_NAME     U2D1 CH23
 '@BASEBOARD_FAB2_LIB.BASEBOARD_FAB2(SCH_1):PAGE70_I9@CHPSET_LIB.SKX_EXT_B(CHIPS)':
 'RSVD'<92>: CDS_PINID='RSVD(92)';
NODE_NAME     U2D1 CH21
 '@BASEBOARD_FAB2_LIB.BASEBOARD_FAB2(SCH_1):PAGE70_I9@CHPSET_LIB.SKX_EXT_B(CHIPS)':
 'RSVD'<93>: CDS_PINID='RSVD(93)';
NODE_NAME     U2D1 CG26
 '@BASEBOARD_FAB2_LIB.BASEBOARD_FAB2(SCH_1):PAGE70_I9@CHPSET_LIB.SKX_EXT_B(CHIPS)':
 'RSVD'<96>: CDS_PINID='RSVD(96)';
NODE_NAME     U2D1 CG20
 '@BASEBOARD_FAB2_LIB.BASEBOARD_FAB2(SCH_1):PAGE70_I9@CHPSET_LIB.SKX_EXT_B(CHIPS)':
 'RSVD'<98>: CDS_PINID='RSVD(98)';
NODE_NAME     U2D1 CF23
 '@BASEBOARD_FAB2_LIB.BASEBOARD_FAB2(SCH_1):PAGE70_I9@CHPSET_LIB.SKX_EXT_B(CHIPS)':
 'RSVD'<102>: CDS_PINID='RSVD(102)';
NODE_NAME     U2D1 CF21
 '@BASEBOARD_FAB2_LIB.BASEBOARD_FAB2(SCH_1):PAGE70_I9@CHPSET_LIB.SKX_EXT_B(CHIPS)':
 'RSVD'<103>: CDS_PINID='RSVD(103)';
NODE_NAME     U2D1 CF19
 '@BASEBOARD_FAB2_LIB.BASEBOARD_FAB2(SCH_1):PAGE70_I9@CHPSET_LIB.SKX_EXT_B(CHIPS)':
 'RSVD'<104>: CDS_PINID='RSVD(104)';
NODE_NAME     U2D1 CE22
 '@BASEBOARD_FAB2_LIB.BASEBOARD_FAB2(SCH_1):PAGE70_I9@CHPSET_LIB.SKX_EXT_B(CHIPS)':
 'RSVD'<107>: CDS_PINID='RSVD(107)';
NODE_NAME     U2D1 CD21
 '@BASEBOARD_FAB2_LIB.BASEBOARD_FAB2(SCH_1):PAGE70_I9@CHPSET_LIB.SKX_EXT_B(CHIPS)':
 'RSVD'<109>: CDS_PINID='RSVD(109)';
NODE_NAME     U2D1 CD19
 '@BASEBOARD_FAB2_LIB.BASEBOARD_FAB2(SCH_1):PAGE70_I9@CHPSET_LIB.SKX_EXT_B(CHIPS)':
 'RSVD'<110>: CDS_PINID='RSVD(110)';
NODE_NAME     U2D1 CC20
 '@BASEBOARD_FAB2_LIB.BASEBOARD_FAB2(SCH_1):PAGE70_I9@CHPSET_LIB.SKX_EXT_B(CHIPS)':
 'RSVD'<112>: CDS_PINID='RSVD(112)';
NODE_NAME     U2D1 CB21
 '@BASEBOARD_FAB2_LIB.BASEBOARD_FAB2(SCH_1):PAGE70_I9@CHPSET_LIB.SKX_EXT_B(CHIPS)':
 'RSVD'<115>: CDS_PINID='RSVD(115)';
NODE_NAME     U2D1 CB19
 '@BASEBOARD_FAB2_LIB.BASEBOARD_FAB2(SCH_1):PAGE70_I9@CHPSET_LIB.SKX_EXT_B(CHIPS)':
 'RSVD'<116>: CDS_PINID='RSVD(116)';
NODE_NAME     U2D1 CA22
 '@BASEBOARD_FAB2_LIB.BASEBOARD_FAB2(SCH_1):PAGE70_I9@CHPSET_LIB.SKX_EXT_B(CHIPS)':
 'RSVD'<118>: CDS_PINID='RSVD(118)';
NODE_NAME     U2D1 BY19
 '@BASEBOARD_FAB2_LIB.BASEBOARD_FAB2(SCH_1):PAGE70_I9@CHPSET_LIB.SKX_EXT_B(CHIPS)':
 'RSVD'<120>: CDS_PINID='RSVD(120)';
NODE_NAME     U2D1 BW20
 '@BASEBOARD_FAB2_LIB.BASEBOARD_FAB2(SCH_1):PAGE70_I9@CHPSET_LIB.SKX_EXT_B(CHIPS)':
 'RSVD'<122>: CDS_PINID='RSVD(122)';
NODE_NAME     U2D1 BV21
 '@BASEBOARD_FAB2_LIB.BASEBOARD_FAB2(SCH_1):PAGE70_I9@CHPSET_LIB.SKX_EXT_B(CHIPS)':
 'RSVD'<125>: CDS_PINID='RSVD(125)';
NODE_NAME     U2D1 BV19
 '@BASEBOARD_FAB2_LIB.BASEBOARD_FAB2(SCH_1):PAGE70_I9@CHPSET_LIB.SKX_EXT_B(CHIPS)':
 'RSVD'<126>: CDS_PINID='RSVD(126)';
NODE_NAME     U2D1 BU22
 '@BASEBOARD_FAB2_LIB.BASEBOARD_FAB2(SCH_1):PAGE70_I9@CHPSET_LIB.SKX_EXT_B(CHIPS)':
 'RSVD'<127>: CDS_PINID='RSVD(127)';
NODE_NAME     U2D1 BU20
 '@BASEBOARD_FAB2_LIB.BASEBOARD_FAB2(SCH_1):PAGE70_I9@CHPSET_LIB.SKX_EXT_B(CHIPS)':
 'RSVD'<128>: CDS_PINID='RSVD(128)';
NODE_NAME     U2D1 BR24
 '@BASEBOARD_FAB2_LIB.BASEBOARD_FAB2(SCH_1):PAGE70_I9@CHPSET_LIB.SKX_EXT_B(CHIPS)':
 'RSVD'<130>: CDS_PINID='RSVD(130)';
NODE_NAME     U2D1 BR22
 '@BASEBOARD_FAB2_LIB.BASEBOARD_FAB2(SCH_1):PAGE70_I9@CHPSET_LIB.SKX_EXT_B(CHIPS)':
 'RSVD'<131>: CDS_PINID='RSVD(131)';
NODE_NAME     U2D1 BP21
 '@BASEBOARD_FAB2_LIB.BASEBOARD_FAB2(SCH_1):PAGE70_I9@CHPSET_LIB.SKX_EXT_B(CHIPS)':
 'RSVD'<132>: CDS_PINID='RSVD(132)';
NODE_NAME     U2D1 BM19
 '@BASEBOARD_FAB2_LIB.BASEBOARD_FAB2(SCH_1):PAGE70_I9@CHPSET_LIB.SKX_EXT_B(CHIPS)':
 'RSVD'<135>: CDS_PINID='RSVD(135)';
NODE_NAME     U2D1 BL20
 '@BASEBOARD_FAB2_LIB.BASEBOARD_FAB2(SCH_1):PAGE70_I9@CHPSET_LIB.SKX_EXT_B(CHIPS)':
 'RSVD'<137>: CDS_PINID='RSVD(137)';
NODE_NAME     U2D1 BK17
 '@BASEBOARD_FAB2_LIB.BASEBOARD_FAB2(SCH_1):PAGE70_I9@CHPSET_LIB.SKX_EXT_B(CHIPS)':
 'RSVD'<139>: CDS_PINID='RSVD(139)';
NODE_NAME     U2D1 BJ20
 '@BASEBOARD_FAB2_LIB.BASEBOARD_FAB2(SCH_1):PAGE70_I9@CHPSET_LIB.SKX_EXT_B(CHIPS)':
 'RSVD'<140>: CDS_PINID='RSVD(140)';
NODE_NAME     U2D1 BJ18
 '@BASEBOARD_FAB2_LIB.BASEBOARD_FAB2(SCH_1):PAGE70_I9@CHPSET_LIB.SKX_EXT_B(CHIPS)':
 'RSVD'<141>: CDS_PINID='RSVD(141)';
NODE_NAME     U2D1 BJ16
 '@BASEBOARD_FAB2_LIB.BASEBOARD_FAB2(SCH_1):PAGE70_I9@CHPSET_LIB.SKX_EXT_B(CHIPS)':
 'RSVD'<142>: CDS_PINID='RSVD(142)';
NODE_NAME     U2D1 BH19
 '@BASEBOARD_FAB2_LIB.BASEBOARD_FAB2(SCH_1):PAGE70_I9@CHPSET_LIB.SKX_EXT_B(CHIPS)':
 'RSVD'<143>: CDS_PINID='RSVD(143)';
NODE_NAME     U2D1 CL24
 '@BASEBOARD_FAB2_LIB.BASEBOARD_FAB2(SCH_1):PAGE70_I10@CHPSET_LIB.SKX_EXT_B(CHIPS)':
 'RSVD'<81>: CDS_PINID='RSVD(81)';
NODE_NAME     U2D1 CK25
 '@BASEBOARD_FAB2_LIB.BASEBOARD_FAB2(SCH_1):PAGE70_I10@CHPSET_LIB.SKX_EXT_B(CHIPS)':
 'RSVD'<83>: CDS_PINID='RSVD(83)';
NODE_NAME     U2D1 CK23
 '@BASEBOARD_FAB2_LIB.BASEBOARD_FAB2(SCH_1):PAGE70_I10@CHPSET_LIB.SKX_EXT_B(CHIPS)':
 'RSVD'<84>: CDS_PINID='RSVD(84)';
NODE_NAME     U2D1 CJ26
 '@BASEBOARD_FAB2_LIB.BASEBOARD_FAB2(SCH_1):PAGE70_I10@CHPSET_LIB.SKX_EXT_B(CHIPS)':
 'RSVD'<86>: CDS_PINID='RSVD(86)';
NODE_NAME     U2D1 CJ24
 '@BASEBOARD_FAB2_LIB.BASEBOARD_FAB2(SCH_1):PAGE70_I10@CHPSET_LIB.SKX_EXT_B(CHIPS)':
 'RSVD'<87>: CDS_PINID='RSVD(87)';
NODE_NAME     U2D1 CJ22
 '@BASEBOARD_FAB2_LIB.BASEBOARD_FAB2(SCH_1):PAGE70_I10@CHPSET_LIB.SKX_EXT_B(CHIPS)':
 'RSVD'<88>: CDS_PINID='RSVD(88)';
NODE_NAME     U2D1 CJ20
 '@BASEBOARD_FAB2_LIB.BASEBOARD_FAB2(SCH_1):PAGE70_I10@CHPSET_LIB.SKX_EXT_B(CHIPS)':
 'RSVD'<89>: CDS_PINID='RSVD(89)';
NODE_NAME     U2D1 BL14
 '@BASEBOARD_FAB2_LIB.BASEBOARD_FAB2(SCH_1):PAGE72_I33@CHPSET_LIB.SKX_EXT_B(CHIPS)':
 'CD_VCC_CORE'<0>: CDS_PINID='CD_VCC_CORE(0)';
NODE_NAME     U2D1 BK15
 '@BASEBOARD_FAB2_LIB.BASEBOARD_FAB2(SCH_1):PAGE72_I33@CHPSET_LIB.SKX_EXT_B(CHIPS)':
 'CD_VCC_CORE'<1>: CDS_PINID='CD_VCC_CORE(1)';
NODE_NAME     U2D1 BK13
 '@BASEBOARD_FAB2_LIB.BASEBOARD_FAB2(SCH_1):PAGE72_I33@CHPSET_LIB.SKX_EXT_B(CHIPS)':
 'CD_VCC_CORE'<2>: CDS_PINID='CD_VCC_CORE(2)';
NODE_NAME     U2D1 BJ14
 '@BASEBOARD_FAB2_LIB.BASEBOARD_FAB2(SCH_1):PAGE72_I33@CHPSET_LIB.SKX_EXT_B(CHIPS)':
 'CD_VCC_CORE'<3>: CDS_PINID='CD_VCC_CORE(3)';
NODE_NAME     U2D1 BJ12
 '@BASEBOARD_FAB2_LIB.BASEBOARD_FAB2(SCH_1):PAGE72_I33@CHPSET_LIB.SKX_EXT_B(CHIPS)':
 'CD_VCC_CORE'<4>: CDS_PINID='CD_VCC_CORE(4)';
NODE_NAME     U2D1 BH13
 '@BASEBOARD_FAB2_LIB.BASEBOARD_FAB2(SCH_1):PAGE72_I33@CHPSET_LIB.SKX_EXT_B(CHIPS)':
 'CD_VCC_CORE'<5>: CDS_PINID='CD_VCC_CORE(5)';
NODE_NAME     U2D1 BG14
 '@BASEBOARD_FAB2_LIB.BASEBOARD_FAB2(SCH_1):PAGE72_I33@CHPSET_LIB.SKX_EXT_B(CHIPS)':
 'CD_VCC_CORE'<6>: CDS_PINID='CD_VCC_CORE(6)';
NODE_NAME     U2D1 BG12
 '@BASEBOARD_FAB2_LIB.BASEBOARD_FAB2(SCH_1):PAGE72_I33@CHPSET_LIB.SKX_EXT_B(CHIPS)':
 'CD_VCC_CORE'<7>: CDS_PINID='CD_VCC_CORE(7)';
NODE_NAME     U2D1 BF13
 '@BASEBOARD_FAB2_LIB.BASEBOARD_FAB2(SCH_1):PAGE72_I33@CHPSET_LIB.SKX_EXT_B(CHIPS)':
 'CD_VCC_CORE'<8>: CDS_PINID='CD_VCC_CORE(8)';
NODE_NAME     U2D1 BF11
 '@BASEBOARD_FAB2_LIB.BASEBOARD_FAB2(SCH_1):PAGE72_I33@CHPSET_LIB.SKX_EXT_B(CHIPS)':
 'CD_VCC_CORE'<9>: CDS_PINID='CD_VCC_CORE(9)';
NODE_NAME     U2D1 BE14
 '@BASEBOARD_FAB2_LIB.BASEBOARD_FAB2(SCH_1):PAGE72_I33@CHPSET_LIB.SKX_EXT_B(CHIPS)':
 'CD_VCC_CORE'<10>: CDS_PINID='CD_VCC_CORE(10)';
NODE_NAME     U2D1 BE12
 '@BASEBOARD_FAB2_LIB.BASEBOARD_FAB2(SCH_1):PAGE72_I33@CHPSET_LIB.SKX_EXT_B(CHIPS)':
 'CD_VCC_CORE'<11>: CDS_PINID='CD_VCC_CORE(11)';
NODE_NAME     U2D1 BD13
 '@BASEBOARD_FAB2_LIB.BASEBOARD_FAB2(SCH_1):PAGE72_I33@CHPSET_LIB.SKX_EXT_B(CHIPS)':
 'CD_VCC_CORE'<12>: CDS_PINID='CD_VCC_CORE(12)';
NODE_NAME     U2D1 DA24
 '@BASEBOARD_FAB2_LIB.BASEBOARD_FAB2(SCH_1):PAGE73_I107@CHPSET_LIB.SKX_EXT_B(CHIPS)':
 'RSVD'<52>: CDS_PINID='RSVD(52)';
NODE_NAME     U2D1 CY25
 '@BASEBOARD_FAB2_LIB.BASEBOARD_FAB2(SCH_1):PAGE73_I107@CHPSET_LIB.SKX_EXT_B(CHIPS)':
 'RSVD'<58>: CDS_PINID='RSVD(58)';
NODE_NAME     U2D1 CW24
 '@BASEBOARD_FAB2_LIB.BASEBOARD_FAB2(SCH_1):PAGE73_I107@CHPSET_LIB.SKX_EXT_B(CHIPS)':
 'RSVD'<62>: CDS_PINID='RSVD(62)';
NODE_NAME     U2D1 CV23
 '@BASEBOARD_FAB2_LIB.BASEBOARD_FAB2(SCH_1):PAGE73_I107@CHPSET_LIB.SKX_EXT_B(CHIPS)':
 'RSVD'<65>: CDS_PINID='RSVD(65)';
NODE_NAME     U2D1 CU24
 '@BASEBOARD_FAB2_LIB.BASEBOARD_FAB2(SCH_1):PAGE73_I107@CHPSET_LIB.SKX_EXT_B(CHIPS)':
 'RSVD'<68>: CDS_PINID='RSVD(68)';
NODE_NAME     U2D1 CT23
 '@BASEBOARD_FAB2_LIB.BASEBOARD_FAB2(SCH_1):PAGE73_I107@CHPSET_LIB.SKX_EXT_B(CHIPS)':
 'RSVD'<71>: CDS_PINID='RSVD(71)';
NODE_NAME     U2D1 CP23
 '@BASEBOARD_FAB2_LIB.BASEBOARD_FAB2(SCH_1):PAGE73_I107@CHPSET_LIB.SKX_EXT_B(CHIPS)':
 'RSVD'<74>: CDS_PINID='RSVD(74)';
NODE_NAME     U2D1 CN24
 '@BASEBOARD_FAB2_LIB.BASEBOARD_FAB2(SCH_1):PAGE73_I107@CHPSET_LIB.SKX_EXT_B(CHIPS)':
 'RSVD'<76>: CDS_PINID='RSVD(76)';
NODE_NAME     U2D1 CM25
 '@BASEBOARD_FAB2_LIB.BASEBOARD_FAB2(SCH_1):PAGE73_I107@CHPSET_LIB.SKX_EXT_B(CHIPS)':
 'RSVD'<78>: CDS_PINID='RSVD(78)';
NODE_NAME     U2D1 CM23
 '@BASEBOARD_FAB2_LIB.BASEBOARD_FAB2(SCH_1):PAGE73_I107@CHPSET_LIB.SKX_EXT_B(CHIPS)':
 'RSVD'<79>: CDS_PINID='RSVD(79)';
NODE_NAME     U2D1 CL26
 '@BASEBOARD_FAB2_LIB.BASEBOARD_FAB2(SCH_1):PAGE73_I107@CHPSET_LIB.SKX_EXT_B(CHIPS)':
 'RSVD'<80>: CDS_PINID='RSVD(80)';
NODE_NAME     C3D21 1
 '@BASEBOARD_FAB2_LIB.BASEBOARD_FAB2(SCH_1):PAGE76_I1@DEV_DISCRETE.CAP_A(CHIPS)':
 'A': CDS_PINID='A';
NODE_NAME     C3D5 1
 '@BASEBOARD_FAB2_LIB.BASEBOARD_FAB2(SCH_1):PAGE76_I3@DEV_DISCRETE.CAP_A(CHIPS)':
 'A': CDS_PINID='A';
NODE_NAME     C3D12 1
 '@BASEBOARD_FAB2_LIB.BASEBOARD_FAB2(SCH_1):PAGE76_I4@DEV_DISCRETE.CAP_A(CHIPS)':
 'A': CDS_PINID='A';
NODE_NAME     C3D4 1
 '@BASEBOARD_FAB2_LIB.BASEBOARD_FAB2(SCH_1):PAGE76_I5@DEV_DISCRETE.CAP_A(CHIPS)':
 'A': CDS_PINID='A';
NODE_NAME     C3D11 1
 '@BASEBOARD_FAB2_LIB.BASEBOARD_FAB2(SCH_1):PAGE76_I7@DEV_DISCRETE.CAP_A(CHIPS)':
 'A': CDS_PINID='A';
NODE_NAME     C3D13 1
 '@BASEBOARD_FAB2_LIB.BASEBOARD_FAB2(SCH_1):PAGE76_I8@DEV_DISCRETE.CAP_A(CHIPS)':
 'A': CDS_PINID='A';
NODE_NAME     C2D40 1
 '@BASEBOARD_FAB2_LIB.BASEBOARD_FAB2(SCH_1):PAGE76_I10@DEV_DISCRETE.CAP_A(CHIPS)':
 'A': CDS_PINID='A';
NODE_NAME     C3D7 1
 '@BASEBOARD_FAB2_LIB.BASEBOARD_FAB2(SCH_1):PAGE76_I164@DEV_DISCRETE.CAP_A(CHIPS)':
 'A': CDS_PINID='A';
NODE_NAME     C2D39 1
 '@BASEBOARD_FAB2_LIB.BASEBOARD_FAB2(SCH_1):PAGE76_I165@DEV_DISCRETE.CAP_A(CHIPS)':
 'A': CDS_PINID='A';
NODE_NAME     C3D17 1
 '@BASEBOARD_FAB2_LIB.BASEBOARD_FAB2(SCH_1):PAGE76_I166@DEV_DISCRETE.CAP_A(CHIPS)':
 'A': CDS_PINID='A';
NODE_NAME     C3D18 1
 '@BASEBOARD_FAB2_LIB.BASEBOARD_FAB2(SCH_1):PAGE76_I169@DEV_DISCRETE.CAP_A(CHIPS)':
 'A': CDS_PINID='A';
NODE_NAME     C3D6 1
 '@BASEBOARD_FAB2_LIB.BASEBOARD_FAB2(SCH_1):PAGE76_I170@DEV_DISCRETE.CAP_A(CHIPS)':
 'A': CDS_PINID='A';
NODE_NAME     C3D14 1
 '@BASEBOARD_FAB2_LIB.BASEBOARD_FAB2(SCH_1):PAGE76_I171@DEV_DISCRETE.CAP_A(CHIPS)':
 'A': CDS_PINID='A';
NODE_NAME     C3D10 1
 '@BASEBOARD_FAB2_LIB.BASEBOARD_FAB2(SCH_1):PAGE76_I196@DEV_DISCRETE.CAP_A(CHIPS)':
 'A': CDS_PINID='A';
NODE_NAME     C2D18 1
 '@BASEBOARD_FAB2_LIB.BASEBOARD_FAB2(SCH_1):PAGE76_I197@DEV_DISCRETE.CAP_A(CHIPS)':
 'A': CDS_PINID='A';
NODE_NAME     C2D28 1
 '@BASEBOARD_FAB2_LIB.BASEBOARD_FAB2(SCH_1):PAGE76_I198@DEV_DISCRETE.CAP_A(CHIPS)':
 'A': CDS_PINID='A';
NODE_NAME     C2D29 1
 '@BASEBOARD_FAB2_LIB.BASEBOARD_FAB2(SCH_1):PAGE76_I199@DEV_DISCRETE.CAP_A(CHIPS)':
 'A': CDS_PINID='A';
NODE_NAME     C3D20 1
 '@BASEBOARD_FAB2_LIB.BASEBOARD_FAB2(SCH_1):PAGE76_I207@DEV_DISCRETE.CAP_A(CHIPS)':
 'A': CDS_PINID='A';
NODE_NAME     C3D19 1
 '@BASEBOARD_FAB2_LIB.BASEBOARD_FAB2(SCH_1):PAGE76_I208@DEV_DISCRETE.CAP_A(CHIPS)':
 'A': CDS_PINID='A';
NODE_NAME     J4E1 A1
 '@BASEBOARD_FAB2_LIB.BASEBOARD_FAB2(SCH_1):PAGE193_I45@MSTR_SCONN.SCONN120_H61426002(CHIPS)':
 'IOA1': CDS_PINID='IOA1';
NODE_NAME     J4E1 A2
 '@BASEBOARD_FAB2_LIB.BASEBOARD_FAB2(SCH_1):PAGE193_I45@MSTR_SCONN.SCONN120_H61426002(CHIPS)':
 'IOA2': CDS_PINID='IOA2';
NODE_NAME     J4E1 A3
 '@BASEBOARD_FAB2_LIB.BASEBOARD_FAB2(SCH_1):PAGE193_I45@MSTR_SCONN.SCONN120_H61426002(CHIPS)':
 'IOA3': CDS_PINID='IOA3';
NODE_NAME     J4E1 A5
 '@BASEBOARD_FAB2_LIB.BASEBOARD_FAB2(SCH_1):PAGE193_I45@MSTR_SCONN.SCONN120_H61426002(CHIPS)':
 'IOA5': CDS_PINID='IOA5';
NODE_NAME     J4E1 A6
 '@BASEBOARD_FAB2_LIB.BASEBOARD_FAB2(SCH_1):PAGE193_I45@MSTR_SCONN.SCONN120_H61426002(CHIPS)':
 'IOA6': CDS_PINID='IOA6';
NODE_NAME     J4E1 A7
 '@BASEBOARD_FAB2_LIB.BASEBOARD_FAB2(SCH_1):PAGE193_I45@MSTR_SCONN.SCONN120_H61426002(CHIPS)':
 'IOA7': CDS_PINID='IOA7';
NODE_NAME     J4E1 A8
 '@BASEBOARD_FAB2_LIB.BASEBOARD_FAB2(SCH_1):PAGE193_I45@MSTR_SCONN.SCONN120_H61426002(CHIPS)':
 'IOA8': CDS_PINID='IOA8';
NODE_NAME     J4E1 A9
 '@BASEBOARD_FAB2_LIB.BASEBOARD_FAB2(SCH_1):PAGE193_I45@MSTR_SCONN.SCONN120_H61426002(CHIPS)':
 'IOA9': CDS_PINID='IOA9';
NODE_NAME     J4E1 A10
 '@BASEBOARD_FAB2_LIB.BASEBOARD_FAB2(SCH_1):PAGE193_I45@MSTR_SCONN.SCONN120_H61426002(CHIPS)':
 'IOA10': CDS_PINID='IOA10';
NODE_NAME     J4E1 A11
 '@BASEBOARD_FAB2_LIB.BASEBOARD_FAB2(SCH_1):PAGE193_I45@MSTR_SCONN.SCONN120_H61426002(CHIPS)':
 'IOA11': CDS_PINID='IOA11';
NODE_NAME     J4E1 A12
 '@BASEBOARD_FAB2_LIB.BASEBOARD_FAB2(SCH_1):PAGE193_I45@MSTR_SCONN.SCONN120_H61426002(CHIPS)':
 'IOA12': CDS_PINID='IOA12';
NODE_NAME     J4E1 A13
 '@BASEBOARD_FAB2_LIB.BASEBOARD_FAB2(SCH_1):PAGE193_I45@MSTR_SCONN.SCONN120_H61426002(CHIPS)':
 'IOA13': CDS_PINID='IOA13';
NODE_NAME     J4E1 A14
 '@BASEBOARD_FAB2_LIB.BASEBOARD_FAB2(SCH_1):PAGE193_I45@MSTR_SCONN.SCONN120_H61426002(CHIPS)':
 'IOA14': CDS_PINID='IOA14';
NODE_NAME     J4E1 A15
 '@BASEBOARD_FAB2_LIB.BASEBOARD_FAB2(SCH_1):PAGE193_I45@MSTR_SCONN.SCONN120_H61426002(CHIPS)':
 'IOA15': CDS_PINID='IOA15';
NODE_NAME     J4E1 A16
 '@BASEBOARD_FAB2_LIB.BASEBOARD_FAB2(SCH_1):PAGE193_I45@MSTR_SCONN.SCONN120_H61426002(CHIPS)':
 'IOA16': CDS_PINID='IOA16';
NODE_NAME     J4E1 A17
 '@BASEBOARD_FAB2_LIB.BASEBOARD_FAB2(SCH_1):PAGE193_I45@MSTR_SCONN.SCONN120_H61426002(CHIPS)':
 'IOA17': CDS_PINID='IOA17';
NODE_NAME     J4E1 A18
 '@BASEBOARD_FAB2_LIB.BASEBOARD_FAB2(SCH_1):PAGE193_I45@MSTR_SCONN.SCONN120_H61426002(CHIPS)':
 'IOA18': CDS_PINID='IOA18';
NODE_NAME     J4E1 B1
 '@BASEBOARD_FAB2_LIB.BASEBOARD_FAB2(SCH_1):PAGE193_I45@MSTR_SCONN.SCONN120_H61426002(CHIPS)':
 'IOB1': CDS_PINID='IOB1';
NODE_NAME     J4E1 B2
 '@BASEBOARD_FAB2_LIB.BASEBOARD_FAB2(SCH_1):PAGE193_I45@MSTR_SCONN.SCONN120_H61426002(CHIPS)':
 'IOB2': CDS_PINID='IOB2';
NODE_NAME     J4E1 B3
 '@BASEBOARD_FAB2_LIB.BASEBOARD_FAB2(SCH_1):PAGE193_I45@MSTR_SCONN.SCONN120_H61426002(CHIPS)':
 'IOB3': CDS_PINID='IOB3';
NODE_NAME     J4E1 B5
 '@BASEBOARD_FAB2_LIB.BASEBOARD_FAB2(SCH_1):PAGE193_I45@MSTR_SCONN.SCONN120_H61426002(CHIPS)':
 'IOB5': CDS_PINID='IOB5';
NODE_NAME     J4E1 B6
 '@BASEBOARD_FAB2_LIB.BASEBOARD_FAB2(SCH_1):PAGE193_I45@MSTR_SCONN.SCONN120_H61426002(CHIPS)':
 'IOB6': CDS_PINID='IOB6';
NODE_NAME     J4E1 B7
 '@BASEBOARD_FAB2_LIB.BASEBOARD_FAB2(SCH_1):PAGE193_I45@MSTR_SCONN.SCONN120_H61426002(CHIPS)':
 'IOB7': CDS_PINID='IOB7';
NODE_NAME     J4E1 B8
 '@BASEBOARD_FAB2_LIB.BASEBOARD_FAB2(SCH_1):PAGE193_I45@MSTR_SCONN.SCONN120_H61426002(CHIPS)':
 'IOB8': CDS_PINID='IOB8';
NODE_NAME     J4E1 B9
 '@BASEBOARD_FAB2_LIB.BASEBOARD_FAB2(SCH_1):PAGE193_I45@MSTR_SCONN.SCONN120_H61426002(CHIPS)':
 'IOB9': CDS_PINID='IOB9';
NODE_NAME     J4E1 B10
 '@BASEBOARD_FAB2_LIB.BASEBOARD_FAB2(SCH_1):PAGE193_I45@MSTR_SCONN.SCONN120_H61426002(CHIPS)':
 'IOB10': CDS_PINID='IOB10';
NODE_NAME     J4E1 B11
 '@BASEBOARD_FAB2_LIB.BASEBOARD_FAB2(SCH_1):PAGE193_I45@MSTR_SCONN.SCONN120_H61426002(CHIPS)':
 'IOB11': CDS_PINID='IOB11';
NODE_NAME     J4E1 B12
 '@BASEBOARD_FAB2_LIB.BASEBOARD_FAB2(SCH_1):PAGE193_I45@MSTR_SCONN.SCONN120_H61426002(CHIPS)':
 'IOB12': CDS_PINID='IOB12';
NODE_NAME     J4E1 B13
 '@BASEBOARD_FAB2_LIB.BASEBOARD_FAB2(SCH_1):PAGE193_I45@MSTR_SCONN.SCONN120_H61426002(CHIPS)':
 'IOB13': CDS_PINID='IOB13';
NODE_NAME     J4E1 B14
 '@BASEBOARD_FAB2_LIB.BASEBOARD_FAB2(SCH_1):PAGE193_I45@MSTR_SCONN.SCONN120_H61426002(CHIPS)':
 'IOB14': CDS_PINID='IOB14';
NODE_NAME     J4E1 B15
 '@BASEBOARD_FAB2_LIB.BASEBOARD_FAB2(SCH_1):PAGE193_I45@MSTR_SCONN.SCONN120_H61426002(CHIPS)':
 'IOB15': CDS_PINID='IOB15';
NODE_NAME     J4E1 B16
 '@BASEBOARD_FAB2_LIB.BASEBOARD_FAB2(SCH_1):PAGE193_I45@MSTR_SCONN.SCONN120_H61426002(CHIPS)':
 'IOB16': CDS_PINID='IOB16';
NODE_NAME     J4E1 B17
 '@BASEBOARD_FAB2_LIB.BASEBOARD_FAB2(SCH_1):PAGE193_I45@MSTR_SCONN.SCONN120_H61426002(CHIPS)':
 'IOB17': CDS_PINID='IOB17';
NODE_NAME     J4E1 B18
 '@BASEBOARD_FAB2_LIB.BASEBOARD_FAB2(SCH_1):PAGE193_I45@MSTR_SCONN.SCONN120_H61426002(CHIPS)':
 'IOB18': CDS_PINID='IOB18';
NODE_NAME     J4E1 C1
 '@BASEBOARD_FAB2_LIB.BASEBOARD_FAB2(SCH_1):PAGE193_I45@MSTR_SCONN.SCONN120_H61426002(CHIPS)':
 'IOC1': CDS_PINID='IOC1';
NODE_NAME     J4E1 C2
 '@BASEBOARD_FAB2_LIB.BASEBOARD_FAB2(SCH_1):PAGE193_I45@MSTR_SCONN.SCONN120_H61426002(CHIPS)':
 'IOC2': CDS_PINID='IOC2';
NODE_NAME     J4E1 C3
 '@BASEBOARD_FAB2_LIB.BASEBOARD_FAB2(SCH_1):PAGE193_I45@MSTR_SCONN.SCONN120_H61426002(CHIPS)':
 'IOC3': CDS_PINID='IOC3';
NODE_NAME     J4E1 C4
 '@BASEBOARD_FAB2_LIB.BASEBOARD_FAB2(SCH_1):PAGE193_I45@MSTR_SCONN.SCONN120_H61426002(CHIPS)':
 'IOC4': CDS_PINID='IOC4';
NODE_NAME     J4E1 C5
 '@BASEBOARD_FAB2_LIB.BASEBOARD_FAB2(SCH_1):PAGE193_I45@MSTR_SCONN.SCONN120_H61426002(CHIPS)':
 'IOC5': CDS_PINID='IOC5';
NODE_NAME     J4E1 C6
 '@BASEBOARD_FAB2_LIB.BASEBOARD_FAB2(SCH_1):PAGE193_I45@MSTR_SCONN.SCONN120_H61426002(CHIPS)':
 'IOC6': CDS_PINID='IOC6';
NODE_NAME     J4E1 C7
 '@BASEBOARD_FAB2_LIB.BASEBOARD_FAB2(SCH_1):PAGE193_I45@MSTR_SCONN.SCONN120_H61426002(CHIPS)':
 'IOC7': CDS_PINID='IOC7';
NODE_NAME     J4E1 C8
 '@BASEBOARD_FAB2_LIB.BASEBOARD_FAB2(SCH_1):PAGE193_I45@MSTR_SCONN.SCONN120_H61426002(CHIPS)':
 'IOC8': CDS_PINID='IOC8';
NODE_NAME     J4E1 C9
 '@BASEBOARD_FAB2_LIB.BASEBOARD_FAB2(SCH_1):PAGE193_I45@MSTR_SCONN.SCONN120_H61426002(CHIPS)':
 'IOC9': CDS_PINID='IOC9';
NODE_NAME     J4E1 C10
 '@BASEBOARD_FAB2_LIB.BASEBOARD_FAB2(SCH_1):PAGE193_I45@MSTR_SCONN.SCONN120_H61426002(CHIPS)':
 'IOC10': CDS_PINID='IOC10';
NODE_NAME     J4E1 C11
 '@BASEBOARD_FAB2_LIB.BASEBOARD_FAB2(SCH_1):PAGE193_I45@MSTR_SCONN.SCONN120_H61426002(CHIPS)':
 'IOC11': CDS_PINID='IOC11';
NODE_NAME     J4E1 C12
 '@BASEBOARD_FAB2_LIB.BASEBOARD_FAB2(SCH_1):PAGE193_I45@MSTR_SCONN.SCONN120_H61426002(CHIPS)':
 'IOC12': CDS_PINID='IOC12';
NODE_NAME     J4E1 C13
 '@BASEBOARD_FAB2_LIB.BASEBOARD_FAB2(SCH_1):PAGE193_I45@MSTR_SCONN.SCONN120_H61426002(CHIPS)':
 'IOC13': CDS_PINID='IOC13';
NODE_NAME     J4E1 C14
 '@BASEBOARD_FAB2_LIB.BASEBOARD_FAB2(SCH_1):PAGE193_I45@MSTR_SCONN.SCONN120_H61426002(CHIPS)':
 'IOC14': CDS_PINID='IOC14';
NODE_NAME     J4E1 C15
 '@BASEBOARD_FAB2_LIB.BASEBOARD_FAB2(SCH_1):PAGE193_I45@MSTR_SCONN.SCONN120_H61426002(CHIPS)':
 'IOC15': CDS_PINID='IOC15';
NODE_NAME     J4E1 C16
 '@BASEBOARD_FAB2_LIB.BASEBOARD_FAB2(SCH_1):PAGE193_I45@MSTR_SCONN.SCONN120_H61426002(CHIPS)':
 'IOC16': CDS_PINID='IOC16';
NODE_NAME     J4E1 C17
 '@BASEBOARD_FAB2_LIB.BASEBOARD_FAB2(SCH_1):PAGE193_I45@MSTR_SCONN.SCONN120_H61426002(CHIPS)':
 'IOC17': CDS_PINID='IOC17';
NODE_NAME     J4E1 C18
 '@BASEBOARD_FAB2_LIB.BASEBOARD_FAB2(SCH_1):PAGE193_I45@MSTR_SCONN.SCONN120_H61426002(CHIPS)':
 'IOC18': CDS_PINID='IOC18';
NODE_NAME     C4E24 1
 '@BASEBOARD_FAB2_LIB.BASEBOARD_FAB2(SCH_1):PAGE193_I61@MSTR_DISCRETE.CAPP(CHIPS)':
 'A': CDS_PINID='A';
NODE_NAME     C6R16 1
 '@BASEBOARD_FAB2_LIB.BASEBOARD_FAB2(SCH_1):PAGE193_I62@MSTR_DISCRETE.CAPP(CHIPS)':
 'A': CDS_PINID='A';
NODE_NAME     C3W4 1
 '@BASEBOARD_FAB2_LIB.BASEBOARD_FAB2(SCH_1):PAGE76_I254@DEV_DISCRETE.CAP_A(CHIPS)':
 'A': CDS_PINID='A';
NODE_NAME     C3W3 1
 '@BASEBOARD_FAB2_LIB.BASEBOARD_FAB2(SCH_1):PAGE76_I256@DEV_DISCRETE.CAP_A(CHIPS)':
 'A': CDS_PINID='A';
NODE_NAME     C4E29 1
 '@BASEBOARD_FAB2_LIB.BASEBOARD_FAB2(SCH_1):PAGE193_I175@MSTR_DISCRETE.CAPP(CHIPS)':
 'A': CDS_PINID='A';
NODE_NAME     C7P9 1
 '@BASEBOARD_FAB2_LIB.BASEBOARD_FAB2(SCH_1):PAGE76_I258@MSTR_DISCRETE.CAP(CHIPS)':
 'A': CDS_PINID='A';
NODE_NAME     C7P5 1
 '@BASEBOARD_FAB2_LIB.BASEBOARD_FAB2(SCH_1):PAGE76_I259@MSTR_DISCRETE.CAP(CHIPS)':
 'A': CDS_PINID='A';
NODE_NAME     C8P23 1
 '@BASEBOARD_FAB2_LIB.BASEBOARD_FAB2(SCH_1):PAGE76_I260@MSTR_DISCRETE.CAP(CHIPS)':
 'A': CDS_PINID='A';
NODE_NAME     C7P14 1
 '@BASEBOARD_FAB2_LIB.BASEBOARD_FAB2(SCH_1):PAGE76_I261@MSTR_DISCRETE.CAP(CHIPS)':
 'A': CDS_PINID='A';
NODE_NAME     C7P11 1
 '@BASEBOARD_FAB2_LIB.BASEBOARD_FAB2(SCH_1):PAGE76_I262@MSTR_DISCRETE.CAP(CHIPS)':
 'A': CDS_PINID='A';
NODE_NAME     C7P15 1
 '@BASEBOARD_FAB2_LIB.BASEBOARD_FAB2(SCH_1):PAGE76_I263@MSTR_DISCRETE.CAP(CHIPS)':
 'A': CDS_PINID='A';
NODE_NAME     C8P22 1
 '@BASEBOARD_FAB2_LIB.BASEBOARD_FAB2(SCH_1):PAGE76_I264@MSTR_DISCRETE.CAP(CHIPS)':
 'A': CDS_PINID='A';
NODE_NAME     C7P8 1
 '@BASEBOARD_FAB2_LIB.BASEBOARD_FAB2(SCH_1):PAGE76_I265@MSTR_DISCRETE.CAP(CHIPS)':
 'A': CDS_PINID='A';
NODE_NAME     C7P10 1
 '@BASEBOARD_FAB2_LIB.BASEBOARD_FAB2(SCH_1):PAGE76_I266@MSTR_DISCRETE.CAP(CHIPS)':
 'A': CDS_PINID='A';
NODE_NAME     C7P7 1
 '@BASEBOARD_FAB2_LIB.BASEBOARD_FAB2(SCH_1):PAGE76_I267@MSTR_DISCRETE.CAP(CHIPS)':
 'A': CDS_PINID='A';
NODE_NAME     C7P6 1
 '@BASEBOARD_FAB2_LIB.BASEBOARD_FAB2(SCH_1):PAGE76_I268@MSTR_DISCRETE.CAP(CHIPS)':
 'A': CDS_PINID='A';
NODE_NAME     C7P13 1
 '@BASEBOARD_FAB2_LIB.BASEBOARD_FAB2(SCH_1):PAGE76_I269@MSTR_DISCRETE.CAP(CHIPS)':
 'A': CDS_PINID='A';
NODE_NAME     C8P15 1
 '@BASEBOARD_FAB2_LIB.BASEBOARD_FAB2(SCH_1):PAGE76_I270@MSTR_DISCRETE.CAP(CHIPS)':
 'A': CDS_PINID='A';
NODE_NAME     C7P4 1
 '@BASEBOARD_FAB2_LIB.BASEBOARD_FAB2(SCH_1):PAGE76_I271@MSTR_DISCRETE.CAP(CHIPS)':
 'A': CDS_PINID='A';
NODE_NAME     C8P14 1
 '@BASEBOARD_FAB2_LIB.BASEBOARD_FAB2(SCH_1):PAGE76_I272@MSTR_DISCRETE.CAP(CHIPS)':
 'A': CDS_PINID='A';
NODE_NAME     C8P9 1
 '@BASEBOARD_FAB2_LIB.BASEBOARD_FAB2(SCH_1):PAGE76_I273@MSTR_DISCRETE.CAP(CHIPS)':
 'A': CDS_PINID='A';
NODE_NAME     C8P8 1
 '@BASEBOARD_FAB2_LIB.BASEBOARD_FAB2(SCH_1):PAGE76_I274@MSTR_DISCRETE.CAP(CHIPS)':
 'A': CDS_PINID='A';
NET_NAME
'PVDDQ_ABC'
 '@BASEBOARD_FAB2_LIB.BASEBOARD_FAB2(SCH_1):PVDDQ_ABC':
 C_SIGNAL='@baseboard_fab2_lib.baseboard_fab2(sch_1):pvddq_abc';
NODE_NAME     U5D1 B49
 '@BASEBOARD_FAB2_LIB.BASEBOARD_FAB2(SCH_1):PAGE38_I33@CHPSET_LIB.SKX_EXT_B(CHIPS)':
 'VCCD012'<0>: CDS_PINID='VCCD012(0)';
NODE_NAME     U5D1 B53
 '@BASEBOARD_FAB2_LIB.BASEBOARD_FAB2(SCH_1):PAGE38_I33@CHPSET_LIB.SKX_EXT_B(CHIPS)':
 'VCCD012'<1>: CDS_PINID='VCCD012(1)';
NODE_NAME     U5D1 B59
 '@BASEBOARD_FAB2_LIB.BASEBOARD_FAB2(SCH_1):PAGE38_I33@CHPSET_LIB.SKX_EXT_B(CHIPS)':
 'VCCD012'<2>: CDS_PINID='VCCD012(2)';
NODE_NAME     U5D1 E46
 '@BASEBOARD_FAB2_LIB.BASEBOARD_FAB2(SCH_1):PAGE38_I33@CHPSET_LIB.SKX_EXT_B(CHIPS)':
 'VCCD012'<3>: CDS_PINID='VCCD012(3)';
NODE_NAME     U5D1 E48
 '@BASEBOARD_FAB2_LIB.BASEBOARD_FAB2(SCH_1):PAGE38_I33@CHPSET_LIB.SKX_EXT_B(CHIPS)':
 'VCCD012'<4>: CDS_PINID='VCCD012(4)';
NODE_NAME     U5D1 E50
 '@BASEBOARD_FAB2_LIB.BASEBOARD_FAB2(SCH_1):PAGE38_I33@CHPSET_LIB.SKX_EXT_B(CHIPS)':
 'VCCD012'<5>: CDS_PINID='VCCD012(5)';
NODE_NAME     U5D1 E52
 '@BASEBOARD_FAB2_LIB.BASEBOARD_FAB2(SCH_1):PAGE38_I33@CHPSET_LIB.SKX_EXT_B(CHIPS)':
 'VCCD012'<6>: CDS_PINID='VCCD012(6)';
NODE_NAME     U5D1 E54
 '@BASEBOARD_FAB2_LIB.BASEBOARD_FAB2(SCH_1):PAGE38_I33@CHPSET_LIB.SKX_EXT_B(CHIPS)':
 'VCCD012'<7>: CDS_PINID='VCCD012(7)';
NODE_NAME     U5D1 E56
 '@BASEBOARD_FAB2_LIB.BASEBOARD_FAB2(SCH_1):PAGE38_I33@CHPSET_LIB.SKX_EXT_B(CHIPS)':
 'VCCD012'<8>: CDS_PINID='VCCD012(8)';
NODE_NAME     U5D1 E58
 '@BASEBOARD_FAB2_LIB.BASEBOARD_FAB2(SCH_1):PAGE38_I33@CHPSET_LIB.SKX_EXT_B(CHIPS)':
 'VCCD012'<9>: CDS_PINID='VCCD012(9)';
NODE_NAME     U5D1 E60
 '@BASEBOARD_FAB2_LIB.BASEBOARD_FAB2(SCH_1):PAGE38_I33@CHPSET_LIB.SKX_EXT_B(CHIPS)':
 'VCCD012'<10>: CDS_PINID='VCCD012(10)';
NODE_NAME     U5D1 E62
 '@BASEBOARD_FAB2_LIB.BASEBOARD_FAB2(SCH_1):PAGE38_I33@CHPSET_LIB.SKX_EXT_B(CHIPS)':
 'VCCD012'<11>: CDS_PINID='VCCD012(11)';
NODE_NAME     U5D1 E64
 '@BASEBOARD_FAB2_LIB.BASEBOARD_FAB2(SCH_1):PAGE38_I33@CHPSET_LIB.SKX_EXT_B(CHIPS)':
 'VCCD012'<12>: CDS_PINID='VCCD012(12)';
NODE_NAME     U5D1 L46
 '@BASEBOARD_FAB2_LIB.BASEBOARD_FAB2(SCH_1):PAGE38_I33@CHPSET_LIB.SKX_EXT_B(CHIPS)':
 'VCCD012'<13>: CDS_PINID='VCCD012(13)';
NODE_NAME     U5D1 L48
 '@BASEBOARD_FAB2_LIB.BASEBOARD_FAB2(SCH_1):PAGE38_I33@CHPSET_LIB.SKX_EXT_B(CHIPS)':
 'VCCD012'<14>: CDS_PINID='VCCD012(14)';
NODE_NAME     U5D1 L50
 '@BASEBOARD_FAB2_LIB.BASEBOARD_FAB2(SCH_1):PAGE38_I33@CHPSET_LIB.SKX_EXT_B(CHIPS)':
 'VCCD012'<15>: CDS_PINID='VCCD012(15)';
NODE_NAME     U5D1 L52
 '@BASEBOARD_FAB2_LIB.BASEBOARD_FAB2(SCH_1):PAGE38_I33@CHPSET_LIB.SKX_EXT_B(CHIPS)':
 'VCCD012'<16>: CDS_PINID='VCCD012(16)';
NODE_NAME     U5D1 L54
 '@BASEBOARD_FAB2_LIB.BASEBOARD_FAB2(SCH_1):PAGE38_I33@CHPSET_LIB.SKX_EXT_B(CHIPS)':
 'VCCD012'<17>: CDS_PINID='VCCD012(17)';
NODE_NAME     U5D1 L56
 '@BASEBOARD_FAB2_LIB.BASEBOARD_FAB2(SCH_1):PAGE38_I33@CHPSET_LIB.SKX_EXT_B(CHIPS)':
 'VCCD012'<18>: CDS_PINID='VCCD012(18)';
NODE_NAME     U5D1 L58
 '@BASEBOARD_FAB2_LIB.BASEBOARD_FAB2(SCH_1):PAGE38_I33@CHPSET_LIB.SKX_EXT_B(CHIPS)':
 'VCCD012'<19>: CDS_PINID='VCCD012(19)';
NODE_NAME     U5D1 L60
 '@BASEBOARD_FAB2_LIB.BASEBOARD_FAB2(SCH_1):PAGE38_I33@CHPSET_LIB.SKX_EXT_B(CHIPS)':
 'VCCD012'<20>: CDS_PINID='VCCD012(20)';
NODE_NAME     U5D1 L62
 '@BASEBOARD_FAB2_LIB.BASEBOARD_FAB2(SCH_1):PAGE38_I33@CHPSET_LIB.SKX_EXT_B(CHIPS)':
 'VCCD012'<21>: CDS_PINID='VCCD012(21)';
NODE_NAME     U5D1 N64
 '@BASEBOARD_FAB2_LIB.BASEBOARD_FAB2(SCH_1):PAGE38_I33@CHPSET_LIB.SKX_EXT_B(CHIPS)':
 'VCCD012'<22>: CDS_PINID='VCCD012(22)';
NODE_NAME     U5D1 U46
 '@BASEBOARD_FAB2_LIB.BASEBOARD_FAB2(SCH_1):PAGE38_I33@CHPSET_LIB.SKX_EXT_B(CHIPS)':
 'VCCD012'<23>: CDS_PINID='VCCD012(23)';
NODE_NAME     U5D1 U48
 '@BASEBOARD_FAB2_LIB.BASEBOARD_FAB2(SCH_1):PAGE38_I33@CHPSET_LIB.SKX_EXT_B(CHIPS)':
 'VCCD012'<24>: CDS_PINID='VCCD012(24)';
NODE_NAME     U5D1 U50
 '@BASEBOARD_FAB2_LIB.BASEBOARD_FAB2(SCH_1):PAGE38_I33@CHPSET_LIB.SKX_EXT_B(CHIPS)':
 'VCCD012'<25>: CDS_PINID='VCCD012(25)';
NODE_NAME     U5D1 U52
 '@BASEBOARD_FAB2_LIB.BASEBOARD_FAB2(SCH_1):PAGE38_I33@CHPSET_LIB.SKX_EXT_B(CHIPS)':
 'VCCD012'<26>: CDS_PINID='VCCD012(26)';
NODE_NAME     U5D1 U54
 '@BASEBOARD_FAB2_LIB.BASEBOARD_FAB2(SCH_1):PAGE38_I33@CHPSET_LIB.SKX_EXT_B(CHIPS)':
 'VCCD012'<27>: CDS_PINID='VCCD012(27)';
NODE_NAME     U5D1 U56
 '@BASEBOARD_FAB2_LIB.BASEBOARD_FAB2(SCH_1):PAGE38_I33@CHPSET_LIB.SKX_EXT_B(CHIPS)':
 'VCCD012'<28>: CDS_PINID='VCCD012(28)';
NODE_NAME     U5D1 U58
 '@BASEBOARD_FAB2_LIB.BASEBOARD_FAB2(SCH_1):PAGE38_I33@CHPSET_LIB.SKX_EXT_B(CHIPS)':
 'VCCD012'<29>: CDS_PINID='VCCD012(29)';
NODE_NAME     U5D1 U60
 '@BASEBOARD_FAB2_LIB.BASEBOARD_FAB2(SCH_1):PAGE38_I33@CHPSET_LIB.SKX_EXT_B(CHIPS)':
 'VCCD012'<30>: CDS_PINID='VCCD012(30)';
NODE_NAME     U5D1 U62
 '@BASEBOARD_FAB2_LIB.BASEBOARD_FAB2(SCH_1):PAGE38_I33@CHPSET_LIB.SKX_EXT_B(CHIPS)':
 'VCCD012'<31>: CDS_PINID='VCCD012(31)';
NODE_NAME     U5D1 W64
 '@BASEBOARD_FAB2_LIB.BASEBOARD_FAB2(SCH_1):PAGE38_I33@CHPSET_LIB.SKX_EXT_B(CHIPS)':
 'VCCD012'<32>: CDS_PINID='VCCD012(32)';
NODE_NAME     U5D1 Y45
 '@BASEBOARD_FAB2_LIB.BASEBOARD_FAB2(SCH_1):PAGE38_I33@CHPSET_LIB.SKX_EXT_B(CHIPS)':
 'VCCD012'<33>: CDS_PINID='VCCD012(33)';
NODE_NAME     U5D1 Y47
 '@BASEBOARD_FAB2_LIB.BASEBOARD_FAB2(SCH_1):PAGE38_I33@CHPSET_LIB.SKX_EXT_B(CHIPS)':
 'VCCD012'<34>: CDS_PINID='VCCD012(34)';
NODE_NAME     U5D1 Y49
 '@BASEBOARD_FAB2_LIB.BASEBOARD_FAB2(SCH_1):PAGE38_I33@CHPSET_LIB.SKX_EXT_B(CHIPS)':
 'VCCD012'<35>: CDS_PINID='VCCD012(35)';
NODE_NAME     U5D1 Y51
 '@BASEBOARD_FAB2_LIB.BASEBOARD_FAB2(SCH_1):PAGE38_I33@CHPSET_LIB.SKX_EXT_B(CHIPS)':
 'VCCD012'<36>: CDS_PINID='VCCD012(36)';
NODE_NAME     U5D1 Y53
 '@BASEBOARD_FAB2_LIB.BASEBOARD_FAB2(SCH_1):PAGE38_I33@CHPSET_LIB.SKX_EXT_B(CHIPS)':
 'VCCD012'<37>: CDS_PINID='VCCD012(37)';
NODE_NAME     U5D1 Y55
 '@BASEBOARD_FAB2_LIB.BASEBOARD_FAB2(SCH_1):PAGE38_I33@CHPSET_LIB.SKX_EXT_B(CHIPS)':
 'VCCD012'<38>: CDS_PINID='VCCD012(38)';
NODE_NAME     U5D1 Y57
 '@BASEBOARD_FAB2_LIB.BASEBOARD_FAB2(SCH_1):PAGE38_I33@CHPSET_LIB.SKX_EXT_B(CHIPS)':
 'VCCD012'<39>: CDS_PINID='VCCD012(39)';
NODE_NAME     U5D1 Y59
 '@BASEBOARD_FAB2_LIB.BASEBOARD_FAB2(SCH_1):PAGE38_I33@CHPSET_LIB.SKX_EXT_B(CHIPS)':
 'VCCD012'<40>: CDS_PINID='VCCD012(40)';
NODE_NAME     U5D1 Y61
 '@BASEBOARD_FAB2_LIB.BASEBOARD_FAB2(SCH_1):PAGE38_I33@CHPSET_LIB.SKX_EXT_B(CHIPS)':
 'VCCD012'<41>: CDS_PINID='VCCD012(41)';
NODE_NAME     U5D1 Y63
 '@BASEBOARD_FAB2_LIB.BASEBOARD_FAB2(SCH_1):PAGE38_I33@CHPSET_LIB.SKX_EXT_B(CHIPS)':
 'VCCD012'<42>: CDS_PINID='VCCD012(42)';
NODE_NAME     U5D1 AD45
 '@BASEBOARD_FAB2_LIB.BASEBOARD_FAB2(SCH_1):PAGE38_I33@CHPSET_LIB.SKX_EXT_B(CHIPS)':
 'VCCD012'<43>: CDS_PINID='VCCD012(43)';
NODE_NAME     U5D1 AF55
 '@BASEBOARD_FAB2_LIB.BASEBOARD_FAB2(SCH_1):PAGE38_I33@CHPSET_LIB.SKX_EXT_B(CHIPS)':
 'VCCD012'<44>: CDS_PINID='VCCD012(44)';
NODE_NAME     U5D1 AF57
 '@BASEBOARD_FAB2_LIB.BASEBOARD_FAB2(SCH_1):PAGE38_I33@CHPSET_LIB.SKX_EXT_B(CHIPS)':
 'VCCD012'<45>: CDS_PINID='VCCD012(45)';
NODE_NAME     U5D1 AF59
 '@BASEBOARD_FAB2_LIB.BASEBOARD_FAB2(SCH_1):PAGE38_I33@CHPSET_LIB.SKX_EXT_B(CHIPS)':
 'VCCD012'<46>: CDS_PINID='VCCD012(46)';
NODE_NAME     U5D1 AF61
 '@BASEBOARD_FAB2_LIB.BASEBOARD_FAB2(SCH_1):PAGE38_I33@CHPSET_LIB.SKX_EXT_B(CHIPS)':
 'VCCD012'<47>: CDS_PINID='VCCD012(47)';
NODE_NAME     U5D1 AF63
 '@BASEBOARD_FAB2_LIB.BASEBOARD_FAB2(SCH_1):PAGE38_I33@CHPSET_LIB.SKX_EXT_B(CHIPS)':
 'VCCD012'<48>: CDS_PINID='VCCD012(48)';
NODE_NAME     U5D1 D45
 '@BASEBOARD_FAB2_LIB.BASEBOARD_FAB2(SCH_1):PAGE38_I33@CHPSET_LIB.SKX_EXT_B(CHIPS)':
 'VCCD012'<49>: CDS_PINID='VCCD012(49)';
NODE_NAME     U5D1 C46
 '@BASEBOARD_FAB2_LIB.BASEBOARD_FAB2(SCH_1):PAGE38_I33@CHPSET_LIB.SKX_EXT_B(CHIPS)':
 'VCCD012'<50>: CDS_PINID='VCCD012(50)';
NODE_NAME     U5D1 B47
 '@BASEBOARD_FAB2_LIB.BASEBOARD_FAB2(SCH_1):PAGE38_I33@CHPSET_LIB.SKX_EXT_B(CHIPS)':
 'VCCD012'<51>: CDS_PINID='VCCD012(51)';
NODE_NAME     J4G1 236
 '@BASEBOARD_FAB2_LIB.BASEBOARD_FAB2(SCH_1):PAGE43_I260@MSTR_SCONN.SCONN288_H44441004(CHIPS)':
 'VDD'<0>: CDS_PINID='VDD(0)';
NODE_NAME     J4G1 233
 '@BASEBOARD_FAB2_LIB.BASEBOARD_FAB2(SCH_1):PAGE43_I260@MSTR_SCONN.SCONN288_H44441004(CHIPS)':
 'VDD'<1>: CDS_PINID='VDD(1)';
NODE_NAME     J4G1 231
 '@BASEBOARD_FAB2_LIB.BASEBOARD_FAB2(SCH_1):PAGE43_I260@MSTR_SCONN.SCONN288_H44441004(CHIPS)':
 'VDD'<2>: CDS_PINID='VDD(2)';
NODE_NAME     J4G1 229
 '@BASEBOARD_FAB2_LIB.BASEBOARD_FAB2(SCH_1):PAGE43_I260@MSTR_SCONN.SCONN288_H44441004(CHIPS)':
 'VDD'<3>: CDS_PINID='VDD(3)';
NODE_NAME     J4G1 226
 '@BASEBOARD_FAB2_LIB.BASEBOARD_FAB2(SCH_1):PAGE43_I260@MSTR_SCONN.SCONN288_H44441004(CHIPS)':
 'VDD'<4>: CDS_PINID='VDD(4)';
NODE_NAME     J4G1 223
 '@BASEBOARD_FAB2_LIB.BASEBOARD_FAB2(SCH_1):PAGE43_I260@MSTR_SCONN.SCONN288_H44441004(CHIPS)':
 'VDD'<5>: CDS_PINID='VDD(5)';
NODE_NAME     J4G1 220
 '@BASEBOARD_FAB2_LIB.BASEBOARD_FAB2(SCH_1):PAGE43_I260@MSTR_SCONN.SCONN288_H44441004(CHIPS)':
 'VDD'<6>: CDS_PINID='VDD(6)';
NODE_NAME     J4G1 217
 '@BASEBOARD_FAB2_LIB.BASEBOARD_FAB2(SCH_1):PAGE43_I260@MSTR_SCONN.SCONN288_H44441004(CHIPS)':
 'VDD'<7>: CDS_PINID='VDD(7)';
NODE_NAME     J4G1 215
 '@BASEBOARD_FAB2_LIB.BASEBOARD_FAB2(SCH_1):PAGE43_I260@MSTR_SCONN.SCONN288_H44441004(CHIPS)':
 'VDD'<8>: CDS_PINID='VDD(8)';
NODE_NAME     J4G1 212
 '@BASEBOARD_FAB2_LIB.BASEBOARD_FAB2(SCH_1):PAGE43_I260@MSTR_SCONN.SCONN288_H44441004(CHIPS)':
 'VDD'<9>: CDS_PINID='VDD(9)';
NODE_NAME     J4G1 209
 '@BASEBOARD_FAB2_LIB.BASEBOARD_FAB2(SCH_1):PAGE43_I260@MSTR_SCONN.SCONN288_H44441004(CHIPS)':
 'VDD'<10>: CDS_PINID='VDD(10)';
NODE_NAME     J4G1 206
 '@BASEBOARD_FAB2_LIB.BASEBOARD_FAB2(SCH_1):PAGE43_I260@MSTR_SCONN.SCONN288_H44441004(CHIPS)':
 'VDD'<11>: CDS_PINID='VDD(11)';
NODE_NAME     J4G1 204
 '@BASEBOARD_FAB2_LIB.BASEBOARD_FAB2(SCH_1):PAGE43_I260@MSTR_SCONN.SCONN288_H44441004(CHIPS)':
 'VDD'<12>: CDS_PINID='VDD(12)';
NODE_NAME     J4G1 92
 '@BASEBOARD_FAB2_LIB.BASEBOARD_FAB2(SCH_1):PAGE43_I260@MSTR_SCONN.SCONN288_H44441004(CHIPS)':
 'VDD'<13>: CDS_PINID='VDD(13)';
NODE_NAME     J4G1 90
 '@BASEBOARD_FAB2_LIB.BASEBOARD_FAB2(SCH_1):PAGE43_I260@MSTR_SCONN.SCONN288_H44441004(CHIPS)':
 'VDD'<14>: CDS_PINID='VDD(14)';
NODE_NAME     J4G1 88
 '@BASEBOARD_FAB2_LIB.BASEBOARD_FAB2(SCH_1):PAGE43_I260@MSTR_SCONN.SCONN288_H44441004(CHIPS)':
 'VDD'<15>: CDS_PINID='VDD(15)';
NODE_NAME     J4G1 85
 '@BASEBOARD_FAB2_LIB.BASEBOARD_FAB2(SCH_1):PAGE43_I260@MSTR_SCONN.SCONN288_H44441004(CHIPS)':
 'VDD'<16>: CDS_PINID='VDD(16)';
NODE_NAME     J4G1 83
 '@BASEBOARD_FAB2_LIB.BASEBOARD_FAB2(SCH_1):PAGE43_I260@MSTR_SCONN.SCONN288_H44441004(CHIPS)':
 'VDD'<17>: CDS_PINID='VDD(17)';
NODE_NAME     J4G1 80
 '@BASEBOARD_FAB2_LIB.BASEBOARD_FAB2(SCH_1):PAGE43_I260@MSTR_SCONN.SCONN288_H44441004(CHIPS)':
 'VDD'<18>: CDS_PINID='VDD(18)';
NODE_NAME     J4G1 76
 '@BASEBOARD_FAB2_LIB.BASEBOARD_FAB2(SCH_1):PAGE43_I260@MSTR_SCONN.SCONN288_H44441004(CHIPS)':
 'VDD'<19>: CDS_PINID='VDD(19)';
NODE_NAME     J4G1 73
 '@BASEBOARD_FAB2_LIB.BASEBOARD_FAB2(SCH_1):PAGE43_I260@MSTR_SCONN.SCONN288_H44441004(CHIPS)':
 'VDD'<20>: CDS_PINID='VDD(20)';
NODE_NAME     J4G1 70
 '@BASEBOARD_FAB2_LIB.BASEBOARD_FAB2(SCH_1):PAGE43_I260@MSTR_SCONN.SCONN288_H44441004(CHIPS)':
 'VDD'<21>: CDS_PINID='VDD(21)';
NODE_NAME     J4G1 67
 '@BASEBOARD_FAB2_LIB.BASEBOARD_FAB2(SCH_1):PAGE43_I260@MSTR_SCONN.SCONN288_H44441004(CHIPS)':
 'VDD'<22>: CDS_PINID='VDD(22)';
NODE_NAME     J4G1 64
 '@BASEBOARD_FAB2_LIB.BASEBOARD_FAB2(SCH_1):PAGE43_I260@MSTR_SCONN.SCONN288_H44441004(CHIPS)':
 'VDD'<23>: CDS_PINID='VDD(23)';
NODE_NAME     J4G1 61
 '@BASEBOARD_FAB2_LIB.BASEBOARD_FAB2(SCH_1):PAGE43_I260@MSTR_SCONN.SCONN288_H44441004(CHIPS)':
 'VDD'<24>: CDS_PINID='VDD(24)';
NODE_NAME     J4G1 59
 '@BASEBOARD_FAB2_LIB.BASEBOARD_FAB2(SCH_1):PAGE43_I260@MSTR_SCONN.SCONN288_H44441004(CHIPS)':
 'VDD'<25>: CDS_PINID='VDD(25)';
NODE_NAME     J6T1 236
 '@BASEBOARD_FAB2_LIB.BASEBOARD_FAB2(SCH_1):PAGE44_I75@MSTR_SCONN.SCONN288_H44441003(CHIPS)':
 'VDD'<0>: CDS_PINID='VDD(0)';
NODE_NAME     J6T1 233
 '@BASEBOARD_FAB2_LIB.BASEBOARD_FAB2(SCH_1):PAGE44_I75@MSTR_SCONN.SCONN288_H44441003(CHIPS)':
 'VDD'<1>: CDS_PINID='VDD(1)';
NODE_NAME     J6T1 231
 '@BASEBOARD_FAB2_LIB.BASEBOARD_FAB2(SCH_1):PAGE44_I75@MSTR_SCONN.SCONN288_H44441003(CHIPS)':
 'VDD'<2>: CDS_PINID='VDD(2)';
NODE_NAME     J6T1 229
 '@BASEBOARD_FAB2_LIB.BASEBOARD_FAB2(SCH_1):PAGE44_I75@MSTR_SCONN.SCONN288_H44441003(CHIPS)':
 'VDD'<3>: CDS_PINID='VDD(3)';
NODE_NAME     J6T1 226
 '@BASEBOARD_FAB2_LIB.BASEBOARD_FAB2(SCH_1):PAGE44_I75@MSTR_SCONN.SCONN288_H44441003(CHIPS)':
 'VDD'<4>: CDS_PINID='VDD(4)';
NODE_NAME     J6T1 223
 '@BASEBOARD_FAB2_LIB.BASEBOARD_FAB2(SCH_1):PAGE44_I75@MSTR_SCONN.SCONN288_H44441003(CHIPS)':
 'VDD'<5>: CDS_PINID='VDD(5)';
NODE_NAME     J6T1 220
 '@BASEBOARD_FAB2_LIB.BASEBOARD_FAB2(SCH_1):PAGE44_I75@MSTR_SCONN.SCONN288_H44441003(CHIPS)':
 'VDD'<6>: CDS_PINID='VDD(6)';
NODE_NAME     J6T1 217
 '@BASEBOARD_FAB2_LIB.BASEBOARD_FAB2(SCH_1):PAGE44_I75@MSTR_SCONN.SCONN288_H44441003(CHIPS)':
 'VDD'<7>: CDS_PINID='VDD(7)';
NODE_NAME     J6T1 215
 '@BASEBOARD_FAB2_LIB.BASEBOARD_FAB2(SCH_1):PAGE44_I75@MSTR_SCONN.SCONN288_H44441003(CHIPS)':
 'VDD'<8>: CDS_PINID='VDD(8)';
NODE_NAME     J6T1 212
 '@BASEBOARD_FAB2_LIB.BASEBOARD_FAB2(SCH_1):PAGE44_I75@MSTR_SCONN.SCONN288_H44441003(CHIPS)':
 'VDD'<9>: CDS_PINID='VDD(9)';
NODE_NAME     J6T1 209
 '@BASEBOARD_FAB2_LIB.BASEBOARD_FAB2(SCH_1):PAGE44_I75@MSTR_SCONN.SCONN288_H44441003(CHIPS)':
 'VDD'<10>: CDS_PINID='VDD(10)';
NODE_NAME     J6T1 206
 '@BASEBOARD_FAB2_LIB.BASEBOARD_FAB2(SCH_1):PAGE44_I75@MSTR_SCONN.SCONN288_H44441003(CHIPS)':
 'VDD'<11>: CDS_PINID='VDD(11)';
NODE_NAME     J6T1 204
 '@BASEBOARD_FAB2_LIB.BASEBOARD_FAB2(SCH_1):PAGE44_I75@MSTR_SCONN.SCONN288_H44441003(CHIPS)':
 'VDD'<12>: CDS_PINID='VDD(12)';
NODE_NAME     J6T1 92
 '@BASEBOARD_FAB2_LIB.BASEBOARD_FAB2(SCH_1):PAGE44_I75@MSTR_SCONN.SCONN288_H44441003(CHIPS)':
 'VDD'<13>: CDS_PINID='VDD(13)';
NODE_NAME     J6T1 90
 '@BASEBOARD_FAB2_LIB.BASEBOARD_FAB2(SCH_1):PAGE44_I75@MSTR_SCONN.SCONN288_H44441003(CHIPS)':
 'VDD'<14>: CDS_PINID='VDD(14)';
NODE_NAME     J6T1 88
 '@BASEBOARD_FAB2_LIB.BASEBOARD_FAB2(SCH_1):PAGE44_I75@MSTR_SCONN.SCONN288_H44441003(CHIPS)':
 'VDD'<15>: CDS_PINID='VDD(15)';
NODE_NAME     J6T1 85
 '@BASEBOARD_FAB2_LIB.BASEBOARD_FAB2(SCH_1):PAGE44_I75@MSTR_SCONN.SCONN288_H44441003(CHIPS)':
 'VDD'<16>: CDS_PINID='VDD(16)';
NODE_NAME     J6T1 83
 '@BASEBOARD_FAB2_LIB.BASEBOARD_FAB2(SCH_1):PAGE44_I75@MSTR_SCONN.SCONN288_H44441003(CHIPS)':
 'VDD'<17>: CDS_PINID='VDD(17)';
NODE_NAME     J6T1 80
 '@BASEBOARD_FAB2_LIB.BASEBOARD_FAB2(SCH_1):PAGE44_I75@MSTR_SCONN.SCONN288_H44441003(CHIPS)':
 'VDD'<18>: CDS_PINID='VDD(18)';
NODE_NAME     J6T1 76
 '@BASEBOARD_FAB2_LIB.BASEBOARD_FAB2(SCH_1):PAGE44_I75@MSTR_SCONN.SCONN288_H44441003(CHIPS)':
 'VDD'<19>: CDS_PINID='VDD(19)';
NODE_NAME     J6T1 73
 '@BASEBOARD_FAB2_LIB.BASEBOARD_FAB2(SCH_1):PAGE44_I75@MSTR_SCONN.SCONN288_H44441003(CHIPS)':
 'VDD'<20>: CDS_PINID='VDD(20)';
NODE_NAME     J6T1 70
 '@BASEBOARD_FAB2_LIB.BASEBOARD_FAB2(SCH_1):PAGE44_I75@MSTR_SCONN.SCONN288_H44441003(CHIPS)':
 'VDD'<21>: CDS_PINID='VDD(21)';
NODE_NAME     J6T1 67
 '@BASEBOARD_FAB2_LIB.BASEBOARD_FAB2(SCH_1):PAGE44_I75@MSTR_SCONN.SCONN288_H44441003(CHIPS)':
 'VDD'<22>: CDS_PINID='VDD(22)';
NODE_NAME     J6T1 64
 '@BASEBOARD_FAB2_LIB.BASEBOARD_FAB2(SCH_1):PAGE44_I75@MSTR_SCONN.SCONN288_H44441003(CHIPS)':
 'VDD'<23>: CDS_PINID='VDD(23)';
NODE_NAME     J6T1 61
 '@BASEBOARD_FAB2_LIB.BASEBOARD_FAB2(SCH_1):PAGE44_I75@MSTR_SCONN.SCONN288_H44441003(CHIPS)':
 'VDD'<24>: CDS_PINID='VDD(24)';
NODE_NAME     J6T1 59
 '@BASEBOARD_FAB2_LIB.BASEBOARD_FAB2(SCH_1):PAGE44_I75@MSTR_SCONN.SCONN288_H44441003(CHIPS)':
 'VDD'<25>: CDS_PINID='VDD(25)';
NODE_NAME     J4G2 236
 '@BASEBOARD_FAB2_LIB.BASEBOARD_FAB2(SCH_1):PAGE45_I169@MSTR_SCONN.SCONN288_H44441004(CHIPS)':
 'VDD'<0>: CDS_PINID='VDD(0)';
NODE_NAME     J4G2 233
 '@BASEBOARD_FAB2_LIB.BASEBOARD_FAB2(SCH_1):PAGE45_I169@MSTR_SCONN.SCONN288_H44441004(CHIPS)':
 'VDD'<1>: CDS_PINID='VDD(1)';
NODE_NAME     J4G2 231
 '@BASEBOARD_FAB2_LIB.BASEBOARD_FAB2(SCH_1):PAGE45_I169@MSTR_SCONN.SCONN288_H44441004(CHIPS)':
 'VDD'<2>: CDS_PINID='VDD(2)';
NODE_NAME     J4G2 229
 '@BASEBOARD_FAB2_LIB.BASEBOARD_FAB2(SCH_1):PAGE45_I169@MSTR_SCONN.SCONN288_H44441004(CHIPS)':
 'VDD'<3>: CDS_PINID='VDD(3)';
NODE_NAME     J4G2 226
 '@BASEBOARD_FAB2_LIB.BASEBOARD_FAB2(SCH_1):PAGE45_I169@MSTR_SCONN.SCONN288_H44441004(CHIPS)':
 'VDD'<4>: CDS_PINID='VDD(4)';
NODE_NAME     J4G2 223
 '@BASEBOARD_FAB2_LIB.BASEBOARD_FAB2(SCH_1):PAGE45_I169@MSTR_SCONN.SCONN288_H44441004(CHIPS)':
 'VDD'<5>: CDS_PINID='VDD(5)';
NODE_NAME     J4G2 220
 '@BASEBOARD_FAB2_LIB.BASEBOARD_FAB2(SCH_1):PAGE45_I169@MSTR_SCONN.SCONN288_H44441004(CHIPS)':
 'VDD'<6>: CDS_PINID='VDD(6)';
NODE_NAME     J4G2 217
 '@BASEBOARD_FAB2_LIB.BASEBOARD_FAB2(SCH_1):PAGE45_I169@MSTR_SCONN.SCONN288_H44441004(CHIPS)':
 'VDD'<7>: CDS_PINID='VDD(7)';
NODE_NAME     J4G2 215
 '@BASEBOARD_FAB2_LIB.BASEBOARD_FAB2(SCH_1):PAGE45_I169@MSTR_SCONN.SCONN288_H44441004(CHIPS)':
 'VDD'<8>: CDS_PINID='VDD(8)';
NODE_NAME     J4G2 212
 '@BASEBOARD_FAB2_LIB.BASEBOARD_FAB2(SCH_1):PAGE45_I169@MSTR_SCONN.SCONN288_H44441004(CHIPS)':
 'VDD'<9>: CDS_PINID='VDD(9)';
NODE_NAME     J4G2 209
 '@BASEBOARD_FAB2_LIB.BASEBOARD_FAB2(SCH_1):PAGE45_I169@MSTR_SCONN.SCONN288_H44441004(CHIPS)':
 'VDD'<10>: CDS_PINID='VDD(10)';
NODE_NAME     J4G2 206
 '@BASEBOARD_FAB2_LIB.BASEBOARD_FAB2(SCH_1):PAGE45_I169@MSTR_SCONN.SCONN288_H44441004(CHIPS)':
 'VDD'<11>: CDS_PINID='VDD(11)';
NODE_NAME     J4G2 204
 '@BASEBOARD_FAB2_LIB.BASEBOARD_FAB2(SCH_1):PAGE45_I169@MSTR_SCONN.SCONN288_H44441004(CHIPS)':
 'VDD'<12>: CDS_PINID='VDD(12)';
NODE_NAME     J4G2 92
 '@BASEBOARD_FAB2_LIB.BASEBOARD_FAB2(SCH_1):PAGE45_I169@MSTR_SCONN.SCONN288_H44441004(CHIPS)':
 'VDD'<13>: CDS_PINID='VDD(13)';
NODE_NAME     J4G2 90
 '@BASEBOARD_FAB2_LIB.BASEBOARD_FAB2(SCH_1):PAGE45_I169@MSTR_SCONN.SCONN288_H44441004(CHIPS)':
 'VDD'<14>: CDS_PINID='VDD(14)';
NODE_NAME     J4G2 88
 '@BASEBOARD_FAB2_LIB.BASEBOARD_FAB2(SCH_1):PAGE45_I169@MSTR_SCONN.SCONN288_H44441004(CHIPS)':
 'VDD'<15>: CDS_PINID='VDD(15)';
NODE_NAME     J4G2 85
 '@BASEBOARD_FAB2_LIB.BASEBOARD_FAB2(SCH_1):PAGE45_I169@MSTR_SCONN.SCONN288_H44441004(CHIPS)':
 'VDD'<16>: CDS_PINID='VDD(16)';
NODE_NAME     J4G2 83
 '@BASEBOARD_FAB2_LIB.BASEBOARD_FAB2(SCH_1):PAGE45_I169@MSTR_SCONN.SCONN288_H44441004(CHIPS)':
 'VDD'<17>: CDS_PINID='VDD(17)';
NODE_NAME     J4G2 80
 '@BASEBOARD_FAB2_LIB.BASEBOARD_FAB2(SCH_1):PAGE45_I169@MSTR_SCONN.SCONN288_H44441004(CHIPS)':
 'VDD'<18>: CDS_PINID='VDD(18)';
NODE_NAME     J4G2 76
 '@BASEBOARD_FAB2_LIB.BASEBOARD_FAB2(SCH_1):PAGE45_I169@MSTR_SCONN.SCONN288_H44441004(CHIPS)':
 'VDD'<19>: CDS_PINID='VDD(19)';
NODE_NAME     J4G2 73
 '@BASEBOARD_FAB2_LIB.BASEBOARD_FAB2(SCH_1):PAGE45_I169@MSTR_SCONN.SCONN288_H44441004(CHIPS)':
 'VDD'<20>: CDS_PINID='VDD(20)';
NODE_NAME     J4G2 70
 '@BASEBOARD_FAB2_LIB.BASEBOARD_FAB2(SCH_1):PAGE45_I169@MSTR_SCONN.SCONN288_H44441004(CHIPS)':
 'VDD'<21>: CDS_PINID='VDD(21)';
NODE_NAME     J4G2 67
 '@BASEBOARD_FAB2_LIB.BASEBOARD_FAB2(SCH_1):PAGE45_I169@MSTR_SCONN.SCONN288_H44441004(CHIPS)':
 'VDD'<22>: CDS_PINID='VDD(22)';
NODE_NAME     J4G2 64
 '@BASEBOARD_FAB2_LIB.BASEBOARD_FAB2(SCH_1):PAGE45_I169@MSTR_SCONN.SCONN288_H44441004(CHIPS)':
 'VDD'<23>: CDS_PINID='VDD(23)';
NODE_NAME     J4G2 61
 '@BASEBOARD_FAB2_LIB.BASEBOARD_FAB2(SCH_1):PAGE45_I169@MSTR_SCONN.SCONN288_H44441004(CHIPS)':
 'VDD'<24>: CDS_PINID='VDD(24)';
NODE_NAME     J4G2 59
 '@BASEBOARD_FAB2_LIB.BASEBOARD_FAB2(SCH_1):PAGE45_I169@MSTR_SCONN.SCONN288_H44441004(CHIPS)':
 'VDD'<25>: CDS_PINID='VDD(25)';
NODE_NAME     J6U1 236
 '@BASEBOARD_FAB2_LIB.BASEBOARD_FAB2(SCH_1):PAGE46_I67@MSTR_SCONN.SCONN288_H44441003(CHIPS)':
 'VDD'<0>: CDS_PINID='VDD(0)';
NODE_NAME     J6U1 233
 '@BASEBOARD_FAB2_LIB.BASEBOARD_FAB2(SCH_1):PAGE46_I67@MSTR_SCONN.SCONN288_H44441003(CHIPS)':
 'VDD'<1>: CDS_PINID='VDD(1)';
NODE_NAME     J6U1 231
 '@BASEBOARD_FAB2_LIB.BASEBOARD_FAB2(SCH_1):PAGE46_I67@MSTR_SCONN.SCONN288_H44441003(CHIPS)':
 'VDD'<2>: CDS_PINID='VDD(2)';
NODE_NAME     J6U1 229
 '@BASEBOARD_FAB2_LIB.BASEBOARD_FAB2(SCH_1):PAGE46_I67@MSTR_SCONN.SCONN288_H44441003(CHIPS)':
 'VDD'<3>: CDS_PINID='VDD(3)';
NODE_NAME     J6U1 226
 '@BASEBOARD_FAB2_LIB.BASEBOARD_FAB2(SCH_1):PAGE46_I67@MSTR_SCONN.SCONN288_H44441003(CHIPS)':
 'VDD'<4>: CDS_PINID='VDD(4)';
NODE_NAME     J6U1 223
 '@BASEBOARD_FAB2_LIB.BASEBOARD_FAB2(SCH_1):PAGE46_I67@MSTR_SCONN.SCONN288_H44441003(CHIPS)':
 'VDD'<5>: CDS_PINID='VDD(5)';
NODE_NAME     J6U1 220
 '@BASEBOARD_FAB2_LIB.BASEBOARD_FAB2(SCH_1):PAGE46_I67@MSTR_SCONN.SCONN288_H44441003(CHIPS)':
 'VDD'<6>: CDS_PINID='VDD(6)';
NODE_NAME     J6U1 217
 '@BASEBOARD_FAB2_LIB.BASEBOARD_FAB2(SCH_1):PAGE46_I67@MSTR_SCONN.SCONN288_H44441003(CHIPS)':
 'VDD'<7>: CDS_PINID='VDD(7)';
NODE_NAME     J6U1 215
 '@BASEBOARD_FAB2_LIB.BASEBOARD_FAB2(SCH_1):PAGE46_I67@MSTR_SCONN.SCONN288_H44441003(CHIPS)':
 'VDD'<8>: CDS_PINID='VDD(8)';
NODE_NAME     J6U1 212
 '@BASEBOARD_FAB2_LIB.BASEBOARD_FAB2(SCH_1):PAGE46_I67@MSTR_SCONN.SCONN288_H44441003(CHIPS)':
 'VDD'<9>: CDS_PINID='VDD(9)';
NODE_NAME     J6U1 209
 '@BASEBOARD_FAB2_LIB.BASEBOARD_FAB2(SCH_1):PAGE46_I67@MSTR_SCONN.SCONN288_H44441003(CHIPS)':
 'VDD'<10>: CDS_PINID='VDD(10)';
NODE_NAME     J6U1 206
 '@BASEBOARD_FAB2_LIB.BASEBOARD_FAB2(SCH_1):PAGE46_I67@MSTR_SCONN.SCONN288_H44441003(CHIPS)':
 'VDD'<11>: CDS_PINID='VDD(11)';
NODE_NAME     J6U1 204
 '@BASEBOARD_FAB2_LIB.BASEBOARD_FAB2(SCH_1):PAGE46_I67@MSTR_SCONN.SCONN288_H44441003(CHIPS)':
 'VDD'<12>: CDS_PINID='VDD(12)';
NODE_NAME     J6U1 92
 '@BASEBOARD_FAB2_LIB.BASEBOARD_FAB2(SCH_1):PAGE46_I67@MSTR_SCONN.SCONN288_H44441003(CHIPS)':
 'VDD'<13>: CDS_PINID='VDD(13)';
NODE_NAME     J6U1 90
 '@BASEBOARD_FAB2_LIB.BASEBOARD_FAB2(SCH_1):PAGE46_I67@MSTR_SCONN.SCONN288_H44441003(CHIPS)':
 'VDD'<14>: CDS_PINID='VDD(14)';
NODE_NAME     J6U1 88
 '@BASEBOARD_FAB2_LIB.BASEBOARD_FAB2(SCH_1):PAGE46_I67@MSTR_SCONN.SCONN288_H44441003(CHIPS)':
 'VDD'<15>: CDS_PINID='VDD(15)';
NODE_NAME     J6U1 85
 '@BASEBOARD_FAB2_LIB.BASEBOARD_FAB2(SCH_1):PAGE46_I67@MSTR_SCONN.SCONN288_H44441003(CHIPS)':
 'VDD'<16>: CDS_PINID='VDD(16)';
NODE_NAME     J6U1 83
 '@BASEBOARD_FAB2_LIB.BASEBOARD_FAB2(SCH_1):PAGE46_I67@MSTR_SCONN.SCONN288_H44441003(CHIPS)':
 'VDD'<17>: CDS_PINID='VDD(17)';
NODE_NAME     J6U1 80
 '@BASEBOARD_FAB2_LIB.BASEBOARD_FAB2(SCH_1):PAGE46_I67@MSTR_SCONN.SCONN288_H44441003(CHIPS)':
 'VDD'<18>: CDS_PINID='VDD(18)';
NODE_NAME     J6U1 76
 '@BASEBOARD_FAB2_LIB.BASEBOARD_FAB2(SCH_1):PAGE46_I67@MSTR_SCONN.SCONN288_H44441003(CHIPS)':
 'VDD'<19>: CDS_PINID='VDD(19)';
NODE_NAME     J6U1 73
 '@BASEBOARD_FAB2_LIB.BASEBOARD_FAB2(SCH_1):PAGE46_I67@MSTR_SCONN.SCONN288_H44441003(CHIPS)':
 'VDD'<20>: CDS_PINID='VDD(20)';
NODE_NAME     J6U1 70
 '@BASEBOARD_FAB2_LIB.BASEBOARD_FAB2(SCH_1):PAGE46_I67@MSTR_SCONN.SCONN288_H44441003(CHIPS)':
 'VDD'<21>: CDS_PINID='VDD(21)';
NODE_NAME     J6U1 67
 '@BASEBOARD_FAB2_LIB.BASEBOARD_FAB2(SCH_1):PAGE46_I67@MSTR_SCONN.SCONN288_H44441003(CHIPS)':
 'VDD'<22>: CDS_PINID='VDD(22)';
NODE_NAME     J6U1 64
 '@BASEBOARD_FAB2_LIB.BASEBOARD_FAB2(SCH_1):PAGE46_I67@MSTR_SCONN.SCONN288_H44441003(CHIPS)':
 'VDD'<23>: CDS_PINID='VDD(23)';
NODE_NAME     J6U1 61
 '@BASEBOARD_FAB2_LIB.BASEBOARD_FAB2(SCH_1):PAGE46_I67@MSTR_SCONN.SCONN288_H44441003(CHIPS)':
 'VDD'<24>: CDS_PINID='VDD(24)';
NODE_NAME     J6U1 59
 '@BASEBOARD_FAB2_LIB.BASEBOARD_FAB2(SCH_1):PAGE46_I67@MSTR_SCONN.SCONN288_H44441003(CHIPS)':
 'VDD'<25>: CDS_PINID='VDD(25)';
NODE_NAME     J4G3 236
 '@BASEBOARD_FAB2_LIB.BASEBOARD_FAB2(SCH_1):PAGE47_I179@MSTR_SCONN.SCONN288_H44441004(CHIPS)':
 'VDD'<0>: CDS_PINID='VDD(0)';
NODE_NAME     J4G3 233
 '@BASEBOARD_FAB2_LIB.BASEBOARD_FAB2(SCH_1):PAGE47_I179@MSTR_SCONN.SCONN288_H44441004(CHIPS)':
 'VDD'<1>: CDS_PINID='VDD(1)';
NODE_NAME     J4G3 231
 '@BASEBOARD_FAB2_LIB.BASEBOARD_FAB2(SCH_1):PAGE47_I179@MSTR_SCONN.SCONN288_H44441004(CHIPS)':
 'VDD'<2>: CDS_PINID='VDD(2)';
NODE_NAME     J4G3 229
 '@BASEBOARD_FAB2_LIB.BASEBOARD_FAB2(SCH_1):PAGE47_I179@MSTR_SCONN.SCONN288_H44441004(CHIPS)':
 'VDD'<3>: CDS_PINID='VDD(3)';
NODE_NAME     J4G3 226
 '@BASEBOARD_FAB2_LIB.BASEBOARD_FAB2(SCH_1):PAGE47_I179@MSTR_SCONN.SCONN288_H44441004(CHIPS)':
 'VDD'<4>: CDS_PINID='VDD(4)';
NODE_NAME     J4G3 223
 '@BASEBOARD_FAB2_LIB.BASEBOARD_FAB2(SCH_1):PAGE47_I179@MSTR_SCONN.SCONN288_H44441004(CHIPS)':
 'VDD'<5>: CDS_PINID='VDD(5)';
NODE_NAME     J4G3 220
 '@BASEBOARD_FAB2_LIB.BASEBOARD_FAB2(SCH_1):PAGE47_I179@MSTR_SCONN.SCONN288_H44441004(CHIPS)':
 'VDD'<6>: CDS_PINID='VDD(6)';
NODE_NAME     J4G3 217
 '@BASEBOARD_FAB2_LIB.BASEBOARD_FAB2(SCH_1):PAGE47_I179@MSTR_SCONN.SCONN288_H44441004(CHIPS)':
 'VDD'<7>: CDS_PINID='VDD(7)';
NODE_NAME     J4G3 215
 '@BASEBOARD_FAB2_LIB.BASEBOARD_FAB2(SCH_1):PAGE47_I179@MSTR_SCONN.SCONN288_H44441004(CHIPS)':
 'VDD'<8>: CDS_PINID='VDD(8)';
NODE_NAME     J4G3 212
 '@BASEBOARD_FAB2_LIB.BASEBOARD_FAB2(SCH_1):PAGE47_I179@MSTR_SCONN.SCONN288_H44441004(CHIPS)':
 'VDD'<9>: CDS_PINID='VDD(9)';
NODE_NAME     J4G3 209
 '@BASEBOARD_FAB2_LIB.BASEBOARD_FAB2(SCH_1):PAGE47_I179@MSTR_SCONN.SCONN288_H44441004(CHIPS)':
 'VDD'<10>: CDS_PINID='VDD(10)';
NODE_NAME     J4G3 206
 '@BASEBOARD_FAB2_LIB.BASEBOARD_FAB2(SCH_1):PAGE47_I179@MSTR_SCONN.SCONN288_H44441004(CHIPS)':
 'VDD'<11>: CDS_PINID='VDD(11)';
NODE_NAME     J4G3 204
 '@BASEBOARD_FAB2_LIB.BASEBOARD_FAB2(SCH_1):PAGE47_I179@MSTR_SCONN.SCONN288_H44441004(CHIPS)':
 'VDD'<12>: CDS_PINID='VDD(12)';
NODE_NAME     J4G3 92
 '@BASEBOARD_FAB2_LIB.BASEBOARD_FAB2(SCH_1):PAGE47_I179@MSTR_SCONN.SCONN288_H44441004(CHIPS)':
 'VDD'<13>: CDS_PINID='VDD(13)';
NODE_NAME     J4G3 90
 '@BASEBOARD_FAB2_LIB.BASEBOARD_FAB2(SCH_1):PAGE47_I179@MSTR_SCONN.SCONN288_H44441004(CHIPS)':
 'VDD'<14>: CDS_PINID='VDD(14)';
NODE_NAME     J4G3 88
 '@BASEBOARD_FAB2_LIB.BASEBOARD_FAB2(SCH_1):PAGE47_I179@MSTR_SCONN.SCONN288_H44441004(CHIPS)':
 'VDD'<15>: CDS_PINID='VDD(15)';
NODE_NAME     J4G3 85
 '@BASEBOARD_FAB2_LIB.BASEBOARD_FAB2(SCH_1):PAGE47_I179@MSTR_SCONN.SCONN288_H44441004(CHIPS)':
 'VDD'<16>: CDS_PINID='VDD(16)';
NODE_NAME     J4G3 83
 '@BASEBOARD_FAB2_LIB.BASEBOARD_FAB2(SCH_1):PAGE47_I179@MSTR_SCONN.SCONN288_H44441004(CHIPS)':
 'VDD'<17>: CDS_PINID='VDD(17)';
NODE_NAME     J4G3 80
 '@BASEBOARD_FAB2_LIB.BASEBOARD_FAB2(SCH_1):PAGE47_I179@MSTR_SCONN.SCONN288_H44441004(CHIPS)':
 'VDD'<18>: CDS_PINID='VDD(18)';
NODE_NAME     J4G3 76
 '@BASEBOARD_FAB2_LIB.BASEBOARD_FAB2(SCH_1):PAGE47_I179@MSTR_SCONN.SCONN288_H44441004(CHIPS)':
 'VDD'<19>: CDS_PINID='VDD(19)';
NODE_NAME     J4G3 73
 '@BASEBOARD_FAB2_LIB.BASEBOARD_FAB2(SCH_1):PAGE47_I179@MSTR_SCONN.SCONN288_H44441004(CHIPS)':
 'VDD'<20>: CDS_PINID='VDD(20)';
NODE_NAME     J4G3 70
 '@BASEBOARD_FAB2_LIB.BASEBOARD_FAB2(SCH_1):PAGE47_I179@MSTR_SCONN.SCONN288_H44441004(CHIPS)':
 'VDD'<21>: CDS_PINID='VDD(21)';
NODE_NAME     J4G3 67
 '@BASEBOARD_FAB2_LIB.BASEBOARD_FAB2(SCH_1):PAGE47_I179@MSTR_SCONN.SCONN288_H44441004(CHIPS)':
 'VDD'<22>: CDS_PINID='VDD(22)';
NODE_NAME     J4G3 64
 '@BASEBOARD_FAB2_LIB.BASEBOARD_FAB2(SCH_1):PAGE47_I179@MSTR_SCONN.SCONN288_H44441004(CHIPS)':
 'VDD'<23>: CDS_PINID='VDD(23)';
NODE_NAME     J4G3 61
 '@BASEBOARD_FAB2_LIB.BASEBOARD_FAB2(SCH_1):PAGE47_I179@MSTR_SCONN.SCONN288_H44441004(CHIPS)':
 'VDD'<24>: CDS_PINID='VDD(24)';
NODE_NAME     J4G3 59
 '@BASEBOARD_FAB2_LIB.BASEBOARD_FAB2(SCH_1):PAGE47_I179@MSTR_SCONN.SCONN288_H44441004(CHIPS)':
 'VDD'<25>: CDS_PINID='VDD(25)';
NODE_NAME     J6U2 236
 '@BASEBOARD_FAB2_LIB.BASEBOARD_FAB2(SCH_1):PAGE48_I171@MSTR_SCONN.SCONN288_H44441003(CHIPS)':
 'VDD'<0>: CDS_PINID='VDD(0)';
NODE_NAME     J6U2 233
 '@BASEBOARD_FAB2_LIB.BASEBOARD_FAB2(SCH_1):PAGE48_I171@MSTR_SCONN.SCONN288_H44441003(CHIPS)':
 'VDD'<1>: CDS_PINID='VDD(1)';
NODE_NAME     J6U2 231
 '@BASEBOARD_FAB2_LIB.BASEBOARD_FAB2(SCH_1):PAGE48_I171@MSTR_SCONN.SCONN288_H44441003(CHIPS)':
 'VDD'<2>: CDS_PINID='VDD(2)';
NODE_NAME     J6U2 229
 '@BASEBOARD_FAB2_LIB.BASEBOARD_FAB2(SCH_1):PAGE48_I171@MSTR_SCONN.SCONN288_H44441003(CHIPS)':
 'VDD'<3>: CDS_PINID='VDD(3)';
NODE_NAME     J6U2 226
 '@BASEBOARD_FAB2_LIB.BASEBOARD_FAB2(SCH_1):PAGE48_I171@MSTR_SCONN.SCONN288_H44441003(CHIPS)':
 'VDD'<4>: CDS_PINID='VDD(4)';
NODE_NAME     J6U2 223
 '@BASEBOARD_FAB2_LIB.BASEBOARD_FAB2(SCH_1):PAGE48_I171@MSTR_SCONN.SCONN288_H44441003(CHIPS)':
 'VDD'<5>: CDS_PINID='VDD(5)';
NODE_NAME     J6U2 220
 '@BASEBOARD_FAB2_LIB.BASEBOARD_FAB2(SCH_1):PAGE48_I171@MSTR_SCONN.SCONN288_H44441003(CHIPS)':
 'VDD'<6>: CDS_PINID='VDD(6)';
NODE_NAME     J6U2 217
 '@BASEBOARD_FAB2_LIB.BASEBOARD_FAB2(SCH_1):PAGE48_I171@MSTR_SCONN.SCONN288_H44441003(CHIPS)':
 'VDD'<7>: CDS_PINID='VDD(7)';
NODE_NAME     J6U2 215
 '@BASEBOARD_FAB2_LIB.BASEBOARD_FAB2(SCH_1):PAGE48_I171@MSTR_SCONN.SCONN288_H44441003(CHIPS)':
 'VDD'<8>: CDS_PINID='VDD(8)';
NODE_NAME     J6U2 212
 '@BASEBOARD_FAB2_LIB.BASEBOARD_FAB2(SCH_1):PAGE48_I171@MSTR_SCONN.SCONN288_H44441003(CHIPS)':
 'VDD'<9>: CDS_PINID='VDD(9)';
NODE_NAME     J6U2 209
 '@BASEBOARD_FAB2_LIB.BASEBOARD_FAB2(SCH_1):PAGE48_I171@MSTR_SCONN.SCONN288_H44441003(CHIPS)':
 'VDD'<10>: CDS_PINID='VDD(10)';
NODE_NAME     J6U2 206
 '@BASEBOARD_FAB2_LIB.BASEBOARD_FAB2(SCH_1):PAGE48_I171@MSTR_SCONN.SCONN288_H44441003(CHIPS)':
 'VDD'<11>: CDS_PINID='VDD(11)';
NODE_NAME     J6U2 204
 '@BASEBOARD_FAB2_LIB.BASEBOARD_FAB2(SCH_1):PAGE48_I171@MSTR_SCONN.SCONN288_H44441003(CHIPS)':
 'VDD'<12>: CDS_PINID='VDD(12)';
NODE_NAME     J6U2 92
 '@BASEBOARD_FAB2_LIB.BASEBOARD_FAB2(SCH_1):PAGE48_I171@MSTR_SCONN.SCONN288_H44441003(CHIPS)':
 'VDD'<13>: CDS_PINID='VDD(13)';
NODE_NAME     J6U2 90
 '@BASEBOARD_FAB2_LIB.BASEBOARD_FAB2(SCH_1):PAGE48_I171@MSTR_SCONN.SCONN288_H44441003(CHIPS)':
 'VDD'<14>: CDS_PINID='VDD(14)';
NODE_NAME     J6U2 88
 '@BASEBOARD_FAB2_LIB.BASEBOARD_FAB2(SCH_1):PAGE48_I171@MSTR_SCONN.SCONN288_H44441003(CHIPS)':
 'VDD'<15>: CDS_PINID='VDD(15)';
NODE_NAME     J6U2 85
 '@BASEBOARD_FAB2_LIB.BASEBOARD_FAB2(SCH_1):PAGE48_I171@MSTR_SCONN.SCONN288_H44441003(CHIPS)':
 'VDD'<16>: CDS_PINID='VDD(16)';
NODE_NAME     J6U2 83
 '@BASEBOARD_FAB2_LIB.BASEBOARD_FAB2(SCH_1):PAGE48_I171@MSTR_SCONN.SCONN288_H44441003(CHIPS)':
 'VDD'<17>: CDS_PINID='VDD(17)';
NODE_NAME     J6U2 80
 '@BASEBOARD_FAB2_LIB.BASEBOARD_FAB2(SCH_1):PAGE48_I171@MSTR_SCONN.SCONN288_H44441003(CHIPS)':
 'VDD'<18>: CDS_PINID='VDD(18)';
NODE_NAME     J6U2 76
 '@BASEBOARD_FAB2_LIB.BASEBOARD_FAB2(SCH_1):PAGE48_I171@MSTR_SCONN.SCONN288_H44441003(CHIPS)':
 'VDD'<19>: CDS_PINID='VDD(19)';
NODE_NAME     J6U2 73
 '@BASEBOARD_FAB2_LIB.BASEBOARD_FAB2(SCH_1):PAGE48_I171@MSTR_SCONN.SCONN288_H44441003(CHIPS)':
 'VDD'<20>: CDS_PINID='VDD(20)';
NODE_NAME     J6U2 70
 '@BASEBOARD_FAB2_LIB.BASEBOARD_FAB2(SCH_1):PAGE48_I171@MSTR_SCONN.SCONN288_H44441003(CHIPS)':
 'VDD'<21>: CDS_PINID='VDD(21)';
NODE_NAME     J6U2 67
 '@BASEBOARD_FAB2_LIB.BASEBOARD_FAB2(SCH_1):PAGE48_I171@MSTR_SCONN.SCONN288_H44441003(CHIPS)':
 'VDD'<22>: CDS_PINID='VDD(22)';
NODE_NAME     J6U2 64
 '@BASEBOARD_FAB2_LIB.BASEBOARD_FAB2(SCH_1):PAGE48_I171@MSTR_SCONN.SCONN288_H44441003(CHIPS)':
 'VDD'<23>: CDS_PINID='VDD(23)';
NODE_NAME     J6U2 61
 '@BASEBOARD_FAB2_LIB.BASEBOARD_FAB2(SCH_1):PAGE48_I171@MSTR_SCONN.SCONN288_H44441003(CHIPS)':
 'VDD'<24>: CDS_PINID='VDD(24)';
NODE_NAME     J6U2 59
 '@BASEBOARD_FAB2_LIB.BASEBOARD_FAB2(SCH_1):PAGE48_I171@MSTR_SCONN.SCONN288_H44441003(CHIPS)':
 'VDD'<25>: CDS_PINID='VDD(25)';
NODE_NAME     R3P38 1
 '@BASEBOARD_FAB2_LIB.BASEBOARD_FAB2(SCH_1):PAGE96_I7@MSTR_DISCRETE.RES(CHIPS)':
 'A': CDS_PINID='A';
NODE_NAME     R4F4 1
 '@BASEBOARD_FAB2_LIB.BASEBOARD_FAB2(SCH_1):PAGE98_I36@MSTR_DISCRETE.RES(CHIPS)':
 'A': CDS_PINID='A';
NODE_NAME     R4G2 1
 '@BASEBOARD_FAB2_LIB.BASEBOARD_FAB2(SCH_1):PAGE98_I38@MSTR_DISCRETE.RES(CHIPS)':
 'A': CDS_PINID='A';
NODE_NAME     R4G21 1
 '@BASEBOARD_FAB2_LIB.BASEBOARD_FAB2(SCH_1):PAGE98_I46@MSTR_DISCRETE.RES(CHIPS)':
 'A': CDS_PINID='A';
NODE_NAME     C6G3 1
 '@BASEBOARD_FAB2_LIB.BASEBOARD_FAB2(SCH_1):PAGE216_I6@MSTR_DISCRETE.CAP(CHIPS)':
 'A': CDS_PINID='A';
NODE_NAME     C7G27 1
 '@BASEBOARD_FAB2_LIB.BASEBOARD_FAB2(SCH_1):PAGE216_I68@MSTR_DISCRETE.CAP(CHIPS)':
 'A': CDS_PINID='A';
NODE_NAME     EU7G2 1
 '@BASEBOARD_FAB2_LIB.BASEBOARD_FAB2(SCH_1):PAGE216_I102@MSTR_DISCRETE.IR354XX(CHIPS)':
 'VOS': CDS_PINID='VOS';
NODE_NAME     EU7G3 1
 '@BASEBOARD_FAB2_LIB.BASEBOARD_FAB2(SCH_1):PAGE216_I103@MSTR_DISCRETE.IR354XX(CHIPS)':
 'VOS': CDS_PINID='VOS';
NODE_NAME     R3U4 1
 '@BASEBOARD_FAB2_LIB.BASEBOARD_FAB2(SCH_1):PAGE217_I58@MSTR_DISCRETE.RES(CHIPS)':
 'A': CDS_PINID='A';
NODE_NAME     C7G28 1
 '@BASEBOARD_FAB2_LIB.BASEBOARD_FAB2(SCH_1):PAGE217_I75@MSTR_DISCRETE.CAPP(CHIPS)':
 'A': CDS_PINID='A';
NODE_NAME     C3U1 1
 '@BASEBOARD_FAB2_LIB.BASEBOARD_FAB2(SCH_1):PAGE217_I76@MSTR_DISCRETE.CAPP(CHIPS)':
 'A': CDS_PINID='A';
NODE_NAME     C3U5 1
 '@BASEBOARD_FAB2_LIB.BASEBOARD_FAB2(SCH_1):PAGE217_I77@MSTR_DISCRETE.CAPP(CHIPS)':
 'A': CDS_PINID='A';
NODE_NAME     C3U8 1
 '@BASEBOARD_FAB2_LIB.BASEBOARD_FAB2(SCH_1):PAGE217_I78@MSTR_DISCRETE.CAPP(CHIPS)':
 'A': CDS_PINID='A';
NODE_NAME     C5F2 1
 '@BASEBOARD_FAB2_LIB.BASEBOARD_FAB2(SCH_1):PAGE217_I205@DEV_DISCRETE.CAP_A(CHIPS)':
 'A': CDS_PINID='A';
NODE_NAME     C5F1 1
 '@BASEBOARD_FAB2_LIB.BASEBOARD_FAB2(SCH_1):PAGE217_I206@DEV_DISCRETE.CAP_A(CHIPS)':
 'A': CDS_PINID='A';
NODE_NAME     C5G10 1
 '@BASEBOARD_FAB2_LIB.BASEBOARD_FAB2(SCH_1):PAGE217_I207@DEV_DISCRETE.CAP_A(CHIPS)':
 'A': CDS_PINID='A';
NODE_NAME     C5T2 1
 '@BASEBOARD_FAB2_LIB.BASEBOARD_FAB2(SCH_1):PAGE217_I208@DEV_DISCRETE.CAP_A(CHIPS)':
 'A': CDS_PINID='A';
NODE_NAME     C5U11 1
 '@BASEBOARD_FAB2_LIB.BASEBOARD_FAB2(SCH_1):PAGE217_I209@DEV_DISCRETE.CAP_A(CHIPS)':
 'A': CDS_PINID='A';
NODE_NAME     C5T13 1
 '@BASEBOARD_FAB2_LIB.BASEBOARD_FAB2(SCH_1):PAGE217_I210@DEV_DISCRETE.CAP_A(CHIPS)':
 'A': CDS_PINID='A';
NODE_NAME     C5T4 1
 '@BASEBOARD_FAB2_LIB.BASEBOARD_FAB2(SCH_1):PAGE217_I211@DEV_DISCRETE.CAP_A(CHIPS)':
 'A': CDS_PINID='A';
NODE_NAME     C5T1 1
 '@BASEBOARD_FAB2_LIB.BASEBOARD_FAB2(SCH_1):PAGE217_I212@DEV_DISCRETE.CAP_A(CHIPS)':
 'A': CDS_PINID='A';
NODE_NAME     C5G19 1
 '@BASEBOARD_FAB2_LIB.BASEBOARD_FAB2(SCH_1):PAGE217_I213@DEV_DISCRETE.CAP_A(CHIPS)':
 'A': CDS_PINID='A';
NODE_NAME     SH4U2 2
 '@BASEBOARD_FAB2_LIB.BASEBOARD_FAB2(SCH_1):PAGE217_I260@MSTR_MISC.SHUNT(CHIPS)':
 'B':NET_SHORT='VSENSE_PVDDQ_ABC_P:PVDDQ_ABC',
 CDS_PINID='B';
NODE_NAME     C5G41 1
 '@BASEBOARD_FAB2_LIB.BASEBOARD_FAB2(SCH_1):PAGE242_I53@DEV_DISCRETE.CAP_A(CHIPS)':
 'A': CDS_PINID='A';
NODE_NAME     C5G42 1
 '@BASEBOARD_FAB2_LIB.BASEBOARD_FAB2(SCH_1):PAGE242_I54@DEV_DISCRETE.CAP_A(CHIPS)':
 'A': CDS_PINID='A';
NODE_NAME     C5G44 1
 '@BASEBOARD_FAB2_LIB.BASEBOARD_FAB2(SCH_1):PAGE242_I55@DEV_DISCRETE.CAP_A(CHIPS)':
 'A': CDS_PINID='A';
NODE_NAME     C5G43 1
 '@BASEBOARD_FAB2_LIB.BASEBOARD_FAB2(SCH_1):PAGE242_I56@DEV_DISCRETE.CAP_A(CHIPS)':
 'A': CDS_PINID='A';
NODE_NAME     C5G48 1
 '@BASEBOARD_FAB2_LIB.BASEBOARD_FAB2(SCH_1):PAGE242_I57@DEV_DISCRETE.CAP_A(CHIPS)':
 'A': CDS_PINID='A';
NODE_NAME     C5G47 1
 '@BASEBOARD_FAB2_LIB.BASEBOARD_FAB2(SCH_1):PAGE242_I58@DEV_DISCRETE.CAP_A(CHIPS)':
 'A': CDS_PINID='A';
NODE_NAME     C5G46 1
 '@BASEBOARD_FAB2_LIB.BASEBOARD_FAB2(SCH_1):PAGE242_I59@DEV_DISCRETE.CAP_A(CHIPS)':
 'A': CDS_PINID='A';
NODE_NAME     C5G45 1
 '@BASEBOARD_FAB2_LIB.BASEBOARD_FAB2(SCH_1):PAGE242_I60@DEV_DISCRETE.CAP_A(CHIPS)':
 'A': CDS_PINID='A';
NODE_NAME     C5G49 1
 '@BASEBOARD_FAB2_LIB.BASEBOARD_FAB2(SCH_1):PAGE242_I61@DEV_DISCRETE.CAP_A(CHIPS)':
 'A': CDS_PINID='A';
NODE_NAME     C5G54 1
 '@BASEBOARD_FAB2_LIB.BASEBOARD_FAB2(SCH_1):PAGE242_I62@DEV_DISCRETE.CAP_A(CHIPS)':
 'A': CDS_PINID='A';
NODE_NAME     C5G58 1
 '@BASEBOARD_FAB2_LIB.BASEBOARD_FAB2(SCH_1):PAGE242_I63@DEV_DISCRETE.CAP_A(CHIPS)':
 'A': CDS_PINID='A';
NODE_NAME     C5G57 1
 '@BASEBOARD_FAB2_LIB.BASEBOARD_FAB2(SCH_1):PAGE242_I64@DEV_DISCRETE.CAP_A(CHIPS)':
 'A': CDS_PINID='A';
NODE_NAME     C5G56 1
 '@BASEBOARD_FAB2_LIB.BASEBOARD_FAB2(SCH_1):PAGE242_I65@DEV_DISCRETE.CAP_A(CHIPS)':
 'A': CDS_PINID='A';
NODE_NAME     C5G55 1
 '@BASEBOARD_FAB2_LIB.BASEBOARD_FAB2(SCH_1):PAGE242_I66@DEV_DISCRETE.CAP_A(CHIPS)':
 'A': CDS_PINID='A';
NODE_NAME     C5G53 1
 '@BASEBOARD_FAB2_LIB.BASEBOARD_FAB2(SCH_1):PAGE242_I67@DEV_DISCRETE.CAP_A(CHIPS)':
 'A': CDS_PINID='A';
NODE_NAME     C5G52 1
 '@BASEBOARD_FAB2_LIB.BASEBOARD_FAB2(SCH_1):PAGE242_I68@DEV_DISCRETE.CAP_A(CHIPS)':
 'A': CDS_PINID='A';
NODE_NAME     C5G51 1
 '@BASEBOARD_FAB2_LIB.BASEBOARD_FAB2(SCH_1):PAGE242_I69@DEV_DISCRETE.CAP_A(CHIPS)':
 'A': CDS_PINID='A';
NODE_NAME     C5G50 1
 '@BASEBOARD_FAB2_LIB.BASEBOARD_FAB2(SCH_1):PAGE242_I70@DEV_DISCRETE.CAP_A(CHIPS)':
 'A': CDS_PINID='A';
NODE_NAME     C5G22 1
 '@BASEBOARD_FAB2_LIB.BASEBOARD_FAB2(SCH_1):PAGE242_I90@MSTR_DISCRETE.CAP(CHIPS)':
 'A': CDS_PINID='A';
NODE_NAME     C5G21 1
 '@BASEBOARD_FAB2_LIB.BASEBOARD_FAB2(SCH_1):PAGE242_I92@MSTR_DISCRETE.CAP(CHIPS)':
 'A': CDS_PINID='A';
NODE_NAME     R6U5 1
 '@BASEBOARD_FAB2_LIB.BASEBOARD_FAB2(SCH_1):PAGE221_I6@MSTR_DISCRETE.RES(CHIPS)':
 'A': CDS_PINID='A';
NODE_NAME     C6U15 1
 '@BASEBOARD_FAB2_LIB.BASEBOARD_FAB2(SCH_1):PAGE221_I18@MSTR_DISCRETE.CAP(CHIPS)':
 'A': CDS_PINID='A';
NODE_NAME     C6U16 1
 '@BASEBOARD_FAB2_LIB.BASEBOARD_FAB2(SCH_1):PAGE221_I19@MSTR_DISCRETE.CAP(CHIPS)':
 'A': CDS_PINID='A';
NODE_NAME     EU4G3 10
 '@BASEBOARD_FAB2_LIB.BASEBOARD_FAB2(SCH_1):PAGE221_I15@MSTR_VREG.MIC5166(CHIPS)':
 'VIN': CDS_PINID='VIN';
NODE_NAME     C5D58 1
 '@BASEBOARD_FAB2_LIB.BASEBOARD_FAB2(SCH_1):PAGE217_I269@DEV_DISCRETE.CAP_A(CHIPS)':
 'A': CDS_PINID='A';
NODE_NAME     C5D61 1
 '@BASEBOARD_FAB2_LIB.BASEBOARD_FAB2(SCH_1):PAGE217_I270@DEV_DISCRETE.CAP_A(CHIPS)':
 'A': CDS_PINID='A';
NODE_NAME     C5D59 1
 '@BASEBOARD_FAB2_LIB.BASEBOARD_FAB2(SCH_1):PAGE217_I271@DEV_DISCRETE.CAP_A(CHIPS)':
 'A': CDS_PINID='A';
NODE_NAME     C5D60 1
 '@BASEBOARD_FAB2_LIB.BASEBOARD_FAB2(SCH_1):PAGE217_I272@DEV_DISCRETE.CAP_A(CHIPS)':
 'A': CDS_PINID='A';
NODE_NAME     C5D54 1
 '@BASEBOARD_FAB2_LIB.BASEBOARD_FAB2(SCH_1):PAGE217_I279@DEV_DISCRETE.CAP_A(CHIPS)':
 'A': CDS_PINID='A';
NODE_NAME     C5D55 1
 '@BASEBOARD_FAB2_LIB.BASEBOARD_FAB2(SCH_1):PAGE217_I280@DEV_DISCRETE.CAP_A(CHIPS)':
 'A': CDS_PINID='A';
NODE_NAME     C5D56 1
 '@BASEBOARD_FAB2_LIB.BASEBOARD_FAB2(SCH_1):PAGE217_I281@DEV_DISCRETE.CAP_A(CHIPS)':
 'A': CDS_PINID='A';
NODE_NAME     C5D57 1
 '@BASEBOARD_FAB2_LIB.BASEBOARD_FAB2(SCH_1):PAGE217_I282@DEV_DISCRETE.CAP_A(CHIPS)':
 'A': CDS_PINID='A';
NODE_NAME     C5U2 1
 '@BASEBOARD_FAB2_LIB.BASEBOARD_FAB2(SCH_1):PAGE217_I283@DEV_DISCRETE.CAP_A(CHIPS)':
 'A': CDS_PINID='A';
NODE_NAME     C5U3 1
 '@BASEBOARD_FAB2_LIB.BASEBOARD_FAB2(SCH_1):PAGE217_I284@DEV_DISCRETE.CAP_A(CHIPS)':
 'A': CDS_PINID='A';
NODE_NAME     C5U4 1
 '@BASEBOARD_FAB2_LIB.BASEBOARD_FAB2(SCH_1):PAGE217_I285@DEV_DISCRETE.CAP_A(CHIPS)':
 'A': CDS_PINID='A';
NODE_NAME     C5U5 1
 '@BASEBOARD_FAB2_LIB.BASEBOARD_FAB2(SCH_1):PAGE217_I286@DEV_DISCRETE.CAP_A(CHIPS)':
 'A': CDS_PINID='A';
NODE_NAME     C5U6 1
 '@BASEBOARD_FAB2_LIB.BASEBOARD_FAB2(SCH_1):PAGE217_I287@DEV_DISCRETE.CAP_A(CHIPS)':
 'A': CDS_PINID='A';
NODE_NAME     C5U7 1
 '@BASEBOARD_FAB2_LIB.BASEBOARD_FAB2(SCH_1):PAGE217_I288@DEV_DISCRETE.CAP_A(CHIPS)':
 'A': CDS_PINID='A';
NODE_NAME     C5U8 1
 '@BASEBOARD_FAB2_LIB.BASEBOARD_FAB2(SCH_1):PAGE217_I289@DEV_DISCRETE.CAP_A(CHIPS)':
 'A': CDS_PINID='A';
NODE_NAME     C5U9 1
 '@BASEBOARD_FAB2_LIB.BASEBOARD_FAB2(SCH_1):PAGE217_I290@DEV_DISCRETE.CAP_A(CHIPS)':
 'A': CDS_PINID='A';
NODE_NAME     C5T12 1
 '@BASEBOARD_FAB2_LIB.BASEBOARD_FAB2(SCH_1):PAGE217_I291@DEV_DISCRETE.CAP_A(CHIPS)':
 'A': CDS_PINID='A';
NODE_NAME     C5T11 1
 '@BASEBOARD_FAB2_LIB.BASEBOARD_FAB2(SCH_1):PAGE217_I292@DEV_DISCRETE.CAP_A(CHIPS)':
 'A': CDS_PINID='A';
NODE_NAME     C5T10 1
 '@BASEBOARD_FAB2_LIB.BASEBOARD_FAB2(SCH_1):PAGE217_I293@DEV_DISCRETE.CAP_A(CHIPS)':
 'A': CDS_PINID='A';
NODE_NAME     C5T9 1
 '@BASEBOARD_FAB2_LIB.BASEBOARD_FAB2(SCH_1):PAGE217_I294@DEV_DISCRETE.CAP_A(CHIPS)':
 'A': CDS_PINID='A';
NODE_NAME     C5T8 1
 '@BASEBOARD_FAB2_LIB.BASEBOARD_FAB2(SCH_1):PAGE217_I295@DEV_DISCRETE.CAP_A(CHIPS)':
 'A': CDS_PINID='A';
NODE_NAME     C5T7 1
 '@BASEBOARD_FAB2_LIB.BASEBOARD_FAB2(SCH_1):PAGE217_I296@DEV_DISCRETE.CAP_A(CHIPS)':
 'A': CDS_PINID='A';
NODE_NAME     C5T6 1
 '@BASEBOARD_FAB2_LIB.BASEBOARD_FAB2(SCH_1):PAGE217_I297@DEV_DISCRETE.CAP_A(CHIPS)':
 'A': CDS_PINID='A';
NODE_NAME     C5T5 1
 '@BASEBOARD_FAB2_LIB.BASEBOARD_FAB2(SCH_1):PAGE217_I298@DEV_DISCRETE.CAP_A(CHIPS)':
 'A': CDS_PINID='A';
NODE_NAME     C5G11 1
 '@BASEBOARD_FAB2_LIB.BASEBOARD_FAB2(SCH_1):PAGE217_I299@DEV_DISCRETE.CAP_A(CHIPS)':
 'A': CDS_PINID='A';
NODE_NAME     C5G12 1
 '@BASEBOARD_FAB2_LIB.BASEBOARD_FAB2(SCH_1):PAGE217_I300@DEV_DISCRETE.CAP_A(CHIPS)':
 'A': CDS_PINID='A';
NODE_NAME     C5G2 1
 '@BASEBOARD_FAB2_LIB.BASEBOARD_FAB2(SCH_1):PAGE217_I301@DEV_DISCRETE.CAP_A(CHIPS)':
 'A': CDS_PINID='A';
NODE_NAME     C5G4 1
 '@BASEBOARD_FAB2_LIB.BASEBOARD_FAB2(SCH_1):PAGE217_I302@DEV_DISCRETE.CAP_A(CHIPS)':
 'A': CDS_PINID='A';
NODE_NAME     C5G13 1
 '@BASEBOARD_FAB2_LIB.BASEBOARD_FAB2(SCH_1):PAGE217_I303@DEV_DISCRETE.CAP_A(CHIPS)':
 'A': CDS_PINID='A';
NODE_NAME     C5G6 1
 '@BASEBOARD_FAB2_LIB.BASEBOARD_FAB2(SCH_1):PAGE217_I304@DEV_DISCRETE.CAP_A(CHIPS)':
 'A': CDS_PINID='A';
NODE_NAME     C5G5 1
 '@BASEBOARD_FAB2_LIB.BASEBOARD_FAB2(SCH_1):PAGE217_I305@DEV_DISCRETE.CAP_A(CHIPS)':
 'A': CDS_PINID='A';
NODE_NAME     C5G7 1
 '@BASEBOARD_FAB2_LIB.BASEBOARD_FAB2(SCH_1):PAGE217_I306@DEV_DISCRETE.CAP_A(CHIPS)':
 'A': CDS_PINID='A';
NODE_NAME     C5G1 1
 '@BASEBOARD_FAB2_LIB.BASEBOARD_FAB2(SCH_1):PAGE217_I307@DEV_DISCRETE.CAP_A(CHIPS)':
 'A': CDS_PINID='A';
NODE_NAME     C5G8 1
 '@BASEBOARD_FAB2_LIB.BASEBOARD_FAB2(SCH_1):PAGE217_I308@DEV_DISCRETE.CAP_A(CHIPS)':
 'A': CDS_PINID='A';
NODE_NAME     C5G18 1
 '@BASEBOARD_FAB2_LIB.BASEBOARD_FAB2(SCH_1):PAGE217_I309@DEV_DISCRETE.CAP_A(CHIPS)':
 'A': CDS_PINID='A';
NODE_NAME     C5G17 1
 '@BASEBOARD_FAB2_LIB.BASEBOARD_FAB2(SCH_1):PAGE217_I310@DEV_DISCRETE.CAP_A(CHIPS)':
 'A': CDS_PINID='A';
NODE_NAME     C5G14 1
 '@BASEBOARD_FAB2_LIB.BASEBOARD_FAB2(SCH_1):PAGE217_I311@DEV_DISCRETE.CAP_A(CHIPS)':
 'A': CDS_PINID='A';
NODE_NAME     C5G16 1
 '@BASEBOARD_FAB2_LIB.BASEBOARD_FAB2(SCH_1):PAGE217_I312@DEV_DISCRETE.CAP_A(CHIPS)':
 'A': CDS_PINID='A';
NODE_NAME     C5G15 1
 '@BASEBOARD_FAB2_LIB.BASEBOARD_FAB2(SCH_1):PAGE217_I313@DEV_DISCRETE.CAP_A(CHIPS)':
 'A': CDS_PINID='A';
NODE_NAME     C5G3 1
 '@BASEBOARD_FAB2_LIB.BASEBOARD_FAB2(SCH_1):PAGE217_I314@DEV_DISCRETE.CAP_A(CHIPS)':
 'A': CDS_PINID='A';
NODE_NAME     L7G1 2
 '@BASEBOARD_FAB2_LIB.BASEBOARD_FAB2(SCH_1):PAGE216_I153@W_HDL.IND-120NH-30-GP(CHIPS)':
 'F': CDS_PINID='F';
NODE_NAME     C5U1 1
 '@BASEBOARD_FAB2_LIB.BASEBOARD_FAB2(SCH_1):PAGE217_I316@MSTR_DISCRETE.CAP(CHIPS)':
 'A': CDS_PINID='A';
NODE_NAME     C5U10 1
 '@BASEBOARD_FAB2_LIB.BASEBOARD_FAB2(SCH_1):PAGE217_I317@MSTR_DISCRETE.CAP(CHIPS)':
 'A': CDS_PINID='A';
NODE_NAME     C5G9 1
 '@BASEBOARD_FAB2_LIB.BASEBOARD_FAB2(SCH_1):PAGE217_I318@MSTR_DISCRETE.CAP(CHIPS)':
 'A': CDS_PINID='A';
NODE_NAME     C4T4 1
 '@BASEBOARD_FAB2_LIB.BASEBOARD_FAB2(SCH_1):PAGE217_I319@MSTR_DISCRETE.CAP(CHIPS)':
 'A': CDS_PINID='A';
NODE_NAME     C5U15 1
 '@BASEBOARD_FAB2_LIB.BASEBOARD_FAB2(SCH_1):PAGE217_I320@MSTR_DISCRETE.CAP(CHIPS)':
 'A': CDS_PINID='A';
NODE_NAME     C5U13 1
 '@BASEBOARD_FAB2_LIB.BASEBOARD_FAB2(SCH_1):PAGE217_I321@MSTR_DISCRETE.CAP(CHIPS)':
 'A': CDS_PINID='A';
NODE_NAME     C5U14 1
 '@BASEBOARD_FAB2_LIB.BASEBOARD_FAB2(SCH_1):PAGE217_I322@MSTR_DISCRETE.CAP(CHIPS)':
 'A': CDS_PINID='A';
NODE_NAME     C5P41 1
 '@BASEBOARD_FAB2_LIB.BASEBOARD_FAB2(SCH_1):PAGE217_I323@MSTR_DISCRETE.CAP(CHIPS)':
 'A': CDS_PINID='A';
NODE_NAME     C5P44 1
 '@BASEBOARD_FAB2_LIB.BASEBOARD_FAB2(SCH_1):PAGE217_I324@MSTR_DISCRETE.CAP(CHIPS)':
 'A': CDS_PINID='A';
NODE_NAME     C5P42 1
 '@BASEBOARD_FAB2_LIB.BASEBOARD_FAB2(SCH_1):PAGE217_I325@MSTR_DISCRETE.CAP(CHIPS)':
 'A': CDS_PINID='A';
NODE_NAME     C5P43 1
 '@BASEBOARD_FAB2_LIB.BASEBOARD_FAB2(SCH_1):PAGE217_I326@MSTR_DISCRETE.CAP(CHIPS)':
 'A': CDS_PINID='A';
NODE_NAME     C5P38 1
 '@BASEBOARD_FAB2_LIB.BASEBOARD_FAB2(SCH_1):PAGE217_I327@MSTR_DISCRETE.CAP(CHIPS)':
 'A': CDS_PINID='A';
NODE_NAME     C5P39 1
 '@BASEBOARD_FAB2_LIB.BASEBOARD_FAB2(SCH_1):PAGE217_I328@MSTR_DISCRETE.CAP(CHIPS)':
 'A': CDS_PINID='A';
NODE_NAME     C5G20 1
 '@BASEBOARD_FAB2_LIB.BASEBOARD_FAB2(SCH_1):PAGE217_I329@MSTR_DISCRETE.CAP(CHIPS)':
 'A': CDS_PINID='A';
NODE_NAME     L7G2 2
 '@BASEBOARD_FAB2_LIB.BASEBOARD_FAB2(SCH_1):PAGE216_I155@W_HDL.IND-120NH-30-GP(CHIPS)':
 'F': CDS_PINID='F';
NET_NAME
'PVDDQ_DEF'
 '@BASEBOARD_FAB2_LIB.BASEBOARD_FAB2(SCH_1):PVDDQ_DEF':
 C_SIGNAL='@baseboard_fab2_lib.baseboard_fab2(sch_1):pvddq_def';
NODE_NAME     U5D1 EF59
 '@BASEBOARD_FAB2_LIB.BASEBOARD_FAB2(SCH_1):PAGE38_I33@CHPSET_LIB.SKX_EXT_B(CHIPS)':
 'VCCD345'<0>: CDS_PINID='VCCD345(0)';
NODE_NAME     U5D1 EF53
 '@BASEBOARD_FAB2_LIB.BASEBOARD_FAB2(SCH_1):PAGE38_I33@CHPSET_LIB.SKX_EXT_B(CHIPS)':
 'VCCD345'<1>: CDS_PINID='VCCD345(1)';
NODE_NAME     U5D1 EF49
 '@BASEBOARD_FAB2_LIB.BASEBOARD_FAB2(SCH_1):PAGE38_I33@CHPSET_LIB.SKX_EXT_B(CHIPS)':
 'VCCD345'<2>: CDS_PINID='VCCD345(2)';
NODE_NAME     U5D1 EC62
 '@BASEBOARD_FAB2_LIB.BASEBOARD_FAB2(SCH_1):PAGE38_I33@CHPSET_LIB.SKX_EXT_B(CHIPS)':
 'VCCD345'<3>: CDS_PINID='VCCD345(3)';
NODE_NAME     U5D1 EC60
 '@BASEBOARD_FAB2_LIB.BASEBOARD_FAB2(SCH_1):PAGE38_I33@CHPSET_LIB.SKX_EXT_B(CHIPS)':
 'VCCD345'<4>: CDS_PINID='VCCD345(4)';
NODE_NAME     U5D1 EC58
 '@BASEBOARD_FAB2_LIB.BASEBOARD_FAB2(SCH_1):PAGE38_I33@CHPSET_LIB.SKX_EXT_B(CHIPS)':
 'VCCD345'<5>: CDS_PINID='VCCD345(5)';
NODE_NAME     U5D1 EC56
 '@BASEBOARD_FAB2_LIB.BASEBOARD_FAB2(SCH_1):PAGE38_I33@CHPSET_LIB.SKX_EXT_B(CHIPS)':
 'VCCD345'<6>: CDS_PINID='VCCD345(6)';
NODE_NAME     U5D1 EC54
 '@BASEBOARD_FAB2_LIB.BASEBOARD_FAB2(SCH_1):PAGE38_I33@CHPSET_LIB.SKX_EXT_B(CHIPS)':
 'VCCD345'<7>: CDS_PINID='VCCD345(7)';
NODE_NAME     U5D1 EC52
 '@BASEBOARD_FAB2_LIB.BASEBOARD_FAB2(SCH_1):PAGE38_I33@CHPSET_LIB.SKX_EXT_B(CHIPS)':
 'VCCD345'<8>: CDS_PINID='VCCD345(8)';
NODE_NAME     U5D1 EC50
 '@BASEBOARD_FAB2_LIB.BASEBOARD_FAB2(SCH_1):PAGE38_I33@CHPSET_LIB.SKX_EXT_B(CHIPS)':
 'VCCD345'<9>: CDS_PINID='VCCD345(9)';
NODE_NAME     U5D1 EC48
 '@BASEBOARD_FAB2_LIB.BASEBOARD_FAB2(SCH_1):PAGE38_I33@CHPSET_LIB.SKX_EXT_B(CHIPS)':
 'VCCD345'<10>: CDS_PINID='VCCD345(10)';
NODE_NAME     U5D1 EC46
 '@BASEBOARD_FAB2_LIB.BASEBOARD_FAB2(SCH_1):PAGE38_I33@CHPSET_LIB.SKX_EXT_B(CHIPS)':
 'VCCD345'<11>: CDS_PINID='VCCD345(11)';
NODE_NAME     U5D1 DU64
 '@BASEBOARD_FAB2_LIB.BASEBOARD_FAB2(SCH_1):PAGE38_I33@CHPSET_LIB.SKX_EXT_B(CHIPS)':
 'VCCD345'<12>: CDS_PINID='VCCD345(12)';
NODE_NAME     U5D1 DU62
 '@BASEBOARD_FAB2_LIB.BASEBOARD_FAB2(SCH_1):PAGE38_I33@CHPSET_LIB.SKX_EXT_B(CHIPS)':
 'VCCD345'<13>: CDS_PINID='VCCD345(13)';
NODE_NAME     U5D1 DU60
 '@BASEBOARD_FAB2_LIB.BASEBOARD_FAB2(SCH_1):PAGE38_I33@CHPSET_LIB.SKX_EXT_B(CHIPS)':
 'VCCD345'<14>: CDS_PINID='VCCD345(14)';
NODE_NAME     U5D1 DU58
 '@BASEBOARD_FAB2_LIB.BASEBOARD_FAB2(SCH_1):PAGE38_I33@CHPSET_LIB.SKX_EXT_B(CHIPS)':
 'VCCD345'<15>: CDS_PINID='VCCD345(15)';
NODE_NAME     U5D1 DU56
 '@BASEBOARD_FAB2_LIB.BASEBOARD_FAB2(SCH_1):PAGE38_I33@CHPSET_LIB.SKX_EXT_B(CHIPS)':
 'VCCD345'<16>: CDS_PINID='VCCD345(16)';
NODE_NAME     U5D1 DU54
 '@BASEBOARD_FAB2_LIB.BASEBOARD_FAB2(SCH_1):PAGE38_I33@CHPSET_LIB.SKX_EXT_B(CHIPS)':
 'VCCD345'<17>: CDS_PINID='VCCD345(17)';
NODE_NAME     U5D1 DU52
 '@BASEBOARD_FAB2_LIB.BASEBOARD_FAB2(SCH_1):PAGE38_I33@CHPSET_LIB.SKX_EXT_B(CHIPS)':
 'VCCD345'<18>: CDS_PINID='VCCD345(18)';
NODE_NAME     U5D1 DU50
 '@BASEBOARD_FAB2_LIB.BASEBOARD_FAB2(SCH_1):PAGE38_I33@CHPSET_LIB.SKX_EXT_B(CHIPS)':
 'VCCD345'<19>: CDS_PINID='VCCD345(19)';
NODE_NAME     U5D1 DU48
 '@BASEBOARD_FAB2_LIB.BASEBOARD_FAB2(SCH_1):PAGE38_I33@CHPSET_LIB.SKX_EXT_B(CHIPS)':
 'VCCD345'<20>: CDS_PINID='VCCD345(20)';
NODE_NAME     U5D1 DU46
 '@BASEBOARD_FAB2_LIB.BASEBOARD_FAB2(SCH_1):PAGE38_I33@CHPSET_LIB.SKX_EXT_B(CHIPS)':
 'VCCD345'<21>: CDS_PINID='VCCD345(21)';
NODE_NAME     U5D1 DL62
 '@BASEBOARD_FAB2_LIB.BASEBOARD_FAB2(SCH_1):PAGE38_I33@CHPSET_LIB.SKX_EXT_B(CHIPS)':
 'VCCD345'<22>: CDS_PINID='VCCD345(22)';
NODE_NAME     U5D1 DL60
 '@BASEBOARD_FAB2_LIB.BASEBOARD_FAB2(SCH_1):PAGE38_I33@CHPSET_LIB.SKX_EXT_B(CHIPS)':
 'VCCD345'<23>: CDS_PINID='VCCD345(23)';
NODE_NAME     U5D1 DL58
 '@BASEBOARD_FAB2_LIB.BASEBOARD_FAB2(SCH_1):PAGE38_I33@CHPSET_LIB.SKX_EXT_B(CHIPS)':
 'VCCD345'<24>: CDS_PINID='VCCD345(24)';
NODE_NAME     U5D1 DL56
 '@BASEBOARD_FAB2_LIB.BASEBOARD_FAB2(SCH_1):PAGE38_I33@CHPSET_LIB.SKX_EXT_B(CHIPS)':
 'VCCD345'<25>: CDS_PINID='VCCD345(25)';
NODE_NAME     U5D1 DL54
 '@BASEBOARD_FAB2_LIB.BASEBOARD_FAB2(SCH_1):PAGE38_I33@CHPSET_LIB.SKX_EXT_B(CHIPS)':
 'VCCD345'<26>: CDS_PINID='VCCD345(26)';
NODE_NAME     U5D1 DL52
 '@BASEBOARD_FAB2_LIB.BASEBOARD_FAB2(SCH_1):PAGE38_I33@CHPSET_LIB.SKX_EXT_B(CHIPS)':
 'VCCD345'<27>: CDS_PINID='VCCD345(27)';
NODE_NAME     U5D1 DL50
 '@BASEBOARD_FAB2_LIB.BASEBOARD_FAB2(SCH_1):PAGE38_I33@CHPSET_LIB.SKX_EXT_B(CHIPS)':
 'VCCD345'<28>: CDS_PINID='VCCD345(28)';
NODE_NAME     U5D1 DL48
 '@BASEBOARD_FAB2_LIB.BASEBOARD_FAB2(SCH_1):PAGE38_I33@CHPSET_LIB.SKX_EXT_B(CHIPS)':
 'VCCD345'<29>: CDS_PINID='VCCD345(29)';
NODE_NAME     U5D1 DL46
 '@BASEBOARD_FAB2_LIB.BASEBOARD_FAB2(SCH_1):PAGE38_I33@CHPSET_LIB.SKX_EXT_B(CHIPS)':
 'VCCD345'<30>: CDS_PINID='VCCD345(30)';
NODE_NAME     U5D1 DJ64
 '@BASEBOARD_FAB2_LIB.BASEBOARD_FAB2(SCH_1):PAGE38_I33@CHPSET_LIB.SKX_EXT_B(CHIPS)':
 'VCCD345'<31>: CDS_PINID='VCCD345(31)';
NODE_NAME     U5D1 DH63
 '@BASEBOARD_FAB2_LIB.BASEBOARD_FAB2(SCH_1):PAGE38_I33@CHPSET_LIB.SKX_EXT_B(CHIPS)':
 'VCCD345'<32>: CDS_PINID='VCCD345(32)';
NODE_NAME     U5D1 DH61
 '@BASEBOARD_FAB2_LIB.BASEBOARD_FAB2(SCH_1):PAGE38_I33@CHPSET_LIB.SKX_EXT_B(CHIPS)':
 'VCCD345'<33>: CDS_PINID='VCCD345(33)';
NODE_NAME     U5D1 DH59
 '@BASEBOARD_FAB2_LIB.BASEBOARD_FAB2(SCH_1):PAGE38_I33@CHPSET_LIB.SKX_EXT_B(CHIPS)':
 'VCCD345'<34>: CDS_PINID='VCCD345(34)';
NODE_NAME     U5D1 DH57
 '@BASEBOARD_FAB2_LIB.BASEBOARD_FAB2(SCH_1):PAGE38_I33@CHPSET_LIB.SKX_EXT_B(CHIPS)':
 'VCCD345'<35>: CDS_PINID='VCCD345(35)';
NODE_NAME     U5D1 DH55
 '@BASEBOARD_FAB2_LIB.BASEBOARD_FAB2(SCH_1):PAGE38_I33@CHPSET_LIB.SKX_EXT_B(CHIPS)':
 'VCCD345'<36>: CDS_PINID='VCCD345(36)';
NODE_NAME     U5D1 DH53
 '@BASEBOARD_FAB2_LIB.BASEBOARD_FAB2(SCH_1):PAGE38_I33@CHPSET_LIB.SKX_EXT_B(CHIPS)':
 'VCCD345'<37>: CDS_PINID='VCCD345(37)';
NODE_NAME     U5D1 DH51
 '@BASEBOARD_FAB2_LIB.BASEBOARD_FAB2(SCH_1):PAGE38_I33@CHPSET_LIB.SKX_EXT_B(CHIPS)':
 'VCCD345'<38>: CDS_PINID='VCCD345(38)';
NODE_NAME     U5D1 DH49
 '@BASEBOARD_FAB2_LIB.BASEBOARD_FAB2(SCH_1):PAGE38_I33@CHPSET_LIB.SKX_EXT_B(CHIPS)':
 'VCCD345'<39>: CDS_PINID='VCCD345(39)';
NODE_NAME     U5D1 DH47
 '@BASEBOARD_FAB2_LIB.BASEBOARD_FAB2(SCH_1):PAGE38_I33@CHPSET_LIB.SKX_EXT_B(CHIPS)':
 'VCCD345'<40>: CDS_PINID='VCCD345(40)';
NODE_NAME     U5D1 DH45
 '@BASEBOARD_FAB2_LIB.BASEBOARD_FAB2(SCH_1):PAGE38_I33@CHPSET_LIB.SKX_EXT_B(CHIPS)':
 'VCCD345'<41>: CDS_PINID='VCCD345(41)';
NODE_NAME     U5D1 DD45
 '@BASEBOARD_FAB2_LIB.BASEBOARD_FAB2(SCH_1):PAGE38_I33@CHPSET_LIB.SKX_EXT_B(CHIPS)':
 'VCCD345'<42>: CDS_PINID='VCCD345(42)';
NODE_NAME     U5D1 DB63
 '@BASEBOARD_FAB2_LIB.BASEBOARD_FAB2(SCH_1):PAGE38_I33@CHPSET_LIB.SKX_EXT_B(CHIPS)':
 'VCCD345'<43>: CDS_PINID='VCCD345(43)';
NODE_NAME     U5D1 DB61
 '@BASEBOARD_FAB2_LIB.BASEBOARD_FAB2(SCH_1):PAGE38_I33@CHPSET_LIB.SKX_EXT_B(CHIPS)':
 'VCCD345'<44>: CDS_PINID='VCCD345(44)';
NODE_NAME     U5D1 DB59
 '@BASEBOARD_FAB2_LIB.BASEBOARD_FAB2(SCH_1):PAGE38_I33@CHPSET_LIB.SKX_EXT_B(CHIPS)':
 'VCCD345'<45>: CDS_PINID='VCCD345(45)';
NODE_NAME     U5D1 DB57
 '@BASEBOARD_FAB2_LIB.BASEBOARD_FAB2(SCH_1):PAGE38_I33@CHPSET_LIB.SKX_EXT_B(CHIPS)':
 'VCCD345'<46>: CDS_PINID='VCCD345(46)';
NODE_NAME     U5D1 DB55
 '@BASEBOARD_FAB2_LIB.BASEBOARD_FAB2(SCH_1):PAGE38_I33@CHPSET_LIB.SKX_EXT_B(CHIPS)':
 'VCCD345'<47>: CDS_PINID='VCCD345(47)';
NODE_NAME     U5D1 DB53
 '@BASEBOARD_FAB2_LIB.BASEBOARD_FAB2(SCH_1):PAGE38_I33@CHPSET_LIB.SKX_EXT_B(CHIPS)':
 'VCCD345'<48>: CDS_PINID='VCCD345(48)';
NODE_NAME     U5D1 EF45
 '@BASEBOARD_FAB2_LIB.BASEBOARD_FAB2(SCH_1):PAGE38_I33@CHPSET_LIB.SKX_EXT_B(CHIPS)':
 'VCCD345'<49>: CDS_PINID='VCCD345(49)';
NODE_NAME     U5D1 EE44
 '@BASEBOARD_FAB2_LIB.BASEBOARD_FAB2(SCH_1):PAGE38_I33@CHPSET_LIB.SKX_EXT_B(CHIPS)':
 'VCCD345'<50>: CDS_PINID='VCCD345(50)';
NODE_NAME     J4B1 236
 '@BASEBOARD_FAB2_LIB.BASEBOARD_FAB2(SCH_1):PAGE49_I169@MSTR_SCONN.SCONN288_H44441004(CHIPS)':
 'VDD'<0>: CDS_PINID='VDD(0)';
NODE_NAME     J4B1 233
 '@BASEBOARD_FAB2_LIB.BASEBOARD_FAB2(SCH_1):PAGE49_I169@MSTR_SCONN.SCONN288_H44441004(CHIPS)':
 'VDD'<1>: CDS_PINID='VDD(1)';
NODE_NAME     J4B1 231
 '@BASEBOARD_FAB2_LIB.BASEBOARD_FAB2(SCH_1):PAGE49_I169@MSTR_SCONN.SCONN288_H44441004(CHIPS)':
 'VDD'<2>: CDS_PINID='VDD(2)';
NODE_NAME     J4B1 229
 '@BASEBOARD_FAB2_LIB.BASEBOARD_FAB2(SCH_1):PAGE49_I169@MSTR_SCONN.SCONN288_H44441004(CHIPS)':
 'VDD'<3>: CDS_PINID='VDD(3)';
NODE_NAME     J4B1 226
 '@BASEBOARD_FAB2_LIB.BASEBOARD_FAB2(SCH_1):PAGE49_I169@MSTR_SCONN.SCONN288_H44441004(CHIPS)':
 'VDD'<4>: CDS_PINID='VDD(4)';
NODE_NAME     J4B1 223
 '@BASEBOARD_FAB2_LIB.BASEBOARD_FAB2(SCH_1):PAGE49_I169@MSTR_SCONN.SCONN288_H44441004(CHIPS)':
 'VDD'<5>: CDS_PINID='VDD(5)';
NODE_NAME     J4B1 220
 '@BASEBOARD_FAB2_LIB.BASEBOARD_FAB2(SCH_1):PAGE49_I169@MSTR_SCONN.SCONN288_H44441004(CHIPS)':
 'VDD'<6>: CDS_PINID='VDD(6)';
NODE_NAME     J4B1 217
 '@BASEBOARD_FAB2_LIB.BASEBOARD_FAB2(SCH_1):PAGE49_I169@MSTR_SCONN.SCONN288_H44441004(CHIPS)':
 'VDD'<7>: CDS_PINID='VDD(7)';
NODE_NAME     J4B1 215
 '@BASEBOARD_FAB2_LIB.BASEBOARD_FAB2(SCH_1):PAGE49_I169@MSTR_SCONN.SCONN288_H44441004(CHIPS)':
 'VDD'<8>: CDS_PINID='VDD(8)';
NODE_NAME     J4B1 212
 '@BASEBOARD_FAB2_LIB.BASEBOARD_FAB2(SCH_1):PAGE49_I169@MSTR_SCONN.SCONN288_H44441004(CHIPS)':
 'VDD'<9>: CDS_PINID='VDD(9)';
NODE_NAME     J4B1 209
 '@BASEBOARD_FAB2_LIB.BASEBOARD_FAB2(SCH_1):PAGE49_I169@MSTR_SCONN.SCONN288_H44441004(CHIPS)':
 'VDD'<10>: CDS_PINID='VDD(10)';
NODE_NAME     J4B1 206
 '@BASEBOARD_FAB2_LIB.BASEBOARD_FAB2(SCH_1):PAGE49_I169@MSTR_SCONN.SCONN288_H44441004(CHIPS)':
 'VDD'<11>: CDS_PINID='VDD(11)';
NODE_NAME     J4B1 204
 '@BASEBOARD_FAB2_LIB.BASEBOARD_FAB2(SCH_1):PAGE49_I169@MSTR_SCONN.SCONN288_H44441004(CHIPS)':
 'VDD'<12>: CDS_PINID='VDD(12)';
NODE_NAME     J4B1 92
 '@BASEBOARD_FAB2_LIB.BASEBOARD_FAB2(SCH_1):PAGE49_I169@MSTR_SCONN.SCONN288_H44441004(CHIPS)':
 'VDD'<13>: CDS_PINID='VDD(13)';
NODE_NAME     J4B1 90
 '@BASEBOARD_FAB2_LIB.BASEBOARD_FAB2(SCH_1):PAGE49_I169@MSTR_SCONN.SCONN288_H44441004(CHIPS)':
 'VDD'<14>: CDS_PINID='VDD(14)';
NODE_NAME     J4B1 88
 '@BASEBOARD_FAB2_LIB.BASEBOARD_FAB2(SCH_1):PAGE49_I169@MSTR_SCONN.SCONN288_H44441004(CHIPS)':
 'VDD'<15>: CDS_PINID='VDD(15)';
NODE_NAME     J4B1 85
 '@BASEBOARD_FAB2_LIB.BASEBOARD_FAB2(SCH_1):PAGE49_I169@MSTR_SCONN.SCONN288_H44441004(CHIPS)':
 'VDD'<16>: CDS_PINID='VDD(16)';
NODE_NAME     J4B1 83
 '@BASEBOARD_FAB2_LIB.BASEBOARD_FAB2(SCH_1):PAGE49_I169@MSTR_SCONN.SCONN288_H44441004(CHIPS)':
 'VDD'<17>: CDS_PINID='VDD(17)';
NODE_NAME     J4B1 80
 '@BASEBOARD_FAB2_LIB.BASEBOARD_FAB2(SCH_1):PAGE49_I169@MSTR_SCONN.SCONN288_H44441004(CHIPS)':
 'VDD'<18>: CDS_PINID='VDD(18)';
NODE_NAME     J4B1 76
 '@BASEBOARD_FAB2_LIB.BASEBOARD_FAB2(SCH_1):PAGE49_I169@MSTR_SCONN.SCONN288_H44441004(CHIPS)':
 'VDD'<19>: CDS_PINID='VDD(19)';
NODE_NAME     J4B1 73
 '@BASEBOARD_FAB2_LIB.BASEBOARD_FAB2(SCH_1):PAGE49_I169@MSTR_SCONN.SCONN288_H44441004(CHIPS)':
 'VDD'<20>: CDS_PINID='VDD(20)';
NODE_NAME     J4B1 70
 '@BASEBOARD_FAB2_LIB.BASEBOARD_FAB2(SCH_1):PAGE49_I169@MSTR_SCONN.SCONN288_H44441004(CHIPS)':
 'VDD'<21>: CDS_PINID='VDD(21)';
NODE_NAME     J4B1 67
 '@BASEBOARD_FAB2_LIB.BASEBOARD_FAB2(SCH_1):PAGE49_I169@MSTR_SCONN.SCONN288_H44441004(CHIPS)':
 'VDD'<22>: CDS_PINID='VDD(22)';
NODE_NAME     J4B1 64
 '@BASEBOARD_FAB2_LIB.BASEBOARD_FAB2(SCH_1):PAGE49_I169@MSTR_SCONN.SCONN288_H44441004(CHIPS)':
 'VDD'<23>: CDS_PINID='VDD(23)';
NODE_NAME     J4B1 61
 '@BASEBOARD_FAB2_LIB.BASEBOARD_FAB2(SCH_1):PAGE49_I169@MSTR_SCONN.SCONN288_H44441004(CHIPS)':
 'VDD'<24>: CDS_PINID='VDD(24)';
NODE_NAME     J4B1 59
 '@BASEBOARD_FAB2_LIB.BASEBOARD_FAB2(SCH_1):PAGE49_I169@MSTR_SCONN.SCONN288_H44441004(CHIPS)':
 'VDD'<25>: CDS_PINID='VDD(25)';
NODE_NAME     J6M1 236
 '@BASEBOARD_FAB2_LIB.BASEBOARD_FAB2(SCH_1):PAGE50_I50@MSTR_SCONN.SCONN288_H44441003(CHIPS)':
 'VDD'<0>: CDS_PINID='VDD(0)';
NODE_NAME     J6M1 233
 '@BASEBOARD_FAB2_LIB.BASEBOARD_FAB2(SCH_1):PAGE50_I50@MSTR_SCONN.SCONN288_H44441003(CHIPS)':
 'VDD'<1>: CDS_PINID='VDD(1)';
NODE_NAME     J6M1 231
 '@BASEBOARD_FAB2_LIB.BASEBOARD_FAB2(SCH_1):PAGE50_I50@MSTR_SCONN.SCONN288_H44441003(CHIPS)':
 'VDD'<2>: CDS_PINID='VDD(2)';
NODE_NAME     J6M1 229
 '@BASEBOARD_FAB2_LIB.BASEBOARD_FAB2(SCH_1):PAGE50_I50@MSTR_SCONN.SCONN288_H44441003(CHIPS)':
 'VDD'<3>: CDS_PINID='VDD(3)';
NODE_NAME     J6M1 226
 '@BASEBOARD_FAB2_LIB.BASEBOARD_FAB2(SCH_1):PAGE50_I50@MSTR_SCONN.SCONN288_H44441003(CHIPS)':
 'VDD'<4>: CDS_PINID='VDD(4)';
NODE_NAME     J6M1 223
 '@BASEBOARD_FAB2_LIB.BASEBOARD_FAB2(SCH_1):PAGE50_I50@MSTR_SCONN.SCONN288_H44441003(CHIPS)':
 'VDD'<5>: CDS_PINID='VDD(5)';
NODE_NAME     J6M1 220
 '@BASEBOARD_FAB2_LIB.BASEBOARD_FAB2(SCH_1):PAGE50_I50@MSTR_SCONN.SCONN288_H44441003(CHIPS)':
 'VDD'<6>: CDS_PINID='VDD(6)';
NODE_NAME     J6M1 217
 '@BASEBOARD_FAB2_LIB.BASEBOARD_FAB2(SCH_1):PAGE50_I50@MSTR_SCONN.SCONN288_H44441003(CHIPS)':
 'VDD'<7>: CDS_PINID='VDD(7)';
NODE_NAME     J6M1 215
 '@BASEBOARD_FAB2_LIB.BASEBOARD_FAB2(SCH_1):PAGE50_I50@MSTR_SCONN.SCONN288_H44441003(CHIPS)':
 'VDD'<8>: CDS_PINID='VDD(8)';
NODE_NAME     J6M1 212
 '@BASEBOARD_FAB2_LIB.BASEBOARD_FAB2(SCH_1):PAGE50_I50@MSTR_SCONN.SCONN288_H44441003(CHIPS)':
 'VDD'<9>: CDS_PINID='VDD(9)';
NODE_NAME     J6M1 209
 '@BASEBOARD_FAB2_LIB.BASEBOARD_FAB2(SCH_1):PAGE50_I50@MSTR_SCONN.SCONN288_H44441003(CHIPS)':
 'VDD'<10>: CDS_PINID='VDD(10)';
NODE_NAME     J6M1 206
 '@BASEBOARD_FAB2_LIB.BASEBOARD_FAB2(SCH_1):PAGE50_I50@MSTR_SCONN.SCONN288_H44441003(CHIPS)':
 'VDD'<11>: CDS_PINID='VDD(11)';
NODE_NAME     J6M1 204
 '@BASEBOARD_FAB2_LIB.BASEBOARD_FAB2(SCH_1):PAGE50_I50@MSTR_SCONN.SCONN288_H44441003(CHIPS)':
 'VDD'<12>: CDS_PINID='VDD(12)';
NODE_NAME     J6M1 92
 '@BASEBOARD_FAB2_LIB.BASEBOARD_FAB2(SCH_1):PAGE50_I50@MSTR_SCONN.SCONN288_H44441003(CHIPS)':
 'VDD'<13>: CDS_PINID='VDD(13)';
NODE_NAME     J6M1 90
 '@BASEBOARD_FAB2_LIB.BASEBOARD_FAB2(SCH_1):PAGE50_I50@MSTR_SCONN.SCONN288_H44441003(CHIPS)':
 'VDD'<14>: CDS_PINID='VDD(14)';
NODE_NAME     J6M1 88
 '@BASEBOARD_FAB2_LIB.BASEBOARD_FAB2(SCH_1):PAGE50_I50@MSTR_SCONN.SCONN288_H44441003(CHIPS)':
 'VDD'<15>: CDS_PINID='VDD(15)';
NODE_NAME     J6M1 85
 '@BASEBOARD_FAB2_LIB.BASEBOARD_FAB2(SCH_1):PAGE50_I50@MSTR_SCONN.SCONN288_H44441003(CHIPS)':
 'VDD'<16>: CDS_PINID='VDD(16)';
NODE_NAME     J6M1 83
 '@BASEBOARD_FAB2_LIB.BASEBOARD_FAB2(SCH_1):PAGE50_I50@MSTR_SCONN.SCONN288_H44441003(CHIPS)':
 'VDD'<17>: CDS_PINID='VDD(17)';
NODE_NAME     J6M1 80
 '@BASEBOARD_FAB2_LIB.BASEBOARD_FAB2(SCH_1):PAGE50_I50@MSTR_SCONN.SCONN288_H44441003(CHIPS)':
 'VDD'<18>: CDS_PINID='VDD(18)';
NODE_NAME     J6M1 76
 '@BASEBOARD_FAB2_LIB.BASEBOARD_FAB2(SCH_1):PAGE50_I50@MSTR_SCONN.SCONN288_H44441003(CHIPS)':
 'VDD'<19>: CDS_PINID='VDD(19)';
NODE_NAME     J6M1 73
 '@BASEBOARD_FAB2_LIB.BASEBOARD_FAB2(SCH_1):PAGE50_I50@MSTR_SCONN.SCONN288_H44441003(CHIPS)':
 'VDD'<20>: CDS_PINID='VDD(20)';
NODE_NAME     J6M1 70
 '@BASEBOARD_FAB2_LIB.BASEBOARD_FAB2(SCH_1):PAGE50_I50@MSTR_SCONN.SCONN288_H44441003(CHIPS)':
 'VDD'<21>: CDS_PINID='VDD(21)';
NODE_NAME     J6M1 67
 '@BASEBOARD_FAB2_LIB.BASEBOARD_FAB2(SCH_1):PAGE50_I50@MSTR_SCONN.SCONN288_H44441003(CHIPS)':
 'VDD'<22>: CDS_PINID='VDD(22)';
NODE_NAME     J6M1 64
 '@BASEBOARD_FAB2_LIB.BASEBOARD_FAB2(SCH_1):PAGE50_I50@MSTR_SCONN.SCONN288_H44441003(CHIPS)':
 'VDD'<23>: CDS_PINID='VDD(23)';
NODE_NAME     J6M1 61
 '@BASEBOARD_FAB2_LIB.BASEBOARD_FAB2(SCH_1):PAGE50_I50@MSTR_SCONN.SCONN288_H44441003(CHIPS)':
 'VDD'<24>: CDS_PINID='VDD(24)';
NODE_NAME     J6M1 59
 '@BASEBOARD_FAB2_LIB.BASEBOARD_FAB2(SCH_1):PAGE50_I50@MSTR_SCONN.SCONN288_H44441003(CHIPS)':
 'VDD'<25>: CDS_PINID='VDD(25)';
NODE_NAME     J4A2 236
 '@BASEBOARD_FAB2_LIB.BASEBOARD_FAB2(SCH_1):PAGE51_I167@MSTR_SCONN.SCONN288_H44441004(CHIPS)':
 'VDD'<0>: CDS_PINID='VDD(0)';
NODE_NAME     J4A2 233
 '@BASEBOARD_FAB2_LIB.BASEBOARD_FAB2(SCH_1):PAGE51_I167@MSTR_SCONN.SCONN288_H44441004(CHIPS)':
 'VDD'<1>: CDS_PINID='VDD(1)';
NODE_NAME     J4A2 231
 '@BASEBOARD_FAB2_LIB.BASEBOARD_FAB2(SCH_1):PAGE51_I167@MSTR_SCONN.SCONN288_H44441004(CHIPS)':
 'VDD'<2>: CDS_PINID='VDD(2)';
NODE_NAME     J4A2 229
 '@BASEBOARD_FAB2_LIB.BASEBOARD_FAB2(SCH_1):PAGE51_I167@MSTR_SCONN.SCONN288_H44441004(CHIPS)':
 'VDD'<3>: CDS_PINID='VDD(3)';
NODE_NAME     J4A2 226
 '@BASEBOARD_FAB2_LIB.BASEBOARD_FAB2(SCH_1):PAGE51_I167@MSTR_SCONN.SCONN288_H44441004(CHIPS)':
 'VDD'<4>: CDS_PINID='VDD(4)';
NODE_NAME     J4A2 223
 '@BASEBOARD_FAB2_LIB.BASEBOARD_FAB2(SCH_1):PAGE51_I167@MSTR_SCONN.SCONN288_H44441004(CHIPS)':
 'VDD'<5>: CDS_PINID='VDD(5)';
NODE_NAME     J4A2 220
 '@BASEBOARD_FAB2_LIB.BASEBOARD_FAB2(SCH_1):PAGE51_I167@MSTR_SCONN.SCONN288_H44441004(CHIPS)':
 'VDD'<6>: CDS_PINID='VDD(6)';
NODE_NAME     J4A2 217
 '@BASEBOARD_FAB2_LIB.BASEBOARD_FAB2(SCH_1):PAGE51_I167@MSTR_SCONN.SCONN288_H44441004(CHIPS)':
 'VDD'<7>: CDS_PINID='VDD(7)';
NODE_NAME     J4A2 215
 '@BASEBOARD_FAB2_LIB.BASEBOARD_FAB2(SCH_1):PAGE51_I167@MSTR_SCONN.SCONN288_H44441004(CHIPS)':
 'VDD'<8>: CDS_PINID='VDD(8)';
NODE_NAME     J4A2 212
 '@BASEBOARD_FAB2_LIB.BASEBOARD_FAB2(SCH_1):PAGE51_I167@MSTR_SCONN.SCONN288_H44441004(CHIPS)':
 'VDD'<9>: CDS_PINID='VDD(9)';
NODE_NAME     J4A2 209
 '@BASEBOARD_FAB2_LIB.BASEBOARD_FAB2(SCH_1):PAGE51_I167@MSTR_SCONN.SCONN288_H44441004(CHIPS)':
 'VDD'<10>: CDS_PINID='VDD(10)';
NODE_NAME     J4A2 206
 '@BASEBOARD_FAB2_LIB.BASEBOARD_FAB2(SCH_1):PAGE51_I167@MSTR_SCONN.SCONN288_H44441004(CHIPS)':
 'VDD'<11>: CDS_PINID='VDD(11)';
NODE_NAME     J4A2 204
 '@BASEBOARD_FAB2_LIB.BASEBOARD_FAB2(SCH_1):PAGE51_I167@MSTR_SCONN.SCONN288_H44441004(CHIPS)':
 'VDD'<12>: CDS_PINID='VDD(12)';
NODE_NAME     J4A2 92
 '@BASEBOARD_FAB2_LIB.BASEBOARD_FAB2(SCH_1):PAGE51_I167@MSTR_SCONN.SCONN288_H44441004(CHIPS)':
 'VDD'<13>: CDS_PINID='VDD(13)';
NODE_NAME     J4A2 90
 '@BASEBOARD_FAB2_LIB.BASEBOARD_FAB2(SCH_1):PAGE51_I167@MSTR_SCONN.SCONN288_H44441004(CHIPS)':
 'VDD'<14>: CDS_PINID='VDD(14)';
NODE_NAME     J4A2 88
 '@BASEBOARD_FAB2_LIB.BASEBOARD_FAB2(SCH_1):PAGE51_I167@MSTR_SCONN.SCONN288_H44441004(CHIPS)':
 'VDD'<15>: CDS_PINID='VDD(15)';
NODE_NAME     J4A2 85
 '@BASEBOARD_FAB2_LIB.BASEBOARD_FAB2(SCH_1):PAGE51_I167@MSTR_SCONN.SCONN288_H44441004(CHIPS)':
 'VDD'<16>: CDS_PINID='VDD(16)';
NODE_NAME     J4A2 83
 '@BASEBOARD_FAB2_LIB.BASEBOARD_FAB2(SCH_1):PAGE51_I167@MSTR_SCONN.SCONN288_H44441004(CHIPS)':
 'VDD'<17>: CDS_PINID='VDD(17)';
NODE_NAME     J4A2 80
 '@BASEBOARD_FAB2_LIB.BASEBOARD_FAB2(SCH_1):PAGE51_I167@MSTR_SCONN.SCONN288_H44441004(CHIPS)':
 'VDD'<18>: CDS_PINID='VDD(18)';
NODE_NAME     J4A2 76
 '@BASEBOARD_FAB2_LIB.BASEBOARD_FAB2(SCH_1):PAGE51_I167@MSTR_SCONN.SCONN288_H44441004(CHIPS)':
 'VDD'<19>: CDS_PINID='VDD(19)';
NODE_NAME     J4A2 73
 '@BASEBOARD_FAB2_LIB.BASEBOARD_FAB2(SCH_1):PAGE51_I167@MSTR_SCONN.SCONN288_H44441004(CHIPS)':
 'VDD'<20>: CDS_PINID='VDD(20)';
NODE_NAME     J4A2 70
 '@BASEBOARD_FAB2_LIB.BASEBOARD_FAB2(SCH_1):PAGE51_I167@MSTR_SCONN.SCONN288_H44441004(CHIPS)':
 'VDD'<21>: CDS_PINID='VDD(21)';
NODE_NAME     J4A2 67
 '@BASEBOARD_FAB2_LIB.BASEBOARD_FAB2(SCH_1):PAGE51_I167@MSTR_SCONN.SCONN288_H44441004(CHIPS)':
 'VDD'<22>: CDS_PINID='VDD(22)';
NODE_NAME     J4A2 64
 '@BASEBOARD_FAB2_LIB.BASEBOARD_FAB2(SCH_1):PAGE51_I167@MSTR_SCONN.SCONN288_H44441004(CHIPS)':
 'VDD'<23>: CDS_PINID='VDD(23)';
NODE_NAME     J4A2 61
 '@BASEBOARD_FAB2_LIB.BASEBOARD_FAB2(SCH_1):PAGE51_I167@MSTR_SCONN.SCONN288_H44441004(CHIPS)':
 'VDD'<24>: CDS_PINID='VDD(24)';
NODE_NAME     J4A2 59
 '@BASEBOARD_FAB2_LIB.BASEBOARD_FAB2(SCH_1):PAGE51_I167@MSTR_SCONN.SCONN288_H44441004(CHIPS)':
 'VDD'<25>: CDS_PINID='VDD(25)';
NODE_NAME     J6L2 236
 '@BASEBOARD_FAB2_LIB.BASEBOARD_FAB2(SCH_1):PAGE52_I55@MSTR_SCONN.SCONN288_H44441003(CHIPS)':
 'VDD'<0>: CDS_PINID='VDD(0)';
NODE_NAME     J6L2 233
 '@BASEBOARD_FAB2_LIB.BASEBOARD_FAB2(SCH_1):PAGE52_I55@MSTR_SCONN.SCONN288_H44441003(CHIPS)':
 'VDD'<1>: CDS_PINID='VDD(1)';
NODE_NAME     J6L2 231
 '@BASEBOARD_FAB2_LIB.BASEBOARD_FAB2(SCH_1):PAGE52_I55@MSTR_SCONN.SCONN288_H44441003(CHIPS)':
 'VDD'<2>: CDS_PINID='VDD(2)';
NODE_NAME     J6L2 229
 '@BASEBOARD_FAB2_LIB.BASEBOARD_FAB2(SCH_1):PAGE52_I55@MSTR_SCONN.SCONN288_H44441003(CHIPS)':
 'VDD'<3>: CDS_PINID='VDD(3)';
NODE_NAME     J6L2 226
 '@BASEBOARD_FAB2_LIB.BASEBOARD_FAB2(SCH_1):PAGE52_I55@MSTR_SCONN.SCONN288_H44441003(CHIPS)':
 'VDD'<4>: CDS_PINID='VDD(4)';
NODE_NAME     J6L2 223
 '@BASEBOARD_FAB2_LIB.BASEBOARD_FAB2(SCH_1):PAGE52_I55@MSTR_SCONN.SCONN288_H44441003(CHIPS)':
 'VDD'<5>: CDS_PINID='VDD(5)';
NODE_NAME     J6L2 220
 '@BASEBOARD_FAB2_LIB.BASEBOARD_FAB2(SCH_1):PAGE52_I55@MSTR_SCONN.SCONN288_H44441003(CHIPS)':
 'VDD'<6>: CDS_PINID='VDD(6)';
NODE_NAME     J6L2 217
 '@BASEBOARD_FAB2_LIB.BASEBOARD_FAB2(SCH_1):PAGE52_I55@MSTR_SCONN.SCONN288_H44441003(CHIPS)':
 'VDD'<7>: CDS_PINID='VDD(7)';
NODE_NAME     J6L2 215
 '@BASEBOARD_FAB2_LIB.BASEBOARD_FAB2(SCH_1):PAGE52_I55@MSTR_SCONN.SCONN288_H44441003(CHIPS)':
 'VDD'<8>: CDS_PINID='VDD(8)';
NODE_NAME     J6L2 212
 '@BASEBOARD_FAB2_LIB.BASEBOARD_FAB2(SCH_1):PAGE52_I55@MSTR_SCONN.SCONN288_H44441003(CHIPS)':
 'VDD'<9>: CDS_PINID='VDD(9)';
NODE_NAME     J6L2 209
 '@BASEBOARD_FAB2_LIB.BASEBOARD_FAB2(SCH_1):PAGE52_I55@MSTR_SCONN.SCONN288_H44441003(CHIPS)':
 'VDD'<10>: CDS_PINID='VDD(10)';
NODE_NAME     J6L2 206
 '@BASEBOARD_FAB2_LIB.BASEBOARD_FAB2(SCH_1):PAGE52_I55@MSTR_SCONN.SCONN288_H44441003(CHIPS)':
 'VDD'<11>: CDS_PINID='VDD(11)';
NODE_NAME     J6L2 204
 '@BASEBOARD_FAB2_LIB.BASEBOARD_FAB2(SCH_1):PAGE52_I55@MSTR_SCONN.SCONN288_H44441003(CHIPS)':
 'VDD'<12>: CDS_PINID='VDD(12)';
NODE_NAME     J6L2 92
 '@BASEBOARD_FAB2_LIB.BASEBOARD_FAB2(SCH_1):PAGE52_I55@MSTR_SCONN.SCONN288_H44441003(CHIPS)':
 'VDD'<13>: CDS_PINID='VDD(13)';
NODE_NAME     J6L2 90
 '@BASEBOARD_FAB2_LIB.BASEBOARD_FAB2(SCH_1):PAGE52_I55@MSTR_SCONN.SCONN288_H44441003(CHIPS)':
 'VDD'<14>: CDS_PINID='VDD(14)';
NODE_NAME     J6L2 88
 '@BASEBOARD_FAB2_LIB.BASEBOARD_FAB2(SCH_1):PAGE52_I55@MSTR_SCONN.SCONN288_H44441003(CHIPS)':
 'VDD'<15>: CDS_PINID='VDD(15)';
NODE_NAME     J6L2 85
 '@BASEBOARD_FAB2_LIB.BASEBOARD_FAB2(SCH_1):PAGE52_I55@MSTR_SCONN.SCONN288_H44441003(CHIPS)':
 'VDD'<16>: CDS_PINID='VDD(16)';
NODE_NAME     J6L2 83
 '@BASEBOARD_FAB2_LIB.BASEBOARD_FAB2(SCH_1):PAGE52_I55@MSTR_SCONN.SCONN288_H44441003(CHIPS)':
 'VDD'<17>: CDS_PINID='VDD(17)';
NODE_NAME     J6L2 80
 '@BASEBOARD_FAB2_LIB.BASEBOARD_FAB2(SCH_1):PAGE52_I55@MSTR_SCONN.SCONN288_H44441003(CHIPS)':
 'VDD'<18>: CDS_PINID='VDD(18)';
NODE_NAME     J6L2 76
 '@BASEBOARD_FAB2_LIB.BASEBOARD_FAB2(SCH_1):PAGE52_I55@MSTR_SCONN.SCONN288_H44441003(CHIPS)':
 'VDD'<19>: CDS_PINID='VDD(19)';
NODE_NAME     J6L2 73
 '@BASEBOARD_FAB2_LIB.BASEBOARD_FAB2(SCH_1):PAGE52_I55@MSTR_SCONN.SCONN288_H44441003(CHIPS)':
 'VDD'<20>: CDS_PINID='VDD(20)';
NODE_NAME     J6L2 70
 '@BASEBOARD_FAB2_LIB.BASEBOARD_FAB2(SCH_1):PAGE52_I55@MSTR_SCONN.SCONN288_H44441003(CHIPS)':
 'VDD'<21>: CDS_PINID='VDD(21)';
NODE_NAME     J6L2 67
 '@BASEBOARD_FAB2_LIB.BASEBOARD_FAB2(SCH_1):PAGE52_I55@MSTR_SCONN.SCONN288_H44441003(CHIPS)':
 'VDD'<22>: CDS_PINID='VDD(22)';
NODE_NAME     J6L2 64
 '@BASEBOARD_FAB2_LIB.BASEBOARD_FAB2(SCH_1):PAGE52_I55@MSTR_SCONN.SCONN288_H44441003(CHIPS)':
 'VDD'<23>: CDS_PINID='VDD(23)';
NODE_NAME     J6L2 61
 '@BASEBOARD_FAB2_LIB.BASEBOARD_FAB2(SCH_1):PAGE52_I55@MSTR_SCONN.SCONN288_H44441003(CHIPS)':
 'VDD'<24>: CDS_PINID='VDD(24)';
NODE_NAME     J6L2 59
 '@BASEBOARD_FAB2_LIB.BASEBOARD_FAB2(SCH_1):PAGE52_I55@MSTR_SCONN.SCONN288_H44441003(CHIPS)':
 'VDD'<25>: CDS_PINID='VDD(25)';
NODE_NAME     J4A1 236
 '@BASEBOARD_FAB2_LIB.BASEBOARD_FAB2(SCH_1):PAGE53_I171@MSTR_SCONN.SCONN288_H44441004(CHIPS)':
 'VDD'<0>: CDS_PINID='VDD(0)';
NODE_NAME     J4A1 233
 '@BASEBOARD_FAB2_LIB.BASEBOARD_FAB2(SCH_1):PAGE53_I171@MSTR_SCONN.SCONN288_H44441004(CHIPS)':
 'VDD'<1>: CDS_PINID='VDD(1)';
NODE_NAME     J4A1 231
 '@BASEBOARD_FAB2_LIB.BASEBOARD_FAB2(SCH_1):PAGE53_I171@MSTR_SCONN.SCONN288_H44441004(CHIPS)':
 'VDD'<2>: CDS_PINID='VDD(2)';
NODE_NAME     J4A1 229
 '@BASEBOARD_FAB2_LIB.BASEBOARD_FAB2(SCH_1):PAGE53_I171@MSTR_SCONN.SCONN288_H44441004(CHIPS)':
 'VDD'<3>: CDS_PINID='VDD(3)';
NODE_NAME     J4A1 226
 '@BASEBOARD_FAB2_LIB.BASEBOARD_FAB2(SCH_1):PAGE53_I171@MSTR_SCONN.SCONN288_H44441004(CHIPS)':
 'VDD'<4>: CDS_PINID='VDD(4)';
NODE_NAME     J4A1 223
 '@BASEBOARD_FAB2_LIB.BASEBOARD_FAB2(SCH_1):PAGE53_I171@MSTR_SCONN.SCONN288_H44441004(CHIPS)':
 'VDD'<5>: CDS_PINID='VDD(5)';
NODE_NAME     J4A1 220
 '@BASEBOARD_FAB2_LIB.BASEBOARD_FAB2(SCH_1):PAGE53_I171@MSTR_SCONN.SCONN288_H44441004(CHIPS)':
 'VDD'<6>: CDS_PINID='VDD(6)';
NODE_NAME     J4A1 217
 '@BASEBOARD_FAB2_LIB.BASEBOARD_FAB2(SCH_1):PAGE53_I171@MSTR_SCONN.SCONN288_H44441004(CHIPS)':
 'VDD'<7>: CDS_PINID='VDD(7)';
NODE_NAME     J4A1 215
 '@BASEBOARD_FAB2_LIB.BASEBOARD_FAB2(SCH_1):PAGE53_I171@MSTR_SCONN.SCONN288_H44441004(CHIPS)':
 'VDD'<8>: CDS_PINID='VDD(8)';
NODE_NAME     J4A1 212
 '@BASEBOARD_FAB2_LIB.BASEBOARD_FAB2(SCH_1):PAGE53_I171@MSTR_SCONN.SCONN288_H44441004(CHIPS)':
 'VDD'<9>: CDS_PINID='VDD(9)';
NODE_NAME     J4A1 209
 '@BASEBOARD_FAB2_LIB.BASEBOARD_FAB2(SCH_1):PAGE53_I171@MSTR_SCONN.SCONN288_H44441004(CHIPS)':
 'VDD'<10>: CDS_PINID='VDD(10)';
NODE_NAME     J4A1 206
 '@BASEBOARD_FAB2_LIB.BASEBOARD_FAB2(SCH_1):PAGE53_I171@MSTR_SCONN.SCONN288_H44441004(CHIPS)':
 'VDD'<11>: CDS_PINID='VDD(11)';
NODE_NAME     J4A1 204
 '@BASEBOARD_FAB2_LIB.BASEBOARD_FAB2(SCH_1):PAGE53_I171@MSTR_SCONN.SCONN288_H44441004(CHIPS)':
 'VDD'<12>: CDS_PINID='VDD(12)';
NODE_NAME     J4A1 92
 '@BASEBOARD_FAB2_LIB.BASEBOARD_FAB2(SCH_1):PAGE53_I171@MSTR_SCONN.SCONN288_H44441004(CHIPS)':
 'VDD'<13>: CDS_PINID='VDD(13)';
NODE_NAME     J4A1 90
 '@BASEBOARD_FAB2_LIB.BASEBOARD_FAB2(SCH_1):PAGE53_I171@MSTR_SCONN.SCONN288_H44441004(CHIPS)':
 'VDD'<14>: CDS_PINID='VDD(14)';
NODE_NAME     J4A1 88
 '@BASEBOARD_FAB2_LIB.BASEBOARD_FAB2(SCH_1):PAGE53_I171@MSTR_SCONN.SCONN288_H44441004(CHIPS)':
 'VDD'<15>: CDS_PINID='VDD(15)';
NODE_NAME     J4A1 85
 '@BASEBOARD_FAB2_LIB.BASEBOARD_FAB2(SCH_1):PAGE53_I171@MSTR_SCONN.SCONN288_H44441004(CHIPS)':
 'VDD'<16>: CDS_PINID='VDD(16)';
NODE_NAME     J4A1 83
 '@BASEBOARD_FAB2_LIB.BASEBOARD_FAB2(SCH_1):PAGE53_I171@MSTR_SCONN.SCONN288_H44441004(CHIPS)':
 'VDD'<17>: CDS_PINID='VDD(17)';
NODE_NAME     J4A1 80
 '@BASEBOARD_FAB2_LIB.BASEBOARD_FAB2(SCH_1):PAGE53_I171@MSTR_SCONN.SCONN288_H44441004(CHIPS)':
 'VDD'<18>: CDS_PINID='VDD(18)';
NODE_NAME     J4A1 76
 '@BASEBOARD_FAB2_LIB.BASEBOARD_FAB2(SCH_1):PAGE53_I171@MSTR_SCONN.SCONN288_H44441004(CHIPS)':
 'VDD'<19>: CDS_PINID='VDD(19)';
NODE_NAME     J4A1 73
 '@BASEBOARD_FAB2_LIB.BASEBOARD_FAB2(SCH_1):PAGE53_I171@MSTR_SCONN.SCONN288_H44441004(CHIPS)':
 'VDD'<20>: CDS_PINID='VDD(20)';
NODE_NAME     J4A1 70
 '@BASEBOARD_FAB2_LIB.BASEBOARD_FAB2(SCH_1):PAGE53_I171@MSTR_SCONN.SCONN288_H44441004(CHIPS)':
 'VDD'<21>: CDS_PINID='VDD(21)';
NODE_NAME     J4A1 67
 '@BASEBOARD_FAB2_LIB.BASEBOARD_FAB2(SCH_1):PAGE53_I171@MSTR_SCONN.SCONN288_H44441004(CHIPS)':
 'VDD'<22>: CDS_PINID='VDD(22)';
NODE_NAME     J4A1 64
 '@BASEBOARD_FAB2_LIB.BASEBOARD_FAB2(SCH_1):PAGE53_I171@MSTR_SCONN.SCONN288_H44441004(CHIPS)':
 'VDD'<23>: CDS_PINID='VDD(23)';
NODE_NAME     J4A1 61
 '@BASEBOARD_FAB2_LIB.BASEBOARD_FAB2(SCH_1):PAGE53_I171@MSTR_SCONN.SCONN288_H44441004(CHIPS)':
 'VDD'<24>: CDS_PINID='VDD(24)';
NODE_NAME     J4A1 59
 '@BASEBOARD_FAB2_LIB.BASEBOARD_FAB2(SCH_1):PAGE53_I171@MSTR_SCONN.SCONN288_H44441004(CHIPS)':
 'VDD'<25>: CDS_PINID='VDD(25)';
NODE_NAME     J6L1 236
 '@BASEBOARD_FAB2_LIB.BASEBOARD_FAB2(SCH_1):PAGE54_I170@MSTR_SCONN.SCONN288_H44441003(CHIPS)':
 'VDD'<0>: CDS_PINID='VDD(0)';
NODE_NAME     J6L1 233
 '@BASEBOARD_FAB2_LIB.BASEBOARD_FAB2(SCH_1):PAGE54_I170@MSTR_SCONN.SCONN288_H44441003(CHIPS)':
 'VDD'<1>: CDS_PINID='VDD(1)';
NODE_NAME     J6L1 231
 '@BASEBOARD_FAB2_LIB.BASEBOARD_FAB2(SCH_1):PAGE54_I170@MSTR_SCONN.SCONN288_H44441003(CHIPS)':
 'VDD'<2>: CDS_PINID='VDD(2)';
NODE_NAME     J6L1 229
 '@BASEBOARD_FAB2_LIB.BASEBOARD_FAB2(SCH_1):PAGE54_I170@MSTR_SCONN.SCONN288_H44441003(CHIPS)':
 'VDD'<3>: CDS_PINID='VDD(3)';
NODE_NAME     J6L1 226
 '@BASEBOARD_FAB2_LIB.BASEBOARD_FAB2(SCH_1):PAGE54_I170@MSTR_SCONN.SCONN288_H44441003(CHIPS)':
 'VDD'<4>: CDS_PINID='VDD(4)';
NODE_NAME     J6L1 223
 '@BASEBOARD_FAB2_LIB.BASEBOARD_FAB2(SCH_1):PAGE54_I170@MSTR_SCONN.SCONN288_H44441003(CHIPS)':
 'VDD'<5>: CDS_PINID='VDD(5)';
NODE_NAME     J6L1 220
 '@BASEBOARD_FAB2_LIB.BASEBOARD_FAB2(SCH_1):PAGE54_I170@MSTR_SCONN.SCONN288_H44441003(CHIPS)':
 'VDD'<6>: CDS_PINID='VDD(6)';
NODE_NAME     J6L1 217
 '@BASEBOARD_FAB2_LIB.BASEBOARD_FAB2(SCH_1):PAGE54_I170@MSTR_SCONN.SCONN288_H44441003(CHIPS)':
 'VDD'<7>: CDS_PINID='VDD(7)';
NODE_NAME     J6L1 215
 '@BASEBOARD_FAB2_LIB.BASEBOARD_FAB2(SCH_1):PAGE54_I170@MSTR_SCONN.SCONN288_H44441003(CHIPS)':
 'VDD'<8>: CDS_PINID='VDD(8)';
NODE_NAME     J6L1 212
 '@BASEBOARD_FAB2_LIB.BASEBOARD_FAB2(SCH_1):PAGE54_I170@MSTR_SCONN.SCONN288_H44441003(CHIPS)':
 'VDD'<9>: CDS_PINID='VDD(9)';
NODE_NAME     J6L1 209
 '@BASEBOARD_FAB2_LIB.BASEBOARD_FAB2(SCH_1):PAGE54_I170@MSTR_SCONN.SCONN288_H44441003(CHIPS)':
 'VDD'<10>: CDS_PINID='VDD(10)';
NODE_NAME     J6L1 206
 '@BASEBOARD_FAB2_LIB.BASEBOARD_FAB2(SCH_1):PAGE54_I170@MSTR_SCONN.SCONN288_H44441003(CHIPS)':
 'VDD'<11>: CDS_PINID='VDD(11)';
NODE_NAME     J6L1 204
 '@BASEBOARD_FAB2_LIB.BASEBOARD_FAB2(SCH_1):PAGE54_I170@MSTR_SCONN.SCONN288_H44441003(CHIPS)':
 'VDD'<12>: CDS_PINID='VDD(12)';
NODE_NAME     J6L1 92
 '@BASEBOARD_FAB2_LIB.BASEBOARD_FAB2(SCH_1):PAGE54_I170@MSTR_SCONN.SCONN288_H44441003(CHIPS)':
 'VDD'<13>: CDS_PINID='VDD(13)';
NODE_NAME     J6L1 90
 '@BASEBOARD_FAB2_LIB.BASEBOARD_FAB2(SCH_1):PAGE54_I170@MSTR_SCONN.SCONN288_H44441003(CHIPS)':
 'VDD'<14>: CDS_PINID='VDD(14)';
NODE_NAME     J6L1 88
 '@BASEBOARD_FAB2_LIB.BASEBOARD_FAB2(SCH_1):PAGE54_I170@MSTR_SCONN.SCONN288_H44441003(CHIPS)':
 'VDD'<15>: CDS_PINID='VDD(15)';
NODE_NAME     J6L1 85
 '@BASEBOARD_FAB2_LIB.BASEBOARD_FAB2(SCH_1):PAGE54_I170@MSTR_SCONN.SCONN288_H44441003(CHIPS)':
 'VDD'<16>: CDS_PINID='VDD(16)';
NODE_NAME     J6L1 83
 '@BASEBOARD_FAB2_LIB.BASEBOARD_FAB2(SCH_1):PAGE54_I170@MSTR_SCONN.SCONN288_H44441003(CHIPS)':
 'VDD'<17>: CDS_PINID='VDD(17)';
NODE_NAME     J6L1 80
 '@BASEBOARD_FAB2_LIB.BASEBOARD_FAB2(SCH_1):PAGE54_I170@MSTR_SCONN.SCONN288_H44441003(CHIPS)':
 'VDD'<18>: CDS_PINID='VDD(18)';
NODE_NAME     J6L1 76
 '@BASEBOARD_FAB2_LIB.BASEBOARD_FAB2(SCH_1):PAGE54_I170@MSTR_SCONN.SCONN288_H44441003(CHIPS)':
 'VDD'<19>: CDS_PINID='VDD(19)';
NODE_NAME     J6L1 73
 '@BASEBOARD_FAB2_LIB.BASEBOARD_FAB2(SCH_1):PAGE54_I170@MSTR_SCONN.SCONN288_H44441003(CHIPS)':
 'VDD'<20>: CDS_PINID='VDD(20)';
NODE_NAME     J6L1 70
 '@BASEBOARD_FAB2_LIB.BASEBOARD_FAB2(SCH_1):PAGE54_I170@MSTR_SCONN.SCONN288_H44441003(CHIPS)':
 'VDD'<21>: CDS_PINID='VDD(21)';
NODE_NAME     J6L1 67
 '@BASEBOARD_FAB2_LIB.BASEBOARD_FAB2(SCH_1):PAGE54_I170@MSTR_SCONN.SCONN288_H44441003(CHIPS)':
 'VDD'<22>: CDS_PINID='VDD(22)';
NODE_NAME     J6L1 64
 '@BASEBOARD_FAB2_LIB.BASEBOARD_FAB2(SCH_1):PAGE54_I170@MSTR_SCONN.SCONN288_H44441003(CHIPS)':
 'VDD'<23>: CDS_PINID='VDD(23)';
NODE_NAME     J6L1 61
 '@BASEBOARD_FAB2_LIB.BASEBOARD_FAB2(SCH_1):PAGE54_I170@MSTR_SCONN.SCONN288_H44441003(CHIPS)':
 'VDD'<24>: CDS_PINID='VDD(24)';
NODE_NAME     J6L1 59
 '@BASEBOARD_FAB2_LIB.BASEBOARD_FAB2(SCH_1):PAGE54_I170@MSTR_SCONN.SCONN288_H44441003(CHIPS)':
 'VDD'<25>: CDS_PINID='VDD(25)';
NODE_NAME     R3P29 1
 '@BASEBOARD_FAB2_LIB.BASEBOARD_FAB2(SCH_1):PAGE96_I5@MSTR_DISCRETE.RES(CHIPS)':
 'A': CDS_PINID='A';
NODE_NAME     R6M1 1
 '@BASEBOARD_FAB2_LIB.BASEBOARD_FAB2(SCH_1):PAGE98_I9@MSTR_DISCRETE.RES(CHIPS)':
 'A': CDS_PINID='A';
NODE_NAME     R6L13 1
 '@BASEBOARD_FAB2_LIB.BASEBOARD_FAB2(SCH_1):PAGE98_I54@MSTR_DISCRETE.RES(CHIPS)':
 'A': CDS_PINID='A';
NODE_NAME     R6L2 1
 '@BASEBOARD_FAB2_LIB.BASEBOARD_FAB2(SCH_1):PAGE98_I62@MSTR_DISCRETE.RES(CHIPS)':
 'A': CDS_PINID='A';
NODE_NAME     C6A4 1
 '@BASEBOARD_FAB2_LIB.BASEBOARD_FAB2(SCH_1):PAGE219_I68@MSTR_DISCRETE.CAP(CHIPS)':
 'A': CDS_PINID='A';
NODE_NAME     C6A1 1
 '@BASEBOARD_FAB2_LIB.BASEBOARD_FAB2(SCH_1):PAGE219_I87@MSTR_DISCRETE.CAP(CHIPS)':
 'A': CDS_PINID='A';
NODE_NAME     EU7A1 1
 '@BASEBOARD_FAB2_LIB.BASEBOARD_FAB2(SCH_1):PAGE219_I106@MSTR_DISCRETE.IR354XX(CHIPS)':
 'VOS': CDS_PINID='VOS';
NODE_NAME     EU7A4 1
 '@BASEBOARD_FAB2_LIB.BASEBOARD_FAB2(SCH_1):PAGE219_I107@MSTR_DISCRETE.IR354XX(CHIPS)':
 'VOS': CDS_PINID='VOS';
NODE_NAME     R4L4 1
 '@BASEBOARD_FAB2_LIB.BASEBOARD_FAB2(SCH_1):PAGE220_I58@MSTR_DISCRETE.RES(CHIPS)':
 'A': CDS_PINID='A';
NODE_NAME     C3L6 1
 '@BASEBOARD_FAB2_LIB.BASEBOARD_FAB2(SCH_1):PAGE220_I75@MSTR_DISCRETE.CAPP(CHIPS)':
 'A': CDS_PINID='A';
NODE_NAME     C3L14 1
 '@BASEBOARD_FAB2_LIB.BASEBOARD_FAB2(SCH_1):PAGE220_I76@MSTR_DISCRETE.CAPP(CHIPS)':
 'A': CDS_PINID='A';
NODE_NAME     C6A5 1
 '@BASEBOARD_FAB2_LIB.BASEBOARD_FAB2(SCH_1):PAGE220_I77@MSTR_DISCRETE.CAPP(CHIPS)':
 'A': CDS_PINID='A';
NODE_NAME     C4L5 1
 '@BASEBOARD_FAB2_LIB.BASEBOARD_FAB2(SCH_1):PAGE220_I78@MSTR_DISCRETE.CAPP(CHIPS)':
 'A': CDS_PINID='A';
NODE_NAME     C5L15 1
 '@BASEBOARD_FAB2_LIB.BASEBOARD_FAB2(SCH_1):PAGE220_I192@DEV_DISCRETE.CAP_A(CHIPS)':
 'A': CDS_PINID='A';
NODE_NAME     C5A5 1
 '@BASEBOARD_FAB2_LIB.BASEBOARD_FAB2(SCH_1):PAGE220_I193@DEV_DISCRETE.CAP_A(CHIPS)':
 'A': CDS_PINID='A';
NODE_NAME     C5B1 1
 '@BASEBOARD_FAB2_LIB.BASEBOARD_FAB2(SCH_1):PAGE220_I194@DEV_DISCRETE.CAP_A(CHIPS)':
 'A': CDS_PINID='A';
NODE_NAME     C5M9 1
 '@BASEBOARD_FAB2_LIB.BASEBOARD_FAB2(SCH_1):PAGE220_I195@DEV_DISCRETE.CAP_A(CHIPS)':
 'A': CDS_PINID='A';
NODE_NAME     C4M5 1
 '@BASEBOARD_FAB2_LIB.BASEBOARD_FAB2(SCH_1):PAGE220_I196@DEV_DISCRETE.CAP_A(CHIPS)':
 'A': CDS_PINID='A';
NODE_NAME     C5B2 1
 '@BASEBOARD_FAB2_LIB.BASEBOARD_FAB2(SCH_1):PAGE220_I197@DEV_DISCRETE.CAP_A(CHIPS)':
 'A': CDS_PINID='A';
NODE_NAME     C5M10 1
 '@BASEBOARD_FAB2_LIB.BASEBOARD_FAB2(SCH_1):PAGE220_I198@DEV_DISCRETE.CAP_A(CHIPS)':
 'A': CDS_PINID='A';
NODE_NAME     C5M3 1
 '@BASEBOARD_FAB2_LIB.BASEBOARD_FAB2(SCH_1):PAGE220_I199@DEV_DISCRETE.CAP_A(CHIPS)':
 'A': CDS_PINID='A';
NODE_NAME     C5M11 1
 '@BASEBOARD_FAB2_LIB.BASEBOARD_FAB2(SCH_1):PAGE220_I200@DEV_DISCRETE.CAP_A(CHIPS)':
 'A': CDS_PINID='A';
NODE_NAME     SH4L2 2
 '@BASEBOARD_FAB2_LIB.BASEBOARD_FAB2(SCH_1):PAGE220_I239@MSTR_MISC.SHUNT(CHIPS)':
 'B':NET_SHORT='VSENSE_PVDDQ_DEF_P:PVDDQ_DEF',
 CDS_PINID='B';
NODE_NAME     C5G67 1
 '@BASEBOARD_FAB2_LIB.BASEBOARD_FAB2(SCH_1):PAGE242_I71@DEV_DISCRETE.CAP_A(CHIPS)':
 'A': CDS_PINID='A';
NODE_NAME     C5G66 1
 '@BASEBOARD_FAB2_LIB.BASEBOARD_FAB2(SCH_1):PAGE242_I72@DEV_DISCRETE.CAP_A(CHIPS)':
 'A': CDS_PINID='A';
NODE_NAME     C5G65 1
 '@BASEBOARD_FAB2_LIB.BASEBOARD_FAB2(SCH_1):PAGE242_I73@DEV_DISCRETE.CAP_A(CHIPS)':
 'A': CDS_PINID='A';
NODE_NAME     C5G64 1
 '@BASEBOARD_FAB2_LIB.BASEBOARD_FAB2(SCH_1):PAGE242_I74@DEV_DISCRETE.CAP_A(CHIPS)':
 'A': CDS_PINID='A';
NODE_NAME     C5G63 1
 '@BASEBOARD_FAB2_LIB.BASEBOARD_FAB2(SCH_1):PAGE242_I75@DEV_DISCRETE.CAP_A(CHIPS)':
 'A': CDS_PINID='A';
NODE_NAME     C5G62 1
 '@BASEBOARD_FAB2_LIB.BASEBOARD_FAB2(SCH_1):PAGE242_I76@DEV_DISCRETE.CAP_A(CHIPS)':
 'A': CDS_PINID='A';
NODE_NAME     C5G61 1
 '@BASEBOARD_FAB2_LIB.BASEBOARD_FAB2(SCH_1):PAGE242_I77@DEV_DISCRETE.CAP_A(CHIPS)':
 'A': CDS_PINID='A';
NODE_NAME     C5G60 1
 '@BASEBOARD_FAB2_LIB.BASEBOARD_FAB2(SCH_1):PAGE242_I78@DEV_DISCRETE.CAP_A(CHIPS)':
 'A': CDS_PINID='A';
NODE_NAME     C5G59 1
 '@BASEBOARD_FAB2_LIB.BASEBOARD_FAB2(SCH_1):PAGE242_I79@DEV_DISCRETE.CAP_A(CHIPS)':
 'A': CDS_PINID='A';
NODE_NAME     C5G76 1
 '@BASEBOARD_FAB2_LIB.BASEBOARD_FAB2(SCH_1):PAGE242_I80@DEV_DISCRETE.CAP_A(CHIPS)':
 'A': CDS_PINID='A';
NODE_NAME     C5G75 1
 '@BASEBOARD_FAB2_LIB.BASEBOARD_FAB2(SCH_1):PAGE242_I81@DEV_DISCRETE.CAP_A(CHIPS)':
 'A': CDS_PINID='A';
NODE_NAME     C5G74 1
 '@BASEBOARD_FAB2_LIB.BASEBOARD_FAB2(SCH_1):PAGE242_I82@DEV_DISCRETE.CAP_A(CHIPS)':
 'A': CDS_PINID='A';
NODE_NAME     C5G73 1
 '@BASEBOARD_FAB2_LIB.BASEBOARD_FAB2(SCH_1):PAGE242_I83@DEV_DISCRETE.CAP_A(CHIPS)':
 'A': CDS_PINID='A';
NODE_NAME     C5G72 1
 '@BASEBOARD_FAB2_LIB.BASEBOARD_FAB2(SCH_1):PAGE242_I84@DEV_DISCRETE.CAP_A(CHIPS)':
 'A': CDS_PINID='A';
NODE_NAME     C5G71 1
 '@BASEBOARD_FAB2_LIB.BASEBOARD_FAB2(SCH_1):PAGE242_I85@DEV_DISCRETE.CAP_A(CHIPS)':
 'A': CDS_PINID='A';
NODE_NAME     C5G70 1
 '@BASEBOARD_FAB2_LIB.BASEBOARD_FAB2(SCH_1):PAGE242_I86@DEV_DISCRETE.CAP_A(CHIPS)':
 'A': CDS_PINID='A';
NODE_NAME     C5G69 1
 '@BASEBOARD_FAB2_LIB.BASEBOARD_FAB2(SCH_1):PAGE242_I87@DEV_DISCRETE.CAP_A(CHIPS)':
 'A': CDS_PINID='A';
NODE_NAME     C5G68 1
 '@BASEBOARD_FAB2_LIB.BASEBOARD_FAB2(SCH_1):PAGE242_I88@DEV_DISCRETE.CAP_A(CHIPS)':
 'A': CDS_PINID='A';
NODE_NAME     C5G77 1
 '@BASEBOARD_FAB2_LIB.BASEBOARD_FAB2(SCH_1):PAGE242_I89@MSTR_DISCRETE.CAP(CHIPS)':
 'A': CDS_PINID='A';
NODE_NAME     C5G78 1
 '@BASEBOARD_FAB2_LIB.BASEBOARD_FAB2(SCH_1):PAGE242_I91@MSTR_DISCRETE.CAP(CHIPS)':
 'A': CDS_PINID='A';
NODE_NAME     R6L10 1
 '@BASEBOARD_FAB2_LIB.BASEBOARD_FAB2(SCH_1):PAGE222_I6@MSTR_DISCRETE.RES(CHIPS)':
 'A': CDS_PINID='A';
NODE_NAME     EU4A1 10
 '@BASEBOARD_FAB2_LIB.BASEBOARD_FAB2(SCH_1):PAGE222_I13@MSTR_VREG.MIC5166(CHIPS)':
 'VIN': CDS_PINID='VIN';
NODE_NAME     C6L4 1
 '@BASEBOARD_FAB2_LIB.BASEBOARD_FAB2(SCH_1):PAGE222_I15@MSTR_DISCRETE.CAP(CHIPS)':
 'A': CDS_PINID='A';
NODE_NAME     C6L3 1
 '@BASEBOARD_FAB2_LIB.BASEBOARD_FAB2(SCH_1):PAGE222_I17@MSTR_DISCRETE.CAP(CHIPS)':
 'A': CDS_PINID='A';
NODE_NAME     C5D4 1
 '@BASEBOARD_FAB2_LIB.BASEBOARD_FAB2(SCH_1):PAGE220_I249@DEV_DISCRETE.CAP_A(CHIPS)':
 'A': CDS_PINID='A';
NODE_NAME     C5D3 1
 '@BASEBOARD_FAB2_LIB.BASEBOARD_FAB2(SCH_1):PAGE220_I250@DEV_DISCRETE.CAP_A(CHIPS)':
 'A': CDS_PINID='A';
NODE_NAME     C5D2 1
 '@BASEBOARD_FAB2_LIB.BASEBOARD_FAB2(SCH_1):PAGE220_I251@DEV_DISCRETE.CAP_A(CHIPS)':
 'A': CDS_PINID='A';
NODE_NAME     C5D1 1
 '@BASEBOARD_FAB2_LIB.BASEBOARD_FAB2(SCH_1):PAGE220_I252@DEV_DISCRETE.CAP_A(CHIPS)':
 'A': CDS_PINID='A';
NODE_NAME     C5D9 1
 '@BASEBOARD_FAB2_LIB.BASEBOARD_FAB2(SCH_1):PAGE220_I258@DEV_DISCRETE.CAP_A(CHIPS)':
 'A': CDS_PINID='A';
NODE_NAME     C5D6 1
 '@BASEBOARD_FAB2_LIB.BASEBOARD_FAB2(SCH_1):PAGE220_I259@DEV_DISCRETE.CAP_A(CHIPS)':
 'A': CDS_PINID='A';
NODE_NAME     C5D7 1
 '@BASEBOARD_FAB2_LIB.BASEBOARD_FAB2(SCH_1):PAGE220_I260@DEV_DISCRETE.CAP_A(CHIPS)':
 'A': CDS_PINID='A';
NODE_NAME     C5D8 1
 '@BASEBOARD_FAB2_LIB.BASEBOARD_FAB2(SCH_1):PAGE220_I261@DEV_DISCRETE.CAP_A(CHIPS)':
 'A': CDS_PINID='A';
NODE_NAME     C5A1 1
 '@BASEBOARD_FAB2_LIB.BASEBOARD_FAB2(SCH_1):PAGE220_I262@DEV_DISCRETE.CAP_A(CHIPS)':
 'A': CDS_PINID='A';
NODE_NAME     C5A15 1
 '@BASEBOARD_FAB2_LIB.BASEBOARD_FAB2(SCH_1):PAGE220_I263@DEV_DISCRETE.CAP_A(CHIPS)':
 'A': CDS_PINID='A';
NODE_NAME     C5A12 1
 '@BASEBOARD_FAB2_LIB.BASEBOARD_FAB2(SCH_1):PAGE220_I264@DEV_DISCRETE.CAP_A(CHIPS)':
 'A': CDS_PINID='A';
NODE_NAME     C5A13 1
 '@BASEBOARD_FAB2_LIB.BASEBOARD_FAB2(SCH_1):PAGE220_I265@DEV_DISCRETE.CAP_A(CHIPS)':
 'A': CDS_PINID='A';
NODE_NAME     C5A2 1
 '@BASEBOARD_FAB2_LIB.BASEBOARD_FAB2(SCH_1):PAGE220_I266@DEV_DISCRETE.CAP_A(CHIPS)':
 'A': CDS_PINID='A';
NODE_NAME     C5A14 1
 '@BASEBOARD_FAB2_LIB.BASEBOARD_FAB2(SCH_1):PAGE220_I267@DEV_DISCRETE.CAP_A(CHIPS)':
 'A': CDS_PINID='A';
NODE_NAME     C5A6 1
 '@BASEBOARD_FAB2_LIB.BASEBOARD_FAB2(SCH_1):PAGE220_I268@DEV_DISCRETE.CAP_A(CHIPS)':
 'A': CDS_PINID='A';
NODE_NAME     C5A7 1
 '@BASEBOARD_FAB2_LIB.BASEBOARD_FAB2(SCH_1):PAGE220_I269@DEV_DISCRETE.CAP_A(CHIPS)':
 'A': CDS_PINID='A';
NODE_NAME     C5A3 1
 '@BASEBOARD_FAB2_LIB.BASEBOARD_FAB2(SCH_1):PAGE220_I270@DEV_DISCRETE.CAP_A(CHIPS)':
 'A': CDS_PINID='A';
NODE_NAME     C5A8 1
 '@BASEBOARD_FAB2_LIB.BASEBOARD_FAB2(SCH_1):PAGE220_I271@DEV_DISCRETE.CAP_A(CHIPS)':
 'A': CDS_PINID='A';
NODE_NAME     C5A9 1
 '@BASEBOARD_FAB2_LIB.BASEBOARD_FAB2(SCH_1):PAGE220_I272@DEV_DISCRETE.CAP_A(CHIPS)':
 'A': CDS_PINID='A';
NODE_NAME     C5A16 1
 '@BASEBOARD_FAB2_LIB.BASEBOARD_FAB2(SCH_1):PAGE220_I273@DEV_DISCRETE.CAP_A(CHIPS)':
 'A': CDS_PINID='A';
NODE_NAME     C5A4 1
 '@BASEBOARD_FAB2_LIB.BASEBOARD_FAB2(SCH_1):PAGE220_I274@DEV_DISCRETE.CAP_A(CHIPS)':
 'A': CDS_PINID='A';
NODE_NAME     C5A17 1
 '@BASEBOARD_FAB2_LIB.BASEBOARD_FAB2(SCH_1):PAGE220_I275@DEV_DISCRETE.CAP_A(CHIPS)':
 'A': CDS_PINID='A';
NODE_NAME     C5A18 1
 '@BASEBOARD_FAB2_LIB.BASEBOARD_FAB2(SCH_1):PAGE220_I276@DEV_DISCRETE.CAP_A(CHIPS)':
 'A': CDS_PINID='A';
NODE_NAME     C5A19 1
 '@BASEBOARD_FAB2_LIB.BASEBOARD_FAB2(SCH_1):PAGE220_I277@DEV_DISCRETE.CAP_A(CHIPS)':
 'A': CDS_PINID='A';
NODE_NAME     C5L6 1
 '@BASEBOARD_FAB2_LIB.BASEBOARD_FAB2(SCH_1):PAGE220_I278@DEV_DISCRETE.CAP_A(CHIPS)':
 'A': CDS_PINID='A';
NODE_NAME     C5L7 1
 '@BASEBOARD_FAB2_LIB.BASEBOARD_FAB2(SCH_1):PAGE220_I279@DEV_DISCRETE.CAP_A(CHIPS)':
 'A': CDS_PINID='A';
NODE_NAME     C5L8 1
 '@BASEBOARD_FAB2_LIB.BASEBOARD_FAB2(SCH_1):PAGE220_I280@DEV_DISCRETE.CAP_A(CHIPS)':
 'A': CDS_PINID='A';
NODE_NAME     C5L9 1
 '@BASEBOARD_FAB2_LIB.BASEBOARD_FAB2(SCH_1):PAGE220_I281@DEV_DISCRETE.CAP_A(CHIPS)':
 'A': CDS_PINID='A';
NODE_NAME     C5L10 1
 '@BASEBOARD_FAB2_LIB.BASEBOARD_FAB2(SCH_1):PAGE220_I282@DEV_DISCRETE.CAP_A(CHIPS)':
 'A': CDS_PINID='A';
NODE_NAME     C5L11 1
 '@BASEBOARD_FAB2_LIB.BASEBOARD_FAB2(SCH_1):PAGE220_I283@DEV_DISCRETE.CAP_A(CHIPS)':
 'A': CDS_PINID='A';
NODE_NAME     C5L12 1
 '@BASEBOARD_FAB2_LIB.BASEBOARD_FAB2(SCH_1):PAGE220_I284@DEV_DISCRETE.CAP_A(CHIPS)':
 'A': CDS_PINID='A';
NODE_NAME     C5L13 1
 '@BASEBOARD_FAB2_LIB.BASEBOARD_FAB2(SCH_1):PAGE220_I285@DEV_DISCRETE.CAP_A(CHIPS)':
 'A': CDS_PINID='A';
NODE_NAME     C5M7 1
 '@BASEBOARD_FAB2_LIB.BASEBOARD_FAB2(SCH_1):PAGE220_I286@DEV_DISCRETE.CAP_A(CHIPS)':
 'A': CDS_PINID='A';
NODE_NAME     C5M6 1
 '@BASEBOARD_FAB2_LIB.BASEBOARD_FAB2(SCH_1):PAGE220_I287@DEV_DISCRETE.CAP_A(CHIPS)':
 'A': CDS_PINID='A';
NODE_NAME     C5M5 1
 '@BASEBOARD_FAB2_LIB.BASEBOARD_FAB2(SCH_1):PAGE220_I288@DEV_DISCRETE.CAP_A(CHIPS)':
 'A': CDS_PINID='A';
NODE_NAME     C5M4 1
 '@BASEBOARD_FAB2_LIB.BASEBOARD_FAB2(SCH_1):PAGE220_I289@DEV_DISCRETE.CAP_A(CHIPS)':
 'A': CDS_PINID='A';
NODE_NAME     C5M2 1
 '@BASEBOARD_FAB2_LIB.BASEBOARD_FAB2(SCH_1):PAGE220_I290@DEV_DISCRETE.CAP_A(CHIPS)':
 'A': CDS_PINID='A';
NODE_NAME     C5M1 1
 '@BASEBOARD_FAB2_LIB.BASEBOARD_FAB2(SCH_1):PAGE220_I291@DEV_DISCRETE.CAP_A(CHIPS)':
 'A': CDS_PINID='A';
NODE_NAME     C4M2 1
 '@BASEBOARD_FAB2_LIB.BASEBOARD_FAB2(SCH_1):PAGE220_I292@DEV_DISCRETE.CAP_A(CHIPS)':
 'A': CDS_PINID='A';
NODE_NAME     C5A11 1
 '@BASEBOARD_FAB2_LIB.BASEBOARD_FAB2(SCH_1):PAGE220_I293@DEV_DISCRETE.CAP_A(CHIPS)':
 'A': CDS_PINID='A';
NODE_NAME     C5A20 1
 '@BASEBOARD_FAB2_LIB.BASEBOARD_FAB2(SCH_1):PAGE220_I308@MSTR_DISCRETE.CAP(CHIPS)':
 'A': CDS_PINID='A';
NODE_NAME     C5L1 1
 '@BASEBOARD_FAB2_LIB.BASEBOARD_FAB2(SCH_1):PAGE220_I309@MSTR_DISCRETE.CAP(CHIPS)':
 'A': CDS_PINID='A';
NODE_NAME     C5L3 1
 '@BASEBOARD_FAB2_LIB.BASEBOARD_FAB2(SCH_1):PAGE220_I310@MSTR_DISCRETE.CAP(CHIPS)':
 'A': CDS_PINID='A';
NODE_NAME     C5L2 1
 '@BASEBOARD_FAB2_LIB.BASEBOARD_FAB2(SCH_1):PAGE220_I311@MSTR_DISCRETE.CAP(CHIPS)':
 'A': CDS_PINID='A';
NODE_NAME     C5M12 1
 '@BASEBOARD_FAB2_LIB.BASEBOARD_FAB2(SCH_1):PAGE220_I312@MSTR_DISCRETE.CAP(CHIPS)':
 'A': CDS_PINID='A';
NODE_NAME     C5L14 1
 '@BASEBOARD_FAB2_LIB.BASEBOARD_FAB2(SCH_1):PAGE220_I313@MSTR_DISCRETE.CAP(CHIPS)':
 'A': CDS_PINID='A';
NODE_NAME     C5M8 1
 '@BASEBOARD_FAB2_LIB.BASEBOARD_FAB2(SCH_1):PAGE220_I314@MSTR_DISCRETE.CAP(CHIPS)':
 'A': CDS_PINID='A';
NODE_NAME     C5P3 1
 '@BASEBOARD_FAB2_LIB.BASEBOARD_FAB2(SCH_1):PAGE220_I315@MSTR_DISCRETE.CAP(CHIPS)':
 'A': CDS_PINID='A';
NODE_NAME     C5P6 1
 '@BASEBOARD_FAB2_LIB.BASEBOARD_FAB2(SCH_1):PAGE220_I316@MSTR_DISCRETE.CAP(CHIPS)':
 'A': CDS_PINID='A';
NODE_NAME     C5P5 1
 '@BASEBOARD_FAB2_LIB.BASEBOARD_FAB2(SCH_1):PAGE220_I317@MSTR_DISCRETE.CAP(CHIPS)':
 'A': CDS_PINID='A';
NODE_NAME     C5P4 1
 '@BASEBOARD_FAB2_LIB.BASEBOARD_FAB2(SCH_1):PAGE220_I318@MSTR_DISCRETE.CAP(CHIPS)':
 'A': CDS_PINID='A';
NODE_NAME     C5P2 1
 '@BASEBOARD_FAB2_LIB.BASEBOARD_FAB2(SCH_1):PAGE220_I319@MSTR_DISCRETE.CAP(CHIPS)':
 'A': CDS_PINID='A';
NODE_NAME     C5P1 1
 '@BASEBOARD_FAB2_LIB.BASEBOARD_FAB2(SCH_1):PAGE220_I320@MSTR_DISCRETE.CAP(CHIPS)':
 'A': CDS_PINID='A';
NODE_NAME     C5A10 1
 '@BASEBOARD_FAB2_LIB.BASEBOARD_FAB2(SCH_1):PAGE220_I321@MSTR_DISCRETE.CAP(CHIPS)':
 'A': CDS_PINID='A';
NODE_NAME     L7A1 2
 '@BASEBOARD_FAB2_LIB.BASEBOARD_FAB2(SCH_1):PAGE219_I157@W_HDL.IND-120NH-30-GP(CHIPS)':
 'F': CDS_PINID='F';
NODE_NAME     L7A3 2
 '@BASEBOARD_FAB2_LIB.BASEBOARD_FAB2(SCH_1):PAGE219_I158@W_HDL.IND-120NH-30-GP(CHIPS)':
 'F': CDS_PINID='F';
NET_NAME
'PVDDQ_GHJ'
 '@BASEBOARD_FAB2_LIB.BASEBOARD_FAB2(SCH_1):PVDDQ_GHJ':
 C_SIGNAL='@baseboard_fab2_lib.baseboard_fab2(sch_1):pvddq_ghj';
NODE_NAME     U2D1 B49
 '@BASEBOARD_FAB2_LIB.BASEBOARD_FAB2(SCH_1):PAGE72_I32@CHPSET_LIB.SKX_EXT_B(CHIPS)':
 'VCCD012'<0>: CDS_PINID='VCCD012(0)';
NODE_NAME     U2D1 B53
 '@BASEBOARD_FAB2_LIB.BASEBOARD_FAB2(SCH_1):PAGE72_I32@CHPSET_LIB.SKX_EXT_B(CHIPS)':
 'VCCD012'<1>: CDS_PINID='VCCD012(1)';
NODE_NAME     U2D1 B59
 '@BASEBOARD_FAB2_LIB.BASEBOARD_FAB2(SCH_1):PAGE72_I32@CHPSET_LIB.SKX_EXT_B(CHIPS)':
 'VCCD012'<2>: CDS_PINID='VCCD012(2)';
NODE_NAME     U2D1 E46
 '@BASEBOARD_FAB2_LIB.BASEBOARD_FAB2(SCH_1):PAGE72_I32@CHPSET_LIB.SKX_EXT_B(CHIPS)':
 'VCCD012'<3>: CDS_PINID='VCCD012(3)';
NODE_NAME     U2D1 E48
 '@BASEBOARD_FAB2_LIB.BASEBOARD_FAB2(SCH_1):PAGE72_I32@CHPSET_LIB.SKX_EXT_B(CHIPS)':
 'VCCD012'<4>: CDS_PINID='VCCD012(4)';
NODE_NAME     U2D1 E50
 '@BASEBOARD_FAB2_LIB.BASEBOARD_FAB2(SCH_1):PAGE72_I32@CHPSET_LIB.SKX_EXT_B(CHIPS)':
 'VCCD012'<5>: CDS_PINID='VCCD012(5)';
NODE_NAME     U2D1 E52
 '@BASEBOARD_FAB2_LIB.BASEBOARD_FAB2(SCH_1):PAGE72_I32@CHPSET_LIB.SKX_EXT_B(CHIPS)':
 'VCCD012'<6>: CDS_PINID='VCCD012(6)';
NODE_NAME     U2D1 E54
 '@BASEBOARD_FAB2_LIB.BASEBOARD_FAB2(SCH_1):PAGE72_I32@CHPSET_LIB.SKX_EXT_B(CHIPS)':
 'VCCD012'<7>: CDS_PINID='VCCD012(7)';
NODE_NAME     U2D1 E56
 '@BASEBOARD_FAB2_LIB.BASEBOARD_FAB2(SCH_1):PAGE72_I32@CHPSET_LIB.SKX_EXT_B(CHIPS)':
 'VCCD012'<8>: CDS_PINID='VCCD012(8)';
NODE_NAME     U2D1 E58
 '@BASEBOARD_FAB2_LIB.BASEBOARD_FAB2(SCH_1):PAGE72_I32@CHPSET_LIB.SKX_EXT_B(CHIPS)':
 'VCCD012'<9>: CDS_PINID='VCCD012(9)';
NODE_NAME     U2D1 E60
 '@BASEBOARD_FAB2_LIB.BASEBOARD_FAB2(SCH_1):PAGE72_I32@CHPSET_LIB.SKX_EXT_B(CHIPS)':
 'VCCD012'<10>: CDS_PINID='VCCD012(10)';
NODE_NAME     U2D1 E62
 '@BASEBOARD_FAB2_LIB.BASEBOARD_FAB2(SCH_1):PAGE72_I32@CHPSET_LIB.SKX_EXT_B(CHIPS)':
 'VCCD012'<11>: CDS_PINID='VCCD012(11)';
NODE_NAME     U2D1 E64
 '@BASEBOARD_FAB2_LIB.BASEBOARD_FAB2(SCH_1):PAGE72_I32@CHPSET_LIB.SKX_EXT_B(CHIPS)':
 'VCCD012'<12>: CDS_PINID='VCCD012(12)';
NODE_NAME     U2D1 L46
 '@BASEBOARD_FAB2_LIB.BASEBOARD_FAB2(SCH_1):PAGE72_I32@CHPSET_LIB.SKX_EXT_B(CHIPS)':
 'VCCD012'<13>: CDS_PINID='VCCD012(13)';
NODE_NAME     U2D1 L48
 '@BASEBOARD_FAB2_LIB.BASEBOARD_FAB2(SCH_1):PAGE72_I32@CHPSET_LIB.SKX_EXT_B(CHIPS)':
 'VCCD012'<14>: CDS_PINID='VCCD012(14)';
NODE_NAME     U2D1 L50
 '@BASEBOARD_FAB2_LIB.BASEBOARD_FAB2(SCH_1):PAGE72_I32@CHPSET_LIB.SKX_EXT_B(CHIPS)':
 'VCCD012'<15>: CDS_PINID='VCCD012(15)';
NODE_NAME     U2D1 L52
 '@BASEBOARD_FAB2_LIB.BASEBOARD_FAB2(SCH_1):PAGE72_I32@CHPSET_LIB.SKX_EXT_B(CHIPS)':
 'VCCD012'<16>: CDS_PINID='VCCD012(16)';
NODE_NAME     U2D1 L54
 '@BASEBOARD_FAB2_LIB.BASEBOARD_FAB2(SCH_1):PAGE72_I32@CHPSET_LIB.SKX_EXT_B(CHIPS)':
 'VCCD012'<17>: CDS_PINID='VCCD012(17)';
NODE_NAME     U2D1 L56
 '@BASEBOARD_FAB2_LIB.BASEBOARD_FAB2(SCH_1):PAGE72_I32@CHPSET_LIB.SKX_EXT_B(CHIPS)':
 'VCCD012'<18>: CDS_PINID='VCCD012(18)';
NODE_NAME     U2D1 L58
 '@BASEBOARD_FAB2_LIB.BASEBOARD_FAB2(SCH_1):PAGE72_I32@CHPSET_LIB.SKX_EXT_B(CHIPS)':
 'VCCD012'<19>: CDS_PINID='VCCD012(19)';
NODE_NAME     U2D1 L60
 '@BASEBOARD_FAB2_LIB.BASEBOARD_FAB2(SCH_1):PAGE72_I32@CHPSET_LIB.SKX_EXT_B(CHIPS)':
 'VCCD012'<20>: CDS_PINID='VCCD012(20)';
NODE_NAME     U2D1 L62
 '@BASEBOARD_FAB2_LIB.BASEBOARD_FAB2(SCH_1):PAGE72_I32@CHPSET_LIB.SKX_EXT_B(CHIPS)':
 'VCCD012'<21>: CDS_PINID='VCCD012(21)';
NODE_NAME     U2D1 N64
 '@BASEBOARD_FAB2_LIB.BASEBOARD_FAB2(SCH_1):PAGE72_I32@CHPSET_LIB.SKX_EXT_B(CHIPS)':
 'VCCD012'<22>: CDS_PINID='VCCD012(22)';
NODE_NAME     U2D1 U46
 '@BASEBOARD_FAB2_LIB.BASEBOARD_FAB2(SCH_1):PAGE72_I32@CHPSET_LIB.SKX_EXT_B(CHIPS)':
 'VCCD012'<23>: CDS_PINID='VCCD012(23)';
NODE_NAME     U2D1 U48
 '@BASEBOARD_FAB2_LIB.BASEBOARD_FAB2(SCH_1):PAGE72_I32@CHPSET_LIB.SKX_EXT_B(CHIPS)':
 'VCCD012'<24>: CDS_PINID='VCCD012(24)';
NODE_NAME     U2D1 U50
 '@BASEBOARD_FAB2_LIB.BASEBOARD_FAB2(SCH_1):PAGE72_I32@CHPSET_LIB.SKX_EXT_B(CHIPS)':
 'VCCD012'<25>: CDS_PINID='VCCD012(25)';
NODE_NAME     U2D1 U52
 '@BASEBOARD_FAB2_LIB.BASEBOARD_FAB2(SCH_1):PAGE72_I32@CHPSET_LIB.SKX_EXT_B(CHIPS)':
 'VCCD012'<26>: CDS_PINID='VCCD012(26)';
NODE_NAME     U2D1 U54
 '@BASEBOARD_FAB2_LIB.BASEBOARD_FAB2(SCH_1):PAGE72_I32@CHPSET_LIB.SKX_EXT_B(CHIPS)':
 'VCCD012'<27>: CDS_PINID='VCCD012(27)';
NODE_NAME     U2D1 U56
 '@BASEBOARD_FAB2_LIB.BASEBOARD_FAB2(SCH_1):PAGE72_I32@CHPSET_LIB.SKX_EXT_B(CHIPS)':
 'VCCD012'<28>: CDS_PINID='VCCD012(28)';
NODE_NAME     U2D1 U58
 '@BASEBOARD_FAB2_LIB.BASEBOARD_FAB2(SCH_1):PAGE72_I32@CHPSET_LIB.SKX_EXT_B(CHIPS)':
 'VCCD012'<29>: CDS_PINID='VCCD012(29)';
NODE_NAME     U2D1 U60
 '@BASEBOARD_FAB2_LIB.BASEBOARD_FAB2(SCH_1):PAGE72_I32@CHPSET_LIB.SKX_EXT_B(CHIPS)':
 'VCCD012'<30>: CDS_PINID='VCCD012(30)';
NODE_NAME     U2D1 U62
 '@BASEBOARD_FAB2_LIB.BASEBOARD_FAB2(SCH_1):PAGE72_I32@CHPSET_LIB.SKX_EXT_B(CHIPS)':
 'VCCD012'<31>: CDS_PINID='VCCD012(31)';
NODE_NAME     U2D1 W64
 '@BASEBOARD_FAB2_LIB.BASEBOARD_FAB2(SCH_1):PAGE72_I32@CHPSET_LIB.SKX_EXT_B(CHIPS)':
 'VCCD012'<32>: CDS_PINID='VCCD012(32)';
NODE_NAME     U2D1 Y45
 '@BASEBOARD_FAB2_LIB.BASEBOARD_FAB2(SCH_1):PAGE72_I32@CHPSET_LIB.SKX_EXT_B(CHIPS)':
 'VCCD012'<33>: CDS_PINID='VCCD012(33)';
NODE_NAME     U2D1 Y47
 '@BASEBOARD_FAB2_LIB.BASEBOARD_FAB2(SCH_1):PAGE72_I32@CHPSET_LIB.SKX_EXT_B(CHIPS)':
 'VCCD012'<34>: CDS_PINID='VCCD012(34)';
NODE_NAME     U2D1 Y49
 '@BASEBOARD_FAB2_LIB.BASEBOARD_FAB2(SCH_1):PAGE72_I32@CHPSET_LIB.SKX_EXT_B(CHIPS)':
 'VCCD012'<35>: CDS_PINID='VCCD012(35)';
NODE_NAME     U2D1 Y51
 '@BASEBOARD_FAB2_LIB.BASEBOARD_FAB2(SCH_1):PAGE72_I32@CHPSET_LIB.SKX_EXT_B(CHIPS)':
 'VCCD012'<36>: CDS_PINID='VCCD012(36)';
NODE_NAME     U2D1 Y53
 '@BASEBOARD_FAB2_LIB.BASEBOARD_FAB2(SCH_1):PAGE72_I32@CHPSET_LIB.SKX_EXT_B(CHIPS)':
 'VCCD012'<37>: CDS_PINID='VCCD012(37)';
NODE_NAME     U2D1 Y55
 '@BASEBOARD_FAB2_LIB.BASEBOARD_FAB2(SCH_1):PAGE72_I32@CHPSET_LIB.SKX_EXT_B(CHIPS)':
 'VCCD012'<38>: CDS_PINID='VCCD012(38)';
NODE_NAME     U2D1 Y57
 '@BASEBOARD_FAB2_LIB.BASEBOARD_FAB2(SCH_1):PAGE72_I32@CHPSET_LIB.SKX_EXT_B(CHIPS)':
 'VCCD012'<39>: CDS_PINID='VCCD012(39)';
NODE_NAME     U2D1 Y59
 '@BASEBOARD_FAB2_LIB.BASEBOARD_FAB2(SCH_1):PAGE72_I32@CHPSET_LIB.SKX_EXT_B(CHIPS)':
 'VCCD012'<40>: CDS_PINID='VCCD012(40)';
NODE_NAME     U2D1 Y61
 '@BASEBOARD_FAB2_LIB.BASEBOARD_FAB2(SCH_1):PAGE72_I32@CHPSET_LIB.SKX_EXT_B(CHIPS)':
 'VCCD012'<41>: CDS_PINID='VCCD012(41)';
NODE_NAME     U2D1 Y63
 '@BASEBOARD_FAB2_LIB.BASEBOARD_FAB2(SCH_1):PAGE72_I32@CHPSET_LIB.SKX_EXT_B(CHIPS)':
 'VCCD012'<42>: CDS_PINID='VCCD012(42)';
NODE_NAME     U2D1 AD45
 '@BASEBOARD_FAB2_LIB.BASEBOARD_FAB2(SCH_1):PAGE72_I32@CHPSET_LIB.SKX_EXT_B(CHIPS)':
 'VCCD012'<43>: CDS_PINID='VCCD012(43)';
NODE_NAME     U2D1 AF55
 '@BASEBOARD_FAB2_LIB.BASEBOARD_FAB2(SCH_1):PAGE72_I32@CHPSET_LIB.SKX_EXT_B(CHIPS)':
 'VCCD012'<44>: CDS_PINID='VCCD012(44)';
NODE_NAME     U2D1 AF57
 '@BASEBOARD_FAB2_LIB.BASEBOARD_FAB2(SCH_1):PAGE72_I32@CHPSET_LIB.SKX_EXT_B(CHIPS)':
 'VCCD012'<45>: CDS_PINID='VCCD012(45)';
NODE_NAME     U2D1 AF59
 '@BASEBOARD_FAB2_LIB.BASEBOARD_FAB2(SCH_1):PAGE72_I32@CHPSET_LIB.SKX_EXT_B(CHIPS)':
 'VCCD012'<46>: CDS_PINID='VCCD012(46)';
NODE_NAME     U2D1 AF61
 '@BASEBOARD_FAB2_LIB.BASEBOARD_FAB2(SCH_1):PAGE72_I32@CHPSET_LIB.SKX_EXT_B(CHIPS)':
 'VCCD012'<47>: CDS_PINID='VCCD012(47)';
NODE_NAME     U2D1 AF63
 '@BASEBOARD_FAB2_LIB.BASEBOARD_FAB2(SCH_1):PAGE72_I32@CHPSET_LIB.SKX_EXT_B(CHIPS)':
 'VCCD012'<48>: CDS_PINID='VCCD012(48)';
NODE_NAME     U2D1 D45
 '@BASEBOARD_FAB2_LIB.BASEBOARD_FAB2(SCH_1):PAGE72_I32@CHPSET_LIB.SKX_EXT_B(CHIPS)':
 'VCCD012'<49>: CDS_PINID='VCCD012(49)';
NODE_NAME     U2D1 C46
 '@BASEBOARD_FAB2_LIB.BASEBOARD_FAB2(SCH_1):PAGE72_I32@CHPSET_LIB.SKX_EXT_B(CHIPS)':
 'VCCD012'<50>: CDS_PINID='VCCD012(50)';
NODE_NAME     U2D1 B47
 '@BASEBOARD_FAB2_LIB.BASEBOARD_FAB2(SCH_1):PAGE72_I32@CHPSET_LIB.SKX_EXT_B(CHIPS)':
 'VCCD012'<51>: CDS_PINID='VCCD012(51)';
NODE_NAME     J1G1 236
 '@BASEBOARD_FAB2_LIB.BASEBOARD_FAB2(SCH_1):PAGE77_I171@MSTR_SCONN.SCONN288_H44441004(CHIPS)':
 'VDD'<0>: CDS_PINID='VDD(0)';
NODE_NAME     J1G1 233
 '@BASEBOARD_FAB2_LIB.BASEBOARD_FAB2(SCH_1):PAGE77_I171@MSTR_SCONN.SCONN288_H44441004(CHIPS)':
 'VDD'<1>: CDS_PINID='VDD(1)';
NODE_NAME     J1G1 231
 '@BASEBOARD_FAB2_LIB.BASEBOARD_FAB2(SCH_1):PAGE77_I171@MSTR_SCONN.SCONN288_H44441004(CHIPS)':
 'VDD'<2>: CDS_PINID='VDD(2)';
NODE_NAME     J1G1 229
 '@BASEBOARD_FAB2_LIB.BASEBOARD_FAB2(SCH_1):PAGE77_I171@MSTR_SCONN.SCONN288_H44441004(CHIPS)':
 'VDD'<3>: CDS_PINID='VDD(3)';
NODE_NAME     J1G1 226
 '@BASEBOARD_FAB2_LIB.BASEBOARD_FAB2(SCH_1):PAGE77_I171@MSTR_SCONN.SCONN288_H44441004(CHIPS)':
 'VDD'<4>: CDS_PINID='VDD(4)';
NODE_NAME     J1G1 223
 '@BASEBOARD_FAB2_LIB.BASEBOARD_FAB2(SCH_1):PAGE77_I171@MSTR_SCONN.SCONN288_H44441004(CHIPS)':
 'VDD'<5>: CDS_PINID='VDD(5)';
NODE_NAME     J1G1 220
 '@BASEBOARD_FAB2_LIB.BASEBOARD_FAB2(SCH_1):PAGE77_I171@MSTR_SCONN.SCONN288_H44441004(CHIPS)':
 'VDD'<6>: CDS_PINID='VDD(6)';
NODE_NAME     J1G1 217
 '@BASEBOARD_FAB2_LIB.BASEBOARD_FAB2(SCH_1):PAGE77_I171@MSTR_SCONN.SCONN288_H44441004(CHIPS)':
 'VDD'<7>: CDS_PINID='VDD(7)';
NODE_NAME     J1G1 215
 '@BASEBOARD_FAB2_LIB.BASEBOARD_FAB2(SCH_1):PAGE77_I171@MSTR_SCONN.SCONN288_H44441004(CHIPS)':
 'VDD'<8>: CDS_PINID='VDD(8)';
NODE_NAME     J1G1 212
 '@BASEBOARD_FAB2_LIB.BASEBOARD_FAB2(SCH_1):PAGE77_I171@MSTR_SCONN.SCONN288_H44441004(CHIPS)':
 'VDD'<9>: CDS_PINID='VDD(9)';
NODE_NAME     J1G1 209
 '@BASEBOARD_FAB2_LIB.BASEBOARD_FAB2(SCH_1):PAGE77_I171@MSTR_SCONN.SCONN288_H44441004(CHIPS)':
 'VDD'<10>: CDS_PINID='VDD(10)';
NODE_NAME     J1G1 206
 '@BASEBOARD_FAB2_LIB.BASEBOARD_FAB2(SCH_1):PAGE77_I171@MSTR_SCONN.SCONN288_H44441004(CHIPS)':
 'VDD'<11>: CDS_PINID='VDD(11)';
NODE_NAME     J1G1 204
 '@BASEBOARD_FAB2_LIB.BASEBOARD_FAB2(SCH_1):PAGE77_I171@MSTR_SCONN.SCONN288_H44441004(CHIPS)':
 'VDD'<12>: CDS_PINID='VDD(12)';
NODE_NAME     J1G1 92
 '@BASEBOARD_FAB2_LIB.BASEBOARD_FAB2(SCH_1):PAGE77_I171@MSTR_SCONN.SCONN288_H44441004(CHIPS)':
 'VDD'<13>: CDS_PINID='VDD(13)';
NODE_NAME     J1G1 90
 '@BASEBOARD_FAB2_LIB.BASEBOARD_FAB2(SCH_1):PAGE77_I171@MSTR_SCONN.SCONN288_H44441004(CHIPS)':
 'VDD'<14>: CDS_PINID='VDD(14)';
NODE_NAME     J1G1 88
 '@BASEBOARD_FAB2_LIB.BASEBOARD_FAB2(SCH_1):PAGE77_I171@MSTR_SCONN.SCONN288_H44441004(CHIPS)':
 'VDD'<15>: CDS_PINID='VDD(15)';
NODE_NAME     J1G1 85
 '@BASEBOARD_FAB2_LIB.BASEBOARD_FAB2(SCH_1):PAGE77_I171@MSTR_SCONN.SCONN288_H44441004(CHIPS)':
 'VDD'<16>: CDS_PINID='VDD(16)';
NODE_NAME     J1G1 83
 '@BASEBOARD_FAB2_LIB.BASEBOARD_FAB2(SCH_1):PAGE77_I171@MSTR_SCONN.SCONN288_H44441004(CHIPS)':
 'VDD'<17>: CDS_PINID='VDD(17)';
NODE_NAME     J1G1 80
 '@BASEBOARD_FAB2_LIB.BASEBOARD_FAB2(SCH_1):PAGE77_I171@MSTR_SCONN.SCONN288_H44441004(CHIPS)':
 'VDD'<18>: CDS_PINID='VDD(18)';
NODE_NAME     J1G1 76
 '@BASEBOARD_FAB2_LIB.BASEBOARD_FAB2(SCH_1):PAGE77_I171@MSTR_SCONN.SCONN288_H44441004(CHIPS)':
 'VDD'<19>: CDS_PINID='VDD(19)';
NODE_NAME     J1G1 73
 '@BASEBOARD_FAB2_LIB.BASEBOARD_FAB2(SCH_1):PAGE77_I171@MSTR_SCONN.SCONN288_H44441004(CHIPS)':
 'VDD'<20>: CDS_PINID='VDD(20)';
NODE_NAME     J1G1 70
 '@BASEBOARD_FAB2_LIB.BASEBOARD_FAB2(SCH_1):PAGE77_I171@MSTR_SCONN.SCONN288_H44441004(CHIPS)':
 'VDD'<21>: CDS_PINID='VDD(21)';
NODE_NAME     J1G1 67
 '@BASEBOARD_FAB2_LIB.BASEBOARD_FAB2(SCH_1):PAGE77_I171@MSTR_SCONN.SCONN288_H44441004(CHIPS)':
 'VDD'<22>: CDS_PINID='VDD(22)';
NODE_NAME     J1G1 64
 '@BASEBOARD_FAB2_LIB.BASEBOARD_FAB2(SCH_1):PAGE77_I171@MSTR_SCONN.SCONN288_H44441004(CHIPS)':
 'VDD'<23>: CDS_PINID='VDD(23)';
NODE_NAME     J1G1 61
 '@BASEBOARD_FAB2_LIB.BASEBOARD_FAB2(SCH_1):PAGE77_I171@MSTR_SCONN.SCONN288_H44441004(CHIPS)':
 'VDD'<24>: CDS_PINID='VDD(24)';
NODE_NAME     J1G1 59
 '@BASEBOARD_FAB2_LIB.BASEBOARD_FAB2(SCH_1):PAGE77_I171@MSTR_SCONN.SCONN288_H44441004(CHIPS)':
 'VDD'<25>: CDS_PINID='VDD(25)';
NODE_NAME     J9T1 236
 '@BASEBOARD_FAB2_LIB.BASEBOARD_FAB2(SCH_1):PAGE78_I75@MSTR_SCONN.SCONN288_H44441003(CHIPS)':
 'VDD'<0>: CDS_PINID='VDD(0)';
NODE_NAME     J9T1 233
 '@BASEBOARD_FAB2_LIB.BASEBOARD_FAB2(SCH_1):PAGE78_I75@MSTR_SCONN.SCONN288_H44441003(CHIPS)':
 'VDD'<1>: CDS_PINID='VDD(1)';
NODE_NAME     J9T1 231
 '@BASEBOARD_FAB2_LIB.BASEBOARD_FAB2(SCH_1):PAGE78_I75@MSTR_SCONN.SCONN288_H44441003(CHIPS)':
 'VDD'<2>: CDS_PINID='VDD(2)';
NODE_NAME     J9T1 229
 '@BASEBOARD_FAB2_LIB.BASEBOARD_FAB2(SCH_1):PAGE78_I75@MSTR_SCONN.SCONN288_H44441003(CHIPS)':
 'VDD'<3>: CDS_PINID='VDD(3)';
NODE_NAME     J9T1 226
 '@BASEBOARD_FAB2_LIB.BASEBOARD_FAB2(SCH_1):PAGE78_I75@MSTR_SCONN.SCONN288_H44441003(CHIPS)':
 'VDD'<4>: CDS_PINID='VDD(4)';
NODE_NAME     J9T1 223
 '@BASEBOARD_FAB2_LIB.BASEBOARD_FAB2(SCH_1):PAGE78_I75@MSTR_SCONN.SCONN288_H44441003(CHIPS)':
 'VDD'<5>: CDS_PINID='VDD(5)';
NODE_NAME     J9T1 220
 '@BASEBOARD_FAB2_LIB.BASEBOARD_FAB2(SCH_1):PAGE78_I75@MSTR_SCONN.SCONN288_H44441003(CHIPS)':
 'VDD'<6>: CDS_PINID='VDD(6)';
NODE_NAME     J9T1 217
 '@BASEBOARD_FAB2_LIB.BASEBOARD_FAB2(SCH_1):PAGE78_I75@MSTR_SCONN.SCONN288_H44441003(CHIPS)':
 'VDD'<7>: CDS_PINID='VDD(7)';
NODE_NAME     J9T1 215
 '@BASEBOARD_FAB2_LIB.BASEBOARD_FAB2(SCH_1):PAGE78_I75@MSTR_SCONN.SCONN288_H44441003(CHIPS)':
 'VDD'<8>: CDS_PINID='VDD(8)';
NODE_NAME     J9T1 212
 '@BASEBOARD_FAB2_LIB.BASEBOARD_FAB2(SCH_1):PAGE78_I75@MSTR_SCONN.SCONN288_H44441003(CHIPS)':
 'VDD'<9>: CDS_PINID='VDD(9)';
NODE_NAME     J9T1 209
 '@BASEBOARD_FAB2_LIB.BASEBOARD_FAB2(SCH_1):PAGE78_I75@MSTR_SCONN.SCONN288_H44441003(CHIPS)':
 'VDD'<10>: CDS_PINID='VDD(10)';
NODE_NAME     J9T1 206
 '@BASEBOARD_FAB2_LIB.BASEBOARD_FAB2(SCH_1):PAGE78_I75@MSTR_SCONN.SCONN288_H44441003(CHIPS)':
 'VDD'<11>: CDS_PINID='VDD(11)';
NODE_NAME     J9T1 204
 '@BASEBOARD_FAB2_LIB.BASEBOARD_FAB2(SCH_1):PAGE78_I75@MSTR_SCONN.SCONN288_H44441003(CHIPS)':
 'VDD'<12>: CDS_PINID='VDD(12)';
NODE_NAME     J9T1 92
 '@BASEBOARD_FAB2_LIB.BASEBOARD_FAB2(SCH_1):PAGE78_I75@MSTR_SCONN.SCONN288_H44441003(CHIPS)':
 'VDD'<13>: CDS_PINID='VDD(13)';
NODE_NAME     J9T1 90
 '@BASEBOARD_FAB2_LIB.BASEBOARD_FAB2(SCH_1):PAGE78_I75@MSTR_SCONN.SCONN288_H44441003(CHIPS)':
 'VDD'<14>: CDS_PINID='VDD(14)';
NODE_NAME     J9T1 88
 '@BASEBOARD_FAB2_LIB.BASEBOARD_FAB2(SCH_1):PAGE78_I75@MSTR_SCONN.SCONN288_H44441003(CHIPS)':
 'VDD'<15>: CDS_PINID='VDD(15)';
NODE_NAME     J9T1 85
 '@BASEBOARD_FAB2_LIB.BASEBOARD_FAB2(SCH_1):PAGE78_I75@MSTR_SCONN.SCONN288_H44441003(CHIPS)':
 'VDD'<16>: CDS_PINID='VDD(16)';
NODE_NAME     J9T1 83
 '@BASEBOARD_FAB2_LIB.BASEBOARD_FAB2(SCH_1):PAGE78_I75@MSTR_SCONN.SCONN288_H44441003(CHIPS)':
 'VDD'<17>: CDS_PINID='VDD(17)';
NODE_NAME     J9T1 80
 '@BASEBOARD_FAB2_LIB.BASEBOARD_FAB2(SCH_1):PAGE78_I75@MSTR_SCONN.SCONN288_H44441003(CHIPS)':
 'VDD'<18>: CDS_PINID='VDD(18)';
NODE_NAME     J9T1 76
 '@BASEBOARD_FAB2_LIB.BASEBOARD_FAB2(SCH_1):PAGE78_I75@MSTR_SCONN.SCONN288_H44441003(CHIPS)':
 'VDD'<19>: CDS_PINID='VDD(19)';
NODE_NAME     J9T1 73
 '@BASEBOARD_FAB2_LIB.BASEBOARD_FAB2(SCH_1):PAGE78_I75@MSTR_SCONN.SCONN288_H44441003(CHIPS)':
 'VDD'<20>: CDS_PINID='VDD(20)';
NODE_NAME     J9T1 70
 '@BASEBOARD_FAB2_LIB.BASEBOARD_FAB2(SCH_1):PAGE78_I75@MSTR_SCONN.SCONN288_H44441003(CHIPS)':
 'VDD'<21>: CDS_PINID='VDD(21)';
NODE_NAME     J9T1 67
 '@BASEBOARD_FAB2_LIB.BASEBOARD_FAB2(SCH_1):PAGE78_I75@MSTR_SCONN.SCONN288_H44441003(CHIPS)':
 'VDD'<22>: CDS_PINID='VDD(22)';
NODE_NAME     J9T1 64
 '@BASEBOARD_FAB2_LIB.BASEBOARD_FAB2(SCH_1):PAGE78_I75@MSTR_SCONN.SCONN288_H44441003(CHIPS)':
 'VDD'<23>: CDS_PINID='VDD(23)';
NODE_NAME     J9T1 61
 '@BASEBOARD_FAB2_LIB.BASEBOARD_FAB2(SCH_1):PAGE78_I75@MSTR_SCONN.SCONN288_H44441003(CHIPS)':
 'VDD'<24>: CDS_PINID='VDD(24)';
NODE_NAME     J9T1 59
 '@BASEBOARD_FAB2_LIB.BASEBOARD_FAB2(SCH_1):PAGE78_I75@MSTR_SCONN.SCONN288_H44441003(CHIPS)':
 'VDD'<25>: CDS_PINID='VDD(25)';
NODE_NAME     J1G2 236
 '@BASEBOARD_FAB2_LIB.BASEBOARD_FAB2(SCH_1):PAGE79_I169@MSTR_SCONN.SCONN288_H44441004(CHIPS)':
 'VDD'<0>: CDS_PINID='VDD(0)';
NODE_NAME     J1G2 233
 '@BASEBOARD_FAB2_LIB.BASEBOARD_FAB2(SCH_1):PAGE79_I169@MSTR_SCONN.SCONN288_H44441004(CHIPS)':
 'VDD'<1>: CDS_PINID='VDD(1)';
NODE_NAME     J1G2 231
 '@BASEBOARD_FAB2_LIB.BASEBOARD_FAB2(SCH_1):PAGE79_I169@MSTR_SCONN.SCONN288_H44441004(CHIPS)':
 'VDD'<2>: CDS_PINID='VDD(2)';
NODE_NAME     J1G2 229
 '@BASEBOARD_FAB2_LIB.BASEBOARD_FAB2(SCH_1):PAGE79_I169@MSTR_SCONN.SCONN288_H44441004(CHIPS)':
 'VDD'<3>: CDS_PINID='VDD(3)';
NODE_NAME     J1G2 226
 '@BASEBOARD_FAB2_LIB.BASEBOARD_FAB2(SCH_1):PAGE79_I169@MSTR_SCONN.SCONN288_H44441004(CHIPS)':
 'VDD'<4>: CDS_PINID='VDD(4)';
NODE_NAME     J1G2 223
 '@BASEBOARD_FAB2_LIB.BASEBOARD_FAB2(SCH_1):PAGE79_I169@MSTR_SCONN.SCONN288_H44441004(CHIPS)':
 'VDD'<5>: CDS_PINID='VDD(5)';
NODE_NAME     J1G2 220
 '@BASEBOARD_FAB2_LIB.BASEBOARD_FAB2(SCH_1):PAGE79_I169@MSTR_SCONN.SCONN288_H44441004(CHIPS)':
 'VDD'<6>: CDS_PINID='VDD(6)';
NODE_NAME     J1G2 217
 '@BASEBOARD_FAB2_LIB.BASEBOARD_FAB2(SCH_1):PAGE79_I169@MSTR_SCONN.SCONN288_H44441004(CHIPS)':
 'VDD'<7>: CDS_PINID='VDD(7)';
NODE_NAME     J1G2 215
 '@BASEBOARD_FAB2_LIB.BASEBOARD_FAB2(SCH_1):PAGE79_I169@MSTR_SCONN.SCONN288_H44441004(CHIPS)':
 'VDD'<8>: CDS_PINID='VDD(8)';
NODE_NAME     J1G2 212
 '@BASEBOARD_FAB2_LIB.BASEBOARD_FAB2(SCH_1):PAGE79_I169@MSTR_SCONN.SCONN288_H44441004(CHIPS)':
 'VDD'<9>: CDS_PINID='VDD(9)';
NODE_NAME     J1G2 209
 '@BASEBOARD_FAB2_LIB.BASEBOARD_FAB2(SCH_1):PAGE79_I169@MSTR_SCONN.SCONN288_H44441004(CHIPS)':
 'VDD'<10>: CDS_PINID='VDD(10)';
NODE_NAME     J1G2 206
 '@BASEBOARD_FAB2_LIB.BASEBOARD_FAB2(SCH_1):PAGE79_I169@MSTR_SCONN.SCONN288_H44441004(CHIPS)':
 'VDD'<11>: CDS_PINID='VDD(11)';
NODE_NAME     J1G2 204
 '@BASEBOARD_FAB2_LIB.BASEBOARD_FAB2(SCH_1):PAGE79_I169@MSTR_SCONN.SCONN288_H44441004(CHIPS)':
 'VDD'<12>: CDS_PINID='VDD(12)';
NODE_NAME     J1G2 92
 '@BASEBOARD_FAB2_LIB.BASEBOARD_FAB2(SCH_1):PAGE79_I169@MSTR_SCONN.SCONN288_H44441004(CHIPS)':
 'VDD'<13>: CDS_PINID='VDD(13)';
NODE_NAME     J1G2 90
 '@BASEBOARD_FAB2_LIB.BASEBOARD_FAB2(SCH_1):PAGE79_I169@MSTR_SCONN.SCONN288_H44441004(CHIPS)':
 'VDD'<14>: CDS_PINID='VDD(14)';
NODE_NAME     J1G2 88
 '@BASEBOARD_FAB2_LIB.BASEBOARD_FAB2(SCH_1):PAGE79_I169@MSTR_SCONN.SCONN288_H44441004(CHIPS)':
 'VDD'<15>: CDS_PINID='VDD(15)';
NODE_NAME     J1G2 85
 '@BASEBOARD_FAB2_LIB.BASEBOARD_FAB2(SCH_1):PAGE79_I169@MSTR_SCONN.SCONN288_H44441004(CHIPS)':
 'VDD'<16>: CDS_PINID='VDD(16)';
NODE_NAME     J1G2 83
 '@BASEBOARD_FAB2_LIB.BASEBOARD_FAB2(SCH_1):PAGE79_I169@MSTR_SCONN.SCONN288_H44441004(CHIPS)':
 'VDD'<17>: CDS_PINID='VDD(17)';
NODE_NAME     J1G2 80
 '@BASEBOARD_FAB2_LIB.BASEBOARD_FAB2(SCH_1):PAGE79_I169@MSTR_SCONN.SCONN288_H44441004(CHIPS)':
 'VDD'<18>: CDS_PINID='VDD(18)';
NODE_NAME     J1G2 76
 '@BASEBOARD_FAB2_LIB.BASEBOARD_FAB2(SCH_1):PAGE79_I169@MSTR_SCONN.SCONN288_H44441004(CHIPS)':
 'VDD'<19>: CDS_PINID='VDD(19)';
NODE_NAME     J1G2 73
 '@BASEBOARD_FAB2_LIB.BASEBOARD_FAB2(SCH_1):PAGE79_I169@MSTR_SCONN.SCONN288_H44441004(CHIPS)':
 'VDD'<20>: CDS_PINID='VDD(20)';
NODE_NAME     J1G2 70
 '@BASEBOARD_FAB2_LIB.BASEBOARD_FAB2(SCH_1):PAGE79_I169@MSTR_SCONN.SCONN288_H44441004(CHIPS)':
 'VDD'<21>: CDS_PINID='VDD(21)';
NODE_NAME     J1G2 67
 '@BASEBOARD_FAB2_LIB.BASEBOARD_FAB2(SCH_1):PAGE79_I169@MSTR_SCONN.SCONN288_H44441004(CHIPS)':
 'VDD'<22>: CDS_PINID='VDD(22)';
NODE_NAME     J1G2 64
 '@BASEBOARD_FAB2_LIB.BASEBOARD_FAB2(SCH_1):PAGE79_I169@MSTR_SCONN.SCONN288_H44441004(CHIPS)':
 'VDD'<23>: CDS_PINID='VDD(23)';
NODE_NAME     J1G2 61
 '@BASEBOARD_FAB2_LIB.BASEBOARD_FAB2(SCH_1):PAGE79_I169@MSTR_SCONN.SCONN288_H44441004(CHIPS)':
 'VDD'<24>: CDS_PINID='VDD(24)';
NODE_NAME     J1G2 59
 '@BASEBOARD_FAB2_LIB.BASEBOARD_FAB2(SCH_1):PAGE79_I169@MSTR_SCONN.SCONN288_H44441004(CHIPS)':
 'VDD'<25>: CDS_PINID='VDD(25)';
NODE_NAME     J9U1 236
 '@BASEBOARD_FAB2_LIB.BASEBOARD_FAB2(SCH_1):PAGE80_I56@MSTR_SCONN.SCONN288_H44441003(CHIPS)':
 'VDD'<0>: CDS_PINID='VDD(0)';
NODE_NAME     J9U1 233
 '@BASEBOARD_FAB2_LIB.BASEBOARD_FAB2(SCH_1):PAGE80_I56@MSTR_SCONN.SCONN288_H44441003(CHIPS)':
 'VDD'<1>: CDS_PINID='VDD(1)';
NODE_NAME     J9U1 231
 '@BASEBOARD_FAB2_LIB.BASEBOARD_FAB2(SCH_1):PAGE80_I56@MSTR_SCONN.SCONN288_H44441003(CHIPS)':
 'VDD'<2>: CDS_PINID='VDD(2)';
NODE_NAME     J9U1 229
 '@BASEBOARD_FAB2_LIB.BASEBOARD_FAB2(SCH_1):PAGE80_I56@MSTR_SCONN.SCONN288_H44441003(CHIPS)':
 'VDD'<3>: CDS_PINID='VDD(3)';
NODE_NAME     J9U1 226
 '@BASEBOARD_FAB2_LIB.BASEBOARD_FAB2(SCH_1):PAGE80_I56@MSTR_SCONN.SCONN288_H44441003(CHIPS)':
 'VDD'<4>: CDS_PINID='VDD(4)';
NODE_NAME     J9U1 223
 '@BASEBOARD_FAB2_LIB.BASEBOARD_FAB2(SCH_1):PAGE80_I56@MSTR_SCONN.SCONN288_H44441003(CHIPS)':
 'VDD'<5>: CDS_PINID='VDD(5)';
NODE_NAME     J9U1 220
 '@BASEBOARD_FAB2_LIB.BASEBOARD_FAB2(SCH_1):PAGE80_I56@MSTR_SCONN.SCONN288_H44441003(CHIPS)':
 'VDD'<6>: CDS_PINID='VDD(6)';
NODE_NAME     J9U1 217
 '@BASEBOARD_FAB2_LIB.BASEBOARD_FAB2(SCH_1):PAGE80_I56@MSTR_SCONN.SCONN288_H44441003(CHIPS)':
 'VDD'<7>: CDS_PINID='VDD(7)';
NODE_NAME     J9U1 215
 '@BASEBOARD_FAB2_LIB.BASEBOARD_FAB2(SCH_1):PAGE80_I56@MSTR_SCONN.SCONN288_H44441003(CHIPS)':
 'VDD'<8>: CDS_PINID='VDD(8)';
NODE_NAME     J9U1 212
 '@BASEBOARD_FAB2_LIB.BASEBOARD_FAB2(SCH_1):PAGE80_I56@MSTR_SCONN.SCONN288_H44441003(CHIPS)':
 'VDD'<9>: CDS_PINID='VDD(9)';
NODE_NAME     J9U1 209
 '@BASEBOARD_FAB2_LIB.BASEBOARD_FAB2(SCH_1):PAGE80_I56@MSTR_SCONN.SCONN288_H44441003(CHIPS)':
 'VDD'<10>: CDS_PINID='VDD(10)';
NODE_NAME     J9U1 206
 '@BASEBOARD_FAB2_LIB.BASEBOARD_FAB2(SCH_1):PAGE80_I56@MSTR_SCONN.SCONN288_H44441003(CHIPS)':
 'VDD'<11>: CDS_PINID='VDD(11)';
NODE_NAME     J9U1 204
 '@BASEBOARD_FAB2_LIB.BASEBOARD_FAB2(SCH_1):PAGE80_I56@MSTR_SCONN.SCONN288_H44441003(CHIPS)':
 'VDD'<12>: CDS_PINID='VDD(12)';
NODE_NAME     J9U1 92
 '@BASEBOARD_FAB2_LIB.BASEBOARD_FAB2(SCH_1):PAGE80_I56@MSTR_SCONN.SCONN288_H44441003(CHIPS)':
 'VDD'<13>: CDS_PINID='VDD(13)';
NODE_NAME     J9U1 90
 '@BASEBOARD_FAB2_LIB.BASEBOARD_FAB2(SCH_1):PAGE80_I56@MSTR_SCONN.SCONN288_H44441003(CHIPS)':
 'VDD'<14>: CDS_PINID='VDD(14)';
NODE_NAME     J9U1 88
 '@BASEBOARD_FAB2_LIB.BASEBOARD_FAB2(SCH_1):PAGE80_I56@MSTR_SCONN.SCONN288_H44441003(CHIPS)':
 'VDD'<15>: CDS_PINID='VDD(15)';
NODE_NAME     J9U1 85
 '@BASEBOARD_FAB2_LIB.BASEBOARD_FAB2(SCH_1):PAGE80_I56@MSTR_SCONN.SCONN288_H44441003(CHIPS)':
 'VDD'<16>: CDS_PINID='VDD(16)';
NODE_NAME     J9U1 83
 '@BASEBOARD_FAB2_LIB.BASEBOARD_FAB2(SCH_1):PAGE80_I56@MSTR_SCONN.SCONN288_H44441003(CHIPS)':
 'VDD'<17>: CDS_PINID='VDD(17)';
NODE_NAME     J9U1 80
 '@BASEBOARD_FAB2_LIB.BASEBOARD_FAB2(SCH_1):PAGE80_I56@MSTR_SCONN.SCONN288_H44441003(CHIPS)':
 'VDD'<18>: CDS_PINID='VDD(18)';
NODE_NAME     J9U1 76
 '@BASEBOARD_FAB2_LIB.BASEBOARD_FAB2(SCH_1):PAGE80_I56@MSTR_SCONN.SCONN288_H44441003(CHIPS)':
 'VDD'<19>: CDS_PINID='VDD(19)';
NODE_NAME     J9U1 73
 '@BASEBOARD_FAB2_LIB.BASEBOARD_FAB2(SCH_1):PAGE80_I56@MSTR_SCONN.SCONN288_H44441003(CHIPS)':
 'VDD'<20>: CDS_PINID='VDD(20)';
NODE_NAME     J9U1 70
 '@BASEBOARD_FAB2_LIB.BASEBOARD_FAB2(SCH_1):PAGE80_I56@MSTR_SCONN.SCONN288_H44441003(CHIPS)':
 'VDD'<21>: CDS_PINID='VDD(21)';
NODE_NAME     J9U1 67
 '@BASEBOARD_FAB2_LIB.BASEBOARD_FAB2(SCH_1):PAGE80_I56@MSTR_SCONN.SCONN288_H44441003(CHIPS)':
 'VDD'<22>: CDS_PINID='VDD(22)';
NODE_NAME     J9U1 64
 '@BASEBOARD_FAB2_LIB.BASEBOARD_FAB2(SCH_1):PAGE80_I56@MSTR_SCONN.SCONN288_H44441003(CHIPS)':
 'VDD'<23>: CDS_PINID='VDD(23)';
NODE_NAME     J9U1 61
 '@BASEBOARD_FAB2_LIB.BASEBOARD_FAB2(SCH_1):PAGE80_I56@MSTR_SCONN.SCONN288_H44441003(CHIPS)':
 'VDD'<24>: CDS_PINID='VDD(24)';
NODE_NAME     J9U1 59
 '@BASEBOARD_FAB2_LIB.BASEBOARD_FAB2(SCH_1):PAGE80_I56@MSTR_SCONN.SCONN288_H44441003(CHIPS)':
 'VDD'<25>: CDS_PINID='VDD(25)';
NODE_NAME     J1G3 236
 '@BASEBOARD_FAB2_LIB.BASEBOARD_FAB2(SCH_1):PAGE81_I169@MSTR_SCONN.SCONN288_H44441004(CHIPS)':
 'VDD'<0>: CDS_PINID='VDD(0)';
NODE_NAME     J1G3 233
 '@BASEBOARD_FAB2_LIB.BASEBOARD_FAB2(SCH_1):PAGE81_I169@MSTR_SCONN.SCONN288_H44441004(CHIPS)':
 'VDD'<1>: CDS_PINID='VDD(1)';
NODE_NAME     J1G3 231
 '@BASEBOARD_FAB2_LIB.BASEBOARD_FAB2(SCH_1):PAGE81_I169@MSTR_SCONN.SCONN288_H44441004(CHIPS)':
 'VDD'<2>: CDS_PINID='VDD(2)';
NODE_NAME     J1G3 229
 '@BASEBOARD_FAB2_LIB.BASEBOARD_FAB2(SCH_1):PAGE81_I169@MSTR_SCONN.SCONN288_H44441004(CHIPS)':
 'VDD'<3>: CDS_PINID='VDD(3)';
NODE_NAME     J1G3 226
 '@BASEBOARD_FAB2_LIB.BASEBOARD_FAB2(SCH_1):PAGE81_I169@MSTR_SCONN.SCONN288_H44441004(CHIPS)':
 'VDD'<4>: CDS_PINID='VDD(4)';
NODE_NAME     J1G3 223
 '@BASEBOARD_FAB2_LIB.BASEBOARD_FAB2(SCH_1):PAGE81_I169@MSTR_SCONN.SCONN288_H44441004(CHIPS)':
 'VDD'<5>: CDS_PINID='VDD(5)';
NODE_NAME     J1G3 220
 '@BASEBOARD_FAB2_LIB.BASEBOARD_FAB2(SCH_1):PAGE81_I169@MSTR_SCONN.SCONN288_H44441004(CHIPS)':
 'VDD'<6>: CDS_PINID='VDD(6)';
NODE_NAME     J1G3 217
 '@BASEBOARD_FAB2_LIB.BASEBOARD_FAB2(SCH_1):PAGE81_I169@MSTR_SCONN.SCONN288_H44441004(CHIPS)':
 'VDD'<7>: CDS_PINID='VDD(7)';
NODE_NAME     J1G3 215
 '@BASEBOARD_FAB2_LIB.BASEBOARD_FAB2(SCH_1):PAGE81_I169@MSTR_SCONN.SCONN288_H44441004(CHIPS)':
 'VDD'<8>: CDS_PINID='VDD(8)';
NODE_NAME     J1G3 212
 '@BASEBOARD_FAB2_LIB.BASEBOARD_FAB2(SCH_1):PAGE81_I169@MSTR_SCONN.SCONN288_H44441004(CHIPS)':
 'VDD'<9>: CDS_PINID='VDD(9)';
NODE_NAME     J1G3 209
 '@BASEBOARD_FAB2_LIB.BASEBOARD_FAB2(SCH_1):PAGE81_I169@MSTR_SCONN.SCONN288_H44441004(CHIPS)':
 'VDD'<10>: CDS_PINID='VDD(10)';
NODE_NAME     J1G3 206
 '@BASEBOARD_FAB2_LIB.BASEBOARD_FAB2(SCH_1):PAGE81_I169@MSTR_SCONN.SCONN288_H44441004(CHIPS)':
 'VDD'<11>: CDS_PINID='VDD(11)';
NODE_NAME     J1G3 204
 '@BASEBOARD_FAB2_LIB.BASEBOARD_FAB2(SCH_1):PAGE81_I169@MSTR_SCONN.SCONN288_H44441004(CHIPS)':
 'VDD'<12>: CDS_PINID='VDD(12)';
NODE_NAME     J1G3 92
 '@BASEBOARD_FAB2_LIB.BASEBOARD_FAB2(SCH_1):PAGE81_I169@MSTR_SCONN.SCONN288_H44441004(CHIPS)':
 'VDD'<13>: CDS_PINID='VDD(13)';
NODE_NAME     J1G3 90
 '@BASEBOARD_FAB2_LIB.BASEBOARD_FAB2(SCH_1):PAGE81_I169@MSTR_SCONN.SCONN288_H44441004(CHIPS)':
 'VDD'<14>: CDS_PINID='VDD(14)';
NODE_NAME     J1G3 88
 '@BASEBOARD_FAB2_LIB.BASEBOARD_FAB2(SCH_1):PAGE81_I169@MSTR_SCONN.SCONN288_H44441004(CHIPS)':
 'VDD'<15>: CDS_PINID='VDD(15)';
NODE_NAME     J1G3 85
 '@BASEBOARD_FAB2_LIB.BASEBOARD_FAB2(SCH_1):PAGE81_I169@MSTR_SCONN.SCONN288_H44441004(CHIPS)':
 'VDD'<16>: CDS_PINID='VDD(16)';
NODE_NAME     J1G3 83
 '@BASEBOARD_FAB2_LIB.BASEBOARD_FAB2(SCH_1):PAGE81_I169@MSTR_SCONN.SCONN288_H44441004(CHIPS)':
 'VDD'<17>: CDS_PINID='VDD(17)';
NODE_NAME     J1G3 80
 '@BASEBOARD_FAB2_LIB.BASEBOARD_FAB2(SCH_1):PAGE81_I169@MSTR_SCONN.SCONN288_H44441004(CHIPS)':
 'VDD'<18>: CDS_PINID='VDD(18)';
NODE_NAME     J1G3 76
 '@BASEBOARD_FAB2_LIB.BASEBOARD_FAB2(SCH_1):PAGE81_I169@MSTR_SCONN.SCONN288_H44441004(CHIPS)':
 'VDD'<19>: CDS_PINID='VDD(19)';
NODE_NAME     J1G3 73
 '@BASEBOARD_FAB2_LIB.BASEBOARD_FAB2(SCH_1):PAGE81_I169@MSTR_SCONN.SCONN288_H44441004(CHIPS)':
 'VDD'<20>: CDS_PINID='VDD(20)';
NODE_NAME     J1G3 70
 '@BASEBOARD_FAB2_LIB.BASEBOARD_FAB2(SCH_1):PAGE81_I169@MSTR_SCONN.SCONN288_H44441004(CHIPS)':
 'VDD'<21>: CDS_PINID='VDD(21)';
NODE_NAME     J1G3 67
 '@BASEBOARD_FAB2_LIB.BASEBOARD_FAB2(SCH_1):PAGE81_I169@MSTR_SCONN.SCONN288_H44441004(CHIPS)':
 'VDD'<22>: CDS_PINID='VDD(22)';
NODE_NAME     J1G3 64
 '@BASEBOARD_FAB2_LIB.BASEBOARD_FAB2(SCH_1):PAGE81_I169@MSTR_SCONN.SCONN288_H44441004(CHIPS)':
 'VDD'<23>: CDS_PINID='VDD(23)';
NODE_NAME     J1G3 61
 '@BASEBOARD_FAB2_LIB.BASEBOARD_FAB2(SCH_1):PAGE81_I169@MSTR_SCONN.SCONN288_H44441004(CHIPS)':
 'VDD'<24>: CDS_PINID='VDD(24)';
NODE_NAME     J1G3 59
 '@BASEBOARD_FAB2_LIB.BASEBOARD_FAB2(SCH_1):PAGE81_I169@MSTR_SCONN.SCONN288_H44441004(CHIPS)':
 'VDD'<25>: CDS_PINID='VDD(25)';
NODE_NAME     J9U2 236
 '@BASEBOARD_FAB2_LIB.BASEBOARD_FAB2(SCH_1):PAGE82_I171@MSTR_SCONN.SCONN288_H44441003(CHIPS)':
 'VDD'<0>: CDS_PINID='VDD(0)';
NODE_NAME     J9U2 233
 '@BASEBOARD_FAB2_LIB.BASEBOARD_FAB2(SCH_1):PAGE82_I171@MSTR_SCONN.SCONN288_H44441003(CHIPS)':
 'VDD'<1>: CDS_PINID='VDD(1)';
NODE_NAME     J9U2 231
 '@BASEBOARD_FAB2_LIB.BASEBOARD_FAB2(SCH_1):PAGE82_I171@MSTR_SCONN.SCONN288_H44441003(CHIPS)':
 'VDD'<2>: CDS_PINID='VDD(2)';
NODE_NAME     J9U2 229
 '@BASEBOARD_FAB2_LIB.BASEBOARD_FAB2(SCH_1):PAGE82_I171@MSTR_SCONN.SCONN288_H44441003(CHIPS)':
 'VDD'<3>: CDS_PINID='VDD(3)';
NODE_NAME     J9U2 226
 '@BASEBOARD_FAB2_LIB.BASEBOARD_FAB2(SCH_1):PAGE82_I171@MSTR_SCONN.SCONN288_H44441003(CHIPS)':
 'VDD'<4>: CDS_PINID='VDD(4)';
NODE_NAME     J9U2 223
 '@BASEBOARD_FAB2_LIB.BASEBOARD_FAB2(SCH_1):PAGE82_I171@MSTR_SCONN.SCONN288_H44441003(CHIPS)':
 'VDD'<5>: CDS_PINID='VDD(5)';
NODE_NAME     J9U2 220
 '@BASEBOARD_FAB2_LIB.BASEBOARD_FAB2(SCH_1):PAGE82_I171@MSTR_SCONN.SCONN288_H44441003(CHIPS)':
 'VDD'<6>: CDS_PINID='VDD(6)';
NODE_NAME     J9U2 217
 '@BASEBOARD_FAB2_LIB.BASEBOARD_FAB2(SCH_1):PAGE82_I171@MSTR_SCONN.SCONN288_H44441003(CHIPS)':
 'VDD'<7>: CDS_PINID='VDD(7)';
NODE_NAME     J9U2 215
 '@BASEBOARD_FAB2_LIB.BASEBOARD_FAB2(SCH_1):PAGE82_I171@MSTR_SCONN.SCONN288_H44441003(CHIPS)':
 'VDD'<8>: CDS_PINID='VDD(8)';
NODE_NAME     J9U2 212
 '@BASEBOARD_FAB2_LIB.BASEBOARD_FAB2(SCH_1):PAGE82_I171@MSTR_SCONN.SCONN288_H44441003(CHIPS)':
 'VDD'<9>: CDS_PINID='VDD(9)';
NODE_NAME     J9U2 209
 '@BASEBOARD_FAB2_LIB.BASEBOARD_FAB2(SCH_1):PAGE82_I171@MSTR_SCONN.SCONN288_H44441003(CHIPS)':
 'VDD'<10>: CDS_PINID='VDD(10)';
NODE_NAME     J9U2 206
 '@BASEBOARD_FAB2_LIB.BASEBOARD_FAB2(SCH_1):PAGE82_I171@MSTR_SCONN.SCONN288_H44441003(CHIPS)':
 'VDD'<11>: CDS_PINID='VDD(11)';
NODE_NAME     J9U2 204
 '@BASEBOARD_FAB2_LIB.BASEBOARD_FAB2(SCH_1):PAGE82_I171@MSTR_SCONN.SCONN288_H44441003(CHIPS)':
 'VDD'<12>: CDS_PINID='VDD(12)';
NODE_NAME     J9U2 92
 '@BASEBOARD_FAB2_LIB.BASEBOARD_FAB2(SCH_1):PAGE82_I171@MSTR_SCONN.SCONN288_H44441003(CHIPS)':
 'VDD'<13>: CDS_PINID='VDD(13)';
NODE_NAME     J9U2 90
 '@BASEBOARD_FAB2_LIB.BASEBOARD_FAB2(SCH_1):PAGE82_I171@MSTR_SCONN.SCONN288_H44441003(CHIPS)':
 'VDD'<14>: CDS_PINID='VDD(14)';
NODE_NAME     J9U2 88
 '@BASEBOARD_FAB2_LIB.BASEBOARD_FAB2(SCH_1):PAGE82_I171@MSTR_SCONN.SCONN288_H44441003(CHIPS)':
 'VDD'<15>: CDS_PINID='VDD(15)';
NODE_NAME     J9U2 85
 '@BASEBOARD_FAB2_LIB.BASEBOARD_FAB2(SCH_1):PAGE82_I171@MSTR_SCONN.SCONN288_H44441003(CHIPS)':
 'VDD'<16>: CDS_PINID='VDD(16)';
NODE_NAME     J9U2 83
 '@BASEBOARD_FAB2_LIB.BASEBOARD_FAB2(SCH_1):PAGE82_I171@MSTR_SCONN.SCONN288_H44441003(CHIPS)':
 'VDD'<17>: CDS_PINID='VDD(17)';
NODE_NAME     J9U2 80
 '@BASEBOARD_FAB2_LIB.BASEBOARD_FAB2(SCH_1):PAGE82_I171@MSTR_SCONN.SCONN288_H44441003(CHIPS)':
 'VDD'<18>: CDS_PINID='VDD(18)';
NODE_NAME     J9U2 76
 '@BASEBOARD_FAB2_LIB.BASEBOARD_FAB2(SCH_1):PAGE82_I171@MSTR_SCONN.SCONN288_H44441003(CHIPS)':
 'VDD'<19>: CDS_PINID='VDD(19)';
NODE_NAME     J9U2 73
 '@BASEBOARD_FAB2_LIB.BASEBOARD_FAB2(SCH_1):PAGE82_I171@MSTR_SCONN.SCONN288_H44441003(CHIPS)':
 'VDD'<20>: CDS_PINID='VDD(20)';
NODE_NAME     J9U2 70
 '@BASEBOARD_FAB2_LIB.BASEBOARD_FAB2(SCH_1):PAGE82_I171@MSTR_SCONN.SCONN288_H44441003(CHIPS)':
 'VDD'<21>: CDS_PINID='VDD(21)';
NODE_NAME     J9U2 67
 '@BASEBOARD_FAB2_LIB.BASEBOARD_FAB2(SCH_1):PAGE82_I171@MSTR_SCONN.SCONN288_H44441003(CHIPS)':
 'VDD'<22>: CDS_PINID='VDD(22)';
NODE_NAME     J9U2 64
 '@BASEBOARD_FAB2_LIB.BASEBOARD_FAB2(SCH_1):PAGE82_I171@MSTR_SCONN.SCONN288_H44441003(CHIPS)':
 'VDD'<23>: CDS_PINID='VDD(23)';
NODE_NAME     J9U2 61
 '@BASEBOARD_FAB2_LIB.BASEBOARD_FAB2(SCH_1):PAGE82_I171@MSTR_SCONN.SCONN288_H44441003(CHIPS)':
 'VDD'<24>: CDS_PINID='VDD(24)';
NODE_NAME     J9U2 59
 '@BASEBOARD_FAB2_LIB.BASEBOARD_FAB2(SCH_1):PAGE82_I171@MSTR_SCONN.SCONN288_H44441003(CHIPS)':
 'VDD'<25>: CDS_PINID='VDD(25)';
NODE_NAME     R3D21 1
 '@BASEBOARD_FAB2_LIB.BASEBOARD_FAB2(SCH_1):PAGE96_I30@MSTR_DISCRETE.RES(CHIPS)':
 'A': CDS_PINID='A';
NODE_NAME     R1F5 1
 '@BASEBOARD_FAB2_LIB.BASEBOARD_FAB2(SCH_1):PAGE100_I6@MSTR_DISCRETE.RES(CHIPS)':
 'A': CDS_PINID='A';
NODE_NAME     R1G2 1
 '@BASEBOARD_FAB2_LIB.BASEBOARD_FAB2(SCH_1):PAGE100_I19@MSTR_DISCRETE.RES(CHIPS)':
 'A': CDS_PINID='A';
NODE_NAME     R1G15 1
 '@BASEBOARD_FAB2_LIB.BASEBOARD_FAB2(SCH_1):PAGE100_I35@MSTR_DISCRETE.RES(CHIPS)':
 'A': CDS_PINID='A';
NODE_NAME     C1G17 1
 '@BASEBOARD_FAB2_LIB.BASEBOARD_FAB2(SCH_1):PAGE224_I6@MSTR_DISCRETE.CAP(CHIPS)':
 'A': CDS_PINID='A';
NODE_NAME     C1G20 1
 '@BASEBOARD_FAB2_LIB.BASEBOARD_FAB2(SCH_1):PAGE224_I68@MSTR_DISCRETE.CAP(CHIPS)':
 'A': CDS_PINID='A';
NODE_NAME     EU1G1 1
 '@BASEBOARD_FAB2_LIB.BASEBOARD_FAB2(SCH_1):PAGE224_I110@MSTR_DISCRETE.IR354XX(CHIPS)':
 'VOS': CDS_PINID='VOS';
NODE_NAME     EU1F1 1
 '@BASEBOARD_FAB2_LIB.BASEBOARD_FAB2(SCH_1):PAGE224_I111@MSTR_DISCRETE.IR354XX(CHIPS)':
 'VOS': CDS_PINID='VOS';
NODE_NAME     R1G20 1
 '@BASEBOARD_FAB2_LIB.BASEBOARD_FAB2(SCH_1):PAGE225_I58@MSTR_DISCRETE.RES(CHIPS)':
 'A': CDS_PINID='A';
NODE_NAME     C9T5 1
 '@BASEBOARD_FAB2_LIB.BASEBOARD_FAB2(SCH_1):PAGE225_I75@MSTR_DISCRETE.CAPP(CHIPS)':
 'A': CDS_PINID='A';
NODE_NAME     C9U2 1
 '@BASEBOARD_FAB2_LIB.BASEBOARD_FAB2(SCH_1):PAGE225_I76@MSTR_DISCRETE.CAPP(CHIPS)':
 'A': CDS_PINID='A';
NODE_NAME     C9U9 1
 '@BASEBOARD_FAB2_LIB.BASEBOARD_FAB2(SCH_1):PAGE225_I77@MSTR_DISCRETE.CAPP(CHIPS)':
 'A': CDS_PINID='A';
NODE_NAME     C9U5 1
 '@BASEBOARD_FAB2_LIB.BASEBOARD_FAB2(SCH_1):PAGE225_I78@MSTR_DISCRETE.CAPP(CHIPS)':
 'A': CDS_PINID='A';
NODE_NAME     C8T4 1
 '@BASEBOARD_FAB2_LIB.BASEBOARD_FAB2(SCH_1):PAGE225_I196@DEV_DISCRETE.CAP_A(CHIPS)':
 'A': CDS_PINID='A';
NODE_NAME     C2G8 1
 '@BASEBOARD_FAB2_LIB.BASEBOARD_FAB2(SCH_1):PAGE225_I197@DEV_DISCRETE.CAP_A(CHIPS)':
 'A': CDS_PINID='A';
NODE_NAME     C8T2 1
 '@BASEBOARD_FAB2_LIB.BASEBOARD_FAB2(SCH_1):PAGE225_I198@DEV_DISCRETE.CAP_A(CHIPS)':
 'A': CDS_PINID='A';
NODE_NAME     C8U13 1
 '@BASEBOARD_FAB2_LIB.BASEBOARD_FAB2(SCH_1):PAGE225_I199@DEV_DISCRETE.CAP_A(CHIPS)':
 'A': CDS_PINID='A';
NODE_NAME     C2G15 1
 '@BASEBOARD_FAB2_LIB.BASEBOARD_FAB2(SCH_1):PAGE225_I200@DEV_DISCRETE.CAP_A(CHIPS)':
 'A': CDS_PINID='A';
NODE_NAME     C2F1 1
 '@BASEBOARD_FAB2_LIB.BASEBOARD_FAB2(SCH_1):PAGE225_I201@DEV_DISCRETE.CAP_A(CHIPS)':
 'A': CDS_PINID='A';
NODE_NAME     C8T1 1
 '@BASEBOARD_FAB2_LIB.BASEBOARD_FAB2(SCH_1):PAGE225_I202@DEV_DISCRETE.CAP_A(CHIPS)':
 'A': CDS_PINID='A';
NODE_NAME     C8U9 1
 '@BASEBOARD_FAB2_LIB.BASEBOARD_FAB2(SCH_1):PAGE225_I203@DEV_DISCRETE.CAP_A(CHIPS)':
 'A': CDS_PINID='A';
NODE_NAME     C8T11 1
 '@BASEBOARD_FAB2_LIB.BASEBOARD_FAB2(SCH_1):PAGE225_I204@DEV_DISCRETE.CAP_A(CHIPS)':
 'A': CDS_PINID='A';
NODE_NAME     SH7U1 2
 '@BASEBOARD_FAB2_LIB.BASEBOARD_FAB2(SCH_1):PAGE225_I243@MSTR_MISC.SHUNT(CHIPS)':
 'B':NET_SHORT='VSENSE_PVDDQ_GHJ_P:PVDDQ_GHJ',
 CDS_PINID='B';
NODE_NAME     C5G79 1
 '@BASEBOARD_FAB2_LIB.BASEBOARD_FAB2(SCH_1):PAGE243_I53@DEV_DISCRETE.CAP_A(CHIPS)':
 'A': CDS_PINID='A';
NODE_NAME     C5G87 1
 '@BASEBOARD_FAB2_LIB.BASEBOARD_FAB2(SCH_1):PAGE243_I54@DEV_DISCRETE.CAP_A(CHIPS)':
 'A': CDS_PINID='A';
NODE_NAME     C5G86 1
 '@BASEBOARD_FAB2_LIB.BASEBOARD_FAB2(SCH_1):PAGE243_I55@DEV_DISCRETE.CAP_A(CHIPS)':
 'A': CDS_PINID='A';
NODE_NAME     C5G85 1
 '@BASEBOARD_FAB2_LIB.BASEBOARD_FAB2(SCH_1):PAGE243_I56@DEV_DISCRETE.CAP_A(CHIPS)':
 'A': CDS_PINID='A';
NODE_NAME     C5G84 1
 '@BASEBOARD_FAB2_LIB.BASEBOARD_FAB2(SCH_1):PAGE243_I57@DEV_DISCRETE.CAP_A(CHIPS)':
 'A': CDS_PINID='A';
NODE_NAME     C5G83 1
 '@BASEBOARD_FAB2_LIB.BASEBOARD_FAB2(SCH_1):PAGE243_I58@DEV_DISCRETE.CAP_A(CHIPS)':
 'A': CDS_PINID='A';
NODE_NAME     C5G82 1
 '@BASEBOARD_FAB2_LIB.BASEBOARD_FAB2(SCH_1):PAGE243_I59@DEV_DISCRETE.CAP_A(CHIPS)':
 'A': CDS_PINID='A';
NODE_NAME     C5G81 1
 '@BASEBOARD_FAB2_LIB.BASEBOARD_FAB2(SCH_1):PAGE243_I60@DEV_DISCRETE.CAP_A(CHIPS)':
 'A': CDS_PINID='A';
NODE_NAME     C5G80 1
 '@BASEBOARD_FAB2_LIB.BASEBOARD_FAB2(SCH_1):PAGE243_I61@DEV_DISCRETE.CAP_A(CHIPS)':
 'A': CDS_PINID='A';
NODE_NAME     C5G96 1
 '@BASEBOARD_FAB2_LIB.BASEBOARD_FAB2(SCH_1):PAGE243_I62@DEV_DISCRETE.CAP_A(CHIPS)':
 'A': CDS_PINID='A';
NODE_NAME     C5G95 1
 '@BASEBOARD_FAB2_LIB.BASEBOARD_FAB2(SCH_1):PAGE243_I63@DEV_DISCRETE.CAP_A(CHIPS)':
 'A': CDS_PINID='A';
NODE_NAME     C5G94 1
 '@BASEBOARD_FAB2_LIB.BASEBOARD_FAB2(SCH_1):PAGE243_I64@DEV_DISCRETE.CAP_A(CHIPS)':
 'A': CDS_PINID='A';
NODE_NAME     C5G93 1
 '@BASEBOARD_FAB2_LIB.BASEBOARD_FAB2(SCH_1):PAGE243_I65@DEV_DISCRETE.CAP_A(CHIPS)':
 'A': CDS_PINID='A';
NODE_NAME     C5G92 1
 '@BASEBOARD_FAB2_LIB.BASEBOARD_FAB2(SCH_1):PAGE243_I66@DEV_DISCRETE.CAP_A(CHIPS)':
 'A': CDS_PINID='A';
NODE_NAME     C5G91 1
 '@BASEBOARD_FAB2_LIB.BASEBOARD_FAB2(SCH_1):PAGE243_I67@DEV_DISCRETE.CAP_A(CHIPS)':
 'A': CDS_PINID='A';
NODE_NAME     C5G90 1
 '@BASEBOARD_FAB2_LIB.BASEBOARD_FAB2(SCH_1):PAGE243_I68@DEV_DISCRETE.CAP_A(CHIPS)':
 'A': CDS_PINID='A';
NODE_NAME     C5G89 1
 '@BASEBOARD_FAB2_LIB.BASEBOARD_FAB2(SCH_1):PAGE243_I69@DEV_DISCRETE.CAP_A(CHIPS)':
 'A': CDS_PINID='A';
NODE_NAME     C5G88 1
 '@BASEBOARD_FAB2_LIB.BASEBOARD_FAB2(SCH_1):PAGE243_I70@DEV_DISCRETE.CAP_A(CHIPS)':
 'A': CDS_PINID='A';
NODE_NAME     C5G118 1
 '@BASEBOARD_FAB2_LIB.BASEBOARD_FAB2(SCH_1):PAGE243_I91@MSTR_DISCRETE.CAP(CHIPS)':
 'A': CDS_PINID='A';
NODE_NAME     C5G117 1
 '@BASEBOARD_FAB2_LIB.BASEBOARD_FAB2(SCH_1):PAGE243_I92@MSTR_DISCRETE.CAP(CHIPS)':
 'A': CDS_PINID='A';
NODE_NAME     R6U6 1
 '@BASEBOARD_FAB2_LIB.BASEBOARD_FAB2(SCH_1):PAGE229_I6@MSTR_DISCRETE.RES(CHIPS)':
 'A': CDS_PINID='A';
NODE_NAME     C6U13 1
 '@BASEBOARD_FAB2_LIB.BASEBOARD_FAB2(SCH_1):PAGE229_I11@MSTR_DISCRETE.CAP(CHIPS)':
 'A': CDS_PINID='A';
NODE_NAME     C6U14 1
 '@BASEBOARD_FAB2_LIB.BASEBOARD_FAB2(SCH_1):PAGE229_I18@MSTR_DISCRETE.CAP(CHIPS)':
 'A': CDS_PINID='A';
NODE_NAME     EU4G2 10
 '@BASEBOARD_FAB2_LIB.BASEBOARD_FAB2(SCH_1):PAGE229_I37@MSTR_VREG.MIC5166(CHIPS)':
 'VIN': CDS_PINID='VIN';
NODE_NAME     C2D45 1
 '@BASEBOARD_FAB2_LIB.BASEBOARD_FAB2(SCH_1):PAGE225_I261@DEV_DISCRETE.CAP_A(CHIPS)':
 'A': CDS_PINID='A';
NODE_NAME     C3D25 1
 '@BASEBOARD_FAB2_LIB.BASEBOARD_FAB2(SCH_1):PAGE225_I262@DEV_DISCRETE.CAP_A(CHIPS)':
 'A': CDS_PINID='A';
NODE_NAME     C2D47 1
 '@BASEBOARD_FAB2_LIB.BASEBOARD_FAB2(SCH_1):PAGE225_I263@DEV_DISCRETE.CAP_A(CHIPS)':
 'A': CDS_PINID='A';
NODE_NAME     C2D46 1
 '@BASEBOARD_FAB2_LIB.BASEBOARD_FAB2(SCH_1):PAGE225_I264@DEV_DISCRETE.CAP_A(CHIPS)':
 'A': CDS_PINID='A';
NODE_NAME     C2D43 1
 '@BASEBOARD_FAB2_LIB.BASEBOARD_FAB2(SCH_1):PAGE225_I270@DEV_DISCRETE.CAP_A(CHIPS)':
 'A': CDS_PINID='A';
NODE_NAME     C2D41 1
 '@BASEBOARD_FAB2_LIB.BASEBOARD_FAB2(SCH_1):PAGE225_I271@DEV_DISCRETE.CAP_A(CHIPS)':
 'A': CDS_PINID='A';
NODE_NAME     C2D44 1
 '@BASEBOARD_FAB2_LIB.BASEBOARD_FAB2(SCH_1):PAGE225_I272@DEV_DISCRETE.CAP_A(CHIPS)':
 'A': CDS_PINID='A';
NODE_NAME     C2D42 1
 '@BASEBOARD_FAB2_LIB.BASEBOARD_FAB2(SCH_1):PAGE225_I273@DEV_DISCRETE.CAP_A(CHIPS)':
 'A': CDS_PINID='A';
NODE_NAME     C2G10 1
 '@BASEBOARD_FAB2_LIB.BASEBOARD_FAB2(SCH_1):PAGE225_I274@DEV_DISCRETE.CAP_A(CHIPS)':
 'A': CDS_PINID='A';
NODE_NAME     C2G11 1
 '@BASEBOARD_FAB2_LIB.BASEBOARD_FAB2(SCH_1):PAGE225_I275@DEV_DISCRETE.CAP_A(CHIPS)':
 'A': CDS_PINID='A';
NODE_NAME     C2G12 1
 '@BASEBOARD_FAB2_LIB.BASEBOARD_FAB2(SCH_1):PAGE225_I276@DEV_DISCRETE.CAP_A(CHIPS)':
 'A': CDS_PINID='A';
NODE_NAME     C2G1 1
 '@BASEBOARD_FAB2_LIB.BASEBOARD_FAB2(SCH_1):PAGE225_I277@DEV_DISCRETE.CAP_A(CHIPS)':
 'A': CDS_PINID='A';
NODE_NAME     C2G9 1
 '@BASEBOARD_FAB2_LIB.BASEBOARD_FAB2(SCH_1):PAGE225_I278@DEV_DISCRETE.CAP_A(CHIPS)':
 'A': CDS_PINID='A';
NODE_NAME     C2G2 1
 '@BASEBOARD_FAB2_LIB.BASEBOARD_FAB2(SCH_1):PAGE225_I279@DEV_DISCRETE.CAP_A(CHIPS)':
 'A': CDS_PINID='A';
NODE_NAME     C2G3 1
 '@BASEBOARD_FAB2_LIB.BASEBOARD_FAB2(SCH_1):PAGE225_I280@DEV_DISCRETE.CAP_A(CHIPS)':
 'A': CDS_PINID='A';
NODE_NAME     C2G4 1
 '@BASEBOARD_FAB2_LIB.BASEBOARD_FAB2(SCH_1):PAGE225_I281@DEV_DISCRETE.CAP_A(CHIPS)':
 'A': CDS_PINID='A';
NODE_NAME     C2G5 1
 '@BASEBOARD_FAB2_LIB.BASEBOARD_FAB2(SCH_1):PAGE225_I282@DEV_DISCRETE.CAP_A(CHIPS)':
 'A': CDS_PINID='A';
NODE_NAME     C2G6 1
 '@BASEBOARD_FAB2_LIB.BASEBOARD_FAB2(SCH_1):PAGE225_I283@DEV_DISCRETE.CAP_A(CHIPS)':
 'A': CDS_PINID='A';
NODE_NAME     C3G1 1
 '@BASEBOARD_FAB2_LIB.BASEBOARD_FAB2(SCH_1):PAGE225_I284@DEV_DISCRETE.CAP_A(CHIPS)':
 'A': CDS_PINID='A';
NODE_NAME     C3G2 1
 '@BASEBOARD_FAB2_LIB.BASEBOARD_FAB2(SCH_1):PAGE225_I285@DEV_DISCRETE.CAP_A(CHIPS)':
 'A': CDS_PINID='A';
NODE_NAME     C2G13 1
 '@BASEBOARD_FAB2_LIB.BASEBOARD_FAB2(SCH_1):PAGE225_I286@DEV_DISCRETE.CAP_A(CHIPS)':
 'A': CDS_PINID='A';
NODE_NAME     C2G14 1
 '@BASEBOARD_FAB2_LIB.BASEBOARD_FAB2(SCH_1):PAGE225_I287@DEV_DISCRETE.CAP_A(CHIPS)':
 'A': CDS_PINID='A';
NODE_NAME     C3G5 1
 '@BASEBOARD_FAB2_LIB.BASEBOARD_FAB2(SCH_1):PAGE225_I288@DEV_DISCRETE.CAP_A(CHIPS)':
 'A': CDS_PINID='A';
NODE_NAME     C3G6 1
 '@BASEBOARD_FAB2_LIB.BASEBOARD_FAB2(SCH_1):PAGE225_I289@DEV_DISCRETE.CAP_A(CHIPS)':
 'A': CDS_PINID='A';
NODE_NAME     C8U7 1
 '@BASEBOARD_FAB2_LIB.BASEBOARD_FAB2(SCH_1):PAGE225_I290@DEV_DISCRETE.CAP_A(CHIPS)':
 'A': CDS_PINID='A';
NODE_NAME     C8U2 1
 '@BASEBOARD_FAB2_LIB.BASEBOARD_FAB2(SCH_1):PAGE225_I291@DEV_DISCRETE.CAP_A(CHIPS)':
 'A': CDS_PINID='A';
NODE_NAME     C7U2 1
 '@BASEBOARD_FAB2_LIB.BASEBOARD_FAB2(SCH_1):PAGE225_I292@DEV_DISCRETE.CAP_A(CHIPS)':
 'A': CDS_PINID='A';
NODE_NAME     C7U1 1
 '@BASEBOARD_FAB2_LIB.BASEBOARD_FAB2(SCH_1):PAGE225_I293@DEV_DISCRETE.CAP_A(CHIPS)':
 'A': CDS_PINID='A';
NODE_NAME     C8U3 1
 '@BASEBOARD_FAB2_LIB.BASEBOARD_FAB2(SCH_1):PAGE225_I294@DEV_DISCRETE.CAP_A(CHIPS)':
 'A': CDS_PINID='A';
NODE_NAME     C7T4 1
 '@BASEBOARD_FAB2_LIB.BASEBOARD_FAB2(SCH_1):PAGE225_I295@DEV_DISCRETE.CAP_A(CHIPS)':
 'A': CDS_PINID='A';
NODE_NAME     C7T5 1
 '@BASEBOARD_FAB2_LIB.BASEBOARD_FAB2(SCH_1):PAGE225_I296@DEV_DISCRETE.CAP_A(CHIPS)':
 'A': CDS_PINID='A';
NODE_NAME     C8T5 1
 '@BASEBOARD_FAB2_LIB.BASEBOARD_FAB2(SCH_1):PAGE225_I297@DEV_DISCRETE.CAP_A(CHIPS)':
 'A': CDS_PINID='A';
NODE_NAME     C8U6 1
 '@BASEBOARD_FAB2_LIB.BASEBOARD_FAB2(SCH_1):PAGE225_I298@DEV_DISCRETE.CAP_A(CHIPS)':
 'A': CDS_PINID='A';
NODE_NAME     C8T6 1
 '@BASEBOARD_FAB2_LIB.BASEBOARD_FAB2(SCH_1):PAGE225_I299@DEV_DISCRETE.CAP_A(CHIPS)':
 'A': CDS_PINID='A';
NODE_NAME     C8T7 1
 '@BASEBOARD_FAB2_LIB.BASEBOARD_FAB2(SCH_1):PAGE225_I300@DEV_DISCRETE.CAP_A(CHIPS)':
 'A': CDS_PINID='A';
NODE_NAME     C8T8 1
 '@BASEBOARD_FAB2_LIB.BASEBOARD_FAB2(SCH_1):PAGE225_I301@DEV_DISCRETE.CAP_A(CHIPS)':
 'A': CDS_PINID='A';
NODE_NAME     C8U5 1
 '@BASEBOARD_FAB2_LIB.BASEBOARD_FAB2(SCH_1):PAGE225_I302@DEV_DISCRETE.CAP_A(CHIPS)':
 'A': CDS_PINID='A';
NODE_NAME     C8T9 1
 '@BASEBOARD_FAB2_LIB.BASEBOARD_FAB2(SCH_1):PAGE225_I303@DEV_DISCRETE.CAP_A(CHIPS)':
 'A': CDS_PINID='A';
NODE_NAME     C8T10 1
 '@BASEBOARD_FAB2_LIB.BASEBOARD_FAB2(SCH_1):PAGE225_I304@DEV_DISCRETE.CAP_A(CHIPS)':
 'A': CDS_PINID='A';
NODE_NAME     C8U4 1
 '@BASEBOARD_FAB2_LIB.BASEBOARD_FAB2(SCH_1):PAGE225_I305@DEV_DISCRETE.CAP_A(CHIPS)':
 'A': CDS_PINID='A';
NODE_NAME     C8U11 1
 '@BASEBOARD_FAB2_LIB.BASEBOARD_FAB2(SCH_1):PAGE225_I307@MSTR_DISCRETE.CAP(CHIPS)':
 'A': CDS_PINID='A';
NODE_NAME     C7U7 1
 '@BASEBOARD_FAB2_LIB.BASEBOARD_FAB2(SCH_1):PAGE225_I308@MSTR_DISCRETE.CAP(CHIPS)':
 'A': CDS_PINID='A';
NODE_NAME     C7T1 1
 '@BASEBOARD_FAB2_LIB.BASEBOARD_FAB2(SCH_1):PAGE225_I309@MSTR_DISCRETE.CAP(CHIPS)':
 'A': CDS_PINID='A';
NODE_NAME     C8U12 1
 '@BASEBOARD_FAB2_LIB.BASEBOARD_FAB2(SCH_1):PAGE225_I310@MSTR_DISCRETE.CAP(CHIPS)':
 'A': CDS_PINID='A';
NODE_NAME     C2G16 1
 '@BASEBOARD_FAB2_LIB.BASEBOARD_FAB2(SCH_1):PAGE225_I311@MSTR_DISCRETE.CAP(CHIPS)':
 'A': CDS_PINID='A';
NODE_NAME     C2G7 1
 '@BASEBOARD_FAB2_LIB.BASEBOARD_FAB2(SCH_1):PAGE225_I312@MSTR_DISCRETE.CAP(CHIPS)':
 'A': CDS_PINID='A';
NODE_NAME     C8P30 1
 '@BASEBOARD_FAB2_LIB.BASEBOARD_FAB2(SCH_1):PAGE225_I313@MSTR_DISCRETE.CAP(CHIPS)':
 'A': CDS_PINID='A';
NODE_NAME     C8P31 1
 '@BASEBOARD_FAB2_LIB.BASEBOARD_FAB2(SCH_1):PAGE225_I314@MSTR_DISCRETE.CAP(CHIPS)':
 'A': CDS_PINID='A';
NODE_NAME     C8P34 1
 '@BASEBOARD_FAB2_LIB.BASEBOARD_FAB2(SCH_1):PAGE225_I315@MSTR_DISCRETE.CAP(CHIPS)':
 'A': CDS_PINID='A';
NODE_NAME     C8P33 1
 '@BASEBOARD_FAB2_LIB.BASEBOARD_FAB2(SCH_1):PAGE225_I316@MSTR_DISCRETE.CAP(CHIPS)':
 'A': CDS_PINID='A';
NODE_NAME     C8P32 1
 '@BASEBOARD_FAB2_LIB.BASEBOARD_FAB2(SCH_1):PAGE225_I317@MSTR_DISCRETE.CAP(CHIPS)':
 'A': CDS_PINID='A';
NODE_NAME     C7P20 1
 '@BASEBOARD_FAB2_LIB.BASEBOARD_FAB2(SCH_1):PAGE225_I318@MSTR_DISCRETE.CAP(CHIPS)':
 'A': CDS_PINID='A';
NODE_NAME     C8U1 1
 '@BASEBOARD_FAB2_LIB.BASEBOARD_FAB2(SCH_1):PAGE225_I319@MSTR_DISCRETE.CAP(CHIPS)':
 'A': CDS_PINID='A';
NODE_NAME     C8U8 1
 '@BASEBOARD_FAB2_LIB.BASEBOARD_FAB2(SCH_1):PAGE225_I320@MSTR_DISCRETE.CAP(CHIPS)':
 'A': CDS_PINID='A';
NODE_NAME     L1G1 2
 '@BASEBOARD_FAB2_LIB.BASEBOARD_FAB2(SCH_1):PAGE224_I160@W_HDL.IND-120NH-30-GP(CHIPS)':
 'F': CDS_PINID='F';
NODE_NAME     L1F2 2
 '@BASEBOARD_FAB2_LIB.BASEBOARD_FAB2(SCH_1):PAGE224_I161@W_HDL.IND-120NH-30-GP(CHIPS)':
 'F': CDS_PINID='F';
NET_NAME
'PVDDQ_KLM'
 '@BASEBOARD_FAB2_LIB.BASEBOARD_FAB2(SCH_1):PVDDQ_KLM':
 C_SIGNAL='@baseboard_fab2_lib.baseboard_fab2(sch_1):pvddq_klm';
NODE_NAME     U2D1 EF59
 '@BASEBOARD_FAB2_LIB.BASEBOARD_FAB2(SCH_1):PAGE72_I32@CHPSET_LIB.SKX_EXT_B(CHIPS)':
 'VCCD345'<0>: CDS_PINID='VCCD345(0)';
NODE_NAME     U2D1 EF53
 '@BASEBOARD_FAB2_LIB.BASEBOARD_FAB2(SCH_1):PAGE72_I32@CHPSET_LIB.SKX_EXT_B(CHIPS)':
 'VCCD345'<1>: CDS_PINID='VCCD345(1)';
NODE_NAME     U2D1 EF49
 '@BASEBOARD_FAB2_LIB.BASEBOARD_FAB2(SCH_1):PAGE72_I32@CHPSET_LIB.SKX_EXT_B(CHIPS)':
 'VCCD345'<2>: CDS_PINID='VCCD345(2)';
NODE_NAME     U2D1 EC62
 '@BASEBOARD_FAB2_LIB.BASEBOARD_FAB2(SCH_1):PAGE72_I32@CHPSET_LIB.SKX_EXT_B(CHIPS)':
 'VCCD345'<3>: CDS_PINID='VCCD345(3)';
NODE_NAME     U2D1 EC60
 '@BASEBOARD_FAB2_LIB.BASEBOARD_FAB2(SCH_1):PAGE72_I32@CHPSET_LIB.SKX_EXT_B(CHIPS)':
 'VCCD345'<4>: CDS_PINID='VCCD345(4)';
NODE_NAME     U2D1 EC58
 '@BASEBOARD_FAB2_LIB.BASEBOARD_FAB2(SCH_1):PAGE72_I32@CHPSET_LIB.SKX_EXT_B(CHIPS)':
 'VCCD345'<5>: CDS_PINID='VCCD345(5)';
NODE_NAME     U2D1 EC56
 '@BASEBOARD_FAB2_LIB.BASEBOARD_FAB2(SCH_1):PAGE72_I32@CHPSET_LIB.SKX_EXT_B(CHIPS)':
 'VCCD345'<6>: CDS_PINID='VCCD345(6)';
NODE_NAME     U2D1 EC54
 '@BASEBOARD_FAB2_LIB.BASEBOARD_FAB2(SCH_1):PAGE72_I32@CHPSET_LIB.SKX_EXT_B(CHIPS)':
 'VCCD345'<7>: CDS_PINID='VCCD345(7)';
NODE_NAME     U2D1 EC52
 '@BASEBOARD_FAB2_LIB.BASEBOARD_FAB2(SCH_1):PAGE72_I32@CHPSET_LIB.SKX_EXT_B(CHIPS)':
 'VCCD345'<8>: CDS_PINID='VCCD345(8)';
NODE_NAME     U2D1 EC50
 '@BASEBOARD_FAB2_LIB.BASEBOARD_FAB2(SCH_1):PAGE72_I32@CHPSET_LIB.SKX_EXT_B(CHIPS)':
 'VCCD345'<9>: CDS_PINID='VCCD345(9)';
NODE_NAME     U2D1 EC48
 '@BASEBOARD_FAB2_LIB.BASEBOARD_FAB2(SCH_1):PAGE72_I32@CHPSET_LIB.SKX_EXT_B(CHIPS)':
 'VCCD345'<10>: CDS_PINID='VCCD345(10)';
NODE_NAME     U2D1 EC46
 '@BASEBOARD_FAB2_LIB.BASEBOARD_FAB2(SCH_1):PAGE72_I32@CHPSET_LIB.SKX_EXT_B(CHIPS)':
 'VCCD345'<11>: CDS_PINID='VCCD345(11)';
NODE_NAME     U2D1 DU64
 '@BASEBOARD_FAB2_LIB.BASEBOARD_FAB2(SCH_1):PAGE72_I32@CHPSET_LIB.SKX_EXT_B(CHIPS)':
 'VCCD345'<12>: CDS_PINID='VCCD345(12)';
NODE_NAME     U2D1 DU62
 '@BASEBOARD_FAB2_LIB.BASEBOARD_FAB2(SCH_1):PAGE72_I32@CHPSET_LIB.SKX_EXT_B(CHIPS)':
 'VCCD345'<13>: CDS_PINID='VCCD345(13)';
NODE_NAME     U2D1 DU60
 '@BASEBOARD_FAB2_LIB.BASEBOARD_FAB2(SCH_1):PAGE72_I32@CHPSET_LIB.SKX_EXT_B(CHIPS)':
 'VCCD345'<14>: CDS_PINID='VCCD345(14)';
NODE_NAME     U2D1 DU58
 '@BASEBOARD_FAB2_LIB.BASEBOARD_FAB2(SCH_1):PAGE72_I32@CHPSET_LIB.SKX_EXT_B(CHIPS)':
 'VCCD345'<15>: CDS_PINID='VCCD345(15)';
NODE_NAME     U2D1 DU56
 '@BASEBOARD_FAB2_LIB.BASEBOARD_FAB2(SCH_1):PAGE72_I32@CHPSET_LIB.SKX_EXT_B(CHIPS)':
 'VCCD345'<16>: CDS_PINID='VCCD345(16)';
NODE_NAME     U2D1 DU54
 '@BASEBOARD_FAB2_LIB.BASEBOARD_FAB2(SCH_1):PAGE72_I32@CHPSET_LIB.SKX_EXT_B(CHIPS)':
 'VCCD345'<17>: CDS_PINID='VCCD345(17)';
NODE_NAME     U2D1 DU52
 '@BASEBOARD_FAB2_LIB.BASEBOARD_FAB2(SCH_1):PAGE72_I32@CHPSET_LIB.SKX_EXT_B(CHIPS)':
 'VCCD345'<18>: CDS_PINID='VCCD345(18)';
NODE_NAME     U2D1 DU50
 '@BASEBOARD_FAB2_LIB.BASEBOARD_FAB2(SCH_1):PAGE72_I32@CHPSET_LIB.SKX_EXT_B(CHIPS)':
 'VCCD345'<19>: CDS_PINID='VCCD345(19)';
NODE_NAME     U2D1 DU48
 '@BASEBOARD_FAB2_LIB.BASEBOARD_FAB2(SCH_1):PAGE72_I32@CHPSET_LIB.SKX_EXT_B(CHIPS)':
 'VCCD345'<20>: CDS_PINID='VCCD345(20)';
NODE_NAME     U2D1 DU46
 '@BASEBOARD_FAB2_LIB.BASEBOARD_FAB2(SCH_1):PAGE72_I32@CHPSET_LIB.SKX_EXT_B(CHIPS)':
 'VCCD345'<21>: CDS_PINID='VCCD345(21)';
NODE_NAME     U2D1 DL62
 '@BASEBOARD_FAB2_LIB.BASEBOARD_FAB2(SCH_1):PAGE72_I32@CHPSET_LIB.SKX_EXT_B(CHIPS)':
 'VCCD345'<22>: CDS_PINID='VCCD345(22)';
NODE_NAME     U2D1 DL60
 '@BASEBOARD_FAB2_LIB.BASEBOARD_FAB2(SCH_1):PAGE72_I32@CHPSET_LIB.SKX_EXT_B(CHIPS)':
 'VCCD345'<23>: CDS_PINID='VCCD345(23)';
NODE_NAME     U2D1 DL58
 '@BASEBOARD_FAB2_LIB.BASEBOARD_FAB2(SCH_1):PAGE72_I32@CHPSET_LIB.SKX_EXT_B(CHIPS)':
 'VCCD345'<24>: CDS_PINID='VCCD345(24)';
NODE_NAME     U2D1 DL56
 '@BASEBOARD_FAB2_LIB.BASEBOARD_FAB2(SCH_1):PAGE72_I32@CHPSET_LIB.SKX_EXT_B(CHIPS)':
 'VCCD345'<25>: CDS_PINID='VCCD345(25)';
NODE_NAME     U2D1 DL54
 '@BASEBOARD_FAB2_LIB.BASEBOARD_FAB2(SCH_1):PAGE72_I32@CHPSET_LIB.SKX_EXT_B(CHIPS)':
 'VCCD345'<26>: CDS_PINID='VCCD345(26)';
NODE_NAME     U2D1 DL52
 '@BASEBOARD_FAB2_LIB.BASEBOARD_FAB2(SCH_1):PAGE72_I32@CHPSET_LIB.SKX_EXT_B(CHIPS)':
 'VCCD345'<27>: CDS_PINID='VCCD345(27)';
NODE_NAME     U2D1 DL50
 '@BASEBOARD_FAB2_LIB.BASEBOARD_FAB2(SCH_1):PAGE72_I32@CHPSET_LIB.SKX_EXT_B(CHIPS)':
 'VCCD345'<28>: CDS_PINID='VCCD345(28)';
NODE_NAME     U2D1 DL48
 '@BASEBOARD_FAB2_LIB.BASEBOARD_FAB2(SCH_1):PAGE72_I32@CHPSET_LIB.SKX_EXT_B(CHIPS)':
 'VCCD345'<29>: CDS_PINID='VCCD345(29)';
NODE_NAME     U2D1 DL46
 '@BASEBOARD_FAB2_LIB.BASEBOARD_FAB2(SCH_1):PAGE72_I32@CHPSET_LIB.SKX_EXT_B(CHIPS)':
 'VCCD345'<30>: CDS_PINID='VCCD345(30)';
NODE_NAME     U2D1 DJ64
 '@BASEBOARD_FAB2_LIB.BASEBOARD_FAB2(SCH_1):PAGE72_I32@CHPSET_LIB.SKX_EXT_B(CHIPS)':
 'VCCD345'<31>: CDS_PINID='VCCD345(31)';
NODE_NAME     U2D1 DH63
 '@BASEBOARD_FAB2_LIB.BASEBOARD_FAB2(SCH_1):PAGE72_I32@CHPSET_LIB.SKX_EXT_B(CHIPS)':
 'VCCD345'<32>: CDS_PINID='VCCD345(32)';
NODE_NAME     U2D1 DH61
 '@BASEBOARD_FAB2_LIB.BASEBOARD_FAB2(SCH_1):PAGE72_I32@CHPSET_LIB.SKX_EXT_B(CHIPS)':
 'VCCD345'<33>: CDS_PINID='VCCD345(33)';
NODE_NAME     U2D1 DH59
 '@BASEBOARD_FAB2_LIB.BASEBOARD_FAB2(SCH_1):PAGE72_I32@CHPSET_LIB.SKX_EXT_B(CHIPS)':
 'VCCD345'<34>: CDS_PINID='VCCD345(34)';
NODE_NAME     U2D1 DH57
 '@BASEBOARD_FAB2_LIB.BASEBOARD_FAB2(SCH_1):PAGE72_I32@CHPSET_LIB.SKX_EXT_B(CHIPS)':
 'VCCD345'<35>: CDS_PINID='VCCD345(35)';
NODE_NAME     U2D1 DH55
 '@BASEBOARD_FAB2_LIB.BASEBOARD_FAB2(SCH_1):PAGE72_I32@CHPSET_LIB.SKX_EXT_B(CHIPS)':
 'VCCD345'<36>: CDS_PINID='VCCD345(36)';
NODE_NAME     U2D1 DH53
 '@BASEBOARD_FAB2_LIB.BASEBOARD_FAB2(SCH_1):PAGE72_I32@CHPSET_LIB.SKX_EXT_B(CHIPS)':
 'VCCD345'<37>: CDS_PINID='VCCD345(37)';
NODE_NAME     U2D1 DH51
 '@BASEBOARD_FAB2_LIB.BASEBOARD_FAB2(SCH_1):PAGE72_I32@CHPSET_LIB.SKX_EXT_B(CHIPS)':
 'VCCD345'<38>: CDS_PINID='VCCD345(38)';
NODE_NAME     U2D1 DH49
 '@BASEBOARD_FAB2_LIB.BASEBOARD_FAB2(SCH_1):PAGE72_I32@CHPSET_LIB.SKX_EXT_B(CHIPS)':
 'VCCD345'<39>: CDS_PINID='VCCD345(39)';
NODE_NAME     U2D1 DH47
 '@BASEBOARD_FAB2_LIB.BASEBOARD_FAB2(SCH_1):PAGE72_I32@CHPSET_LIB.SKX_EXT_B(CHIPS)':
 'VCCD345'<40>: CDS_PINID='VCCD345(40)';
NODE_NAME     U2D1 DH45
 '@BASEBOARD_FAB2_LIB.BASEBOARD_FAB2(SCH_1):PAGE72_I32@CHPSET_LIB.SKX_EXT_B(CHIPS)':
 'VCCD345'<41>: CDS_PINID='VCCD345(41)';
NODE_NAME     U2D1 DD45
 '@BASEBOARD_FAB2_LIB.BASEBOARD_FAB2(SCH_1):PAGE72_I32@CHPSET_LIB.SKX_EXT_B(CHIPS)':
 'VCCD345'<42>: CDS_PINID='VCCD345(42)';
NODE_NAME     U2D1 DB63
 '@BASEBOARD_FAB2_LIB.BASEBOARD_FAB2(SCH_1):PAGE72_I32@CHPSET_LIB.SKX_EXT_B(CHIPS)':
 'VCCD345'<43>: CDS_PINID='VCCD345(43)';
NODE_NAME     U2D1 DB61
 '@BASEBOARD_FAB2_LIB.BASEBOARD_FAB2(SCH_1):PAGE72_I32@CHPSET_LIB.SKX_EXT_B(CHIPS)':
 'VCCD345'<44>: CDS_PINID='VCCD345(44)';
NODE_NAME     U2D1 DB59
 '@BASEBOARD_FAB2_LIB.BASEBOARD_FAB2(SCH_1):PAGE72_I32@CHPSET_LIB.SKX_EXT_B(CHIPS)':
 'VCCD345'<45>: CDS_PINID='VCCD345(45)';
NODE_NAME     U2D1 DB57
 '@BASEBOARD_FAB2_LIB.BASEBOARD_FAB2(SCH_1):PAGE72_I32@CHPSET_LIB.SKX_EXT_B(CHIPS)':
 'VCCD345'<46>: CDS_PINID='VCCD345(46)';
NODE_NAME     U2D1 DB55
 '@BASEBOARD_FAB2_LIB.BASEBOARD_FAB2(SCH_1):PAGE72_I32@CHPSET_LIB.SKX_EXT_B(CHIPS)':
 'VCCD345'<47>: CDS_PINID='VCCD345(47)';
NODE_NAME     U2D1 DB53
 '@BASEBOARD_FAB2_LIB.BASEBOARD_FAB2(SCH_1):PAGE72_I32@CHPSET_LIB.SKX_EXT_B(CHIPS)':
 'VCCD345'<48>: CDS_PINID='VCCD345(48)';
NODE_NAME     U2D1 EF45
 '@BASEBOARD_FAB2_LIB.BASEBOARD_FAB2(SCH_1):PAGE72_I32@CHPSET_LIB.SKX_EXT_B(CHIPS)':
 'VCCD345'<49>: CDS_PINID='VCCD345(49)';
NODE_NAME     U2D1 EE44
 '@BASEBOARD_FAB2_LIB.BASEBOARD_FAB2(SCH_1):PAGE72_I32@CHPSET_LIB.SKX_EXT_B(CHIPS)':
 'VCCD345'<50>: CDS_PINID='VCCD345(50)';
NODE_NAME     J1B1 236
 '@BASEBOARD_FAB2_LIB.BASEBOARD_FAB2(SCH_1):PAGE83_I167@MSTR_SCONN.SCONN288_H44441004(CHIPS)':
 'VDD'<0>: CDS_PINID='VDD(0)';
NODE_NAME     J1B1 233
 '@BASEBOARD_FAB2_LIB.BASEBOARD_FAB2(SCH_1):PAGE83_I167@MSTR_SCONN.SCONN288_H44441004(CHIPS)':
 'VDD'<1>: CDS_PINID='VDD(1)';
NODE_NAME     J1B1 231
 '@BASEBOARD_FAB2_LIB.BASEBOARD_FAB2(SCH_1):PAGE83_I167@MSTR_SCONN.SCONN288_H44441004(CHIPS)':
 'VDD'<2>: CDS_PINID='VDD(2)';
NODE_NAME     J1B1 229
 '@BASEBOARD_FAB2_LIB.BASEBOARD_FAB2(SCH_1):PAGE83_I167@MSTR_SCONN.SCONN288_H44441004(CHIPS)':
 'VDD'<3>: CDS_PINID='VDD(3)';
NODE_NAME     J1B1 226
 '@BASEBOARD_FAB2_LIB.BASEBOARD_FAB2(SCH_1):PAGE83_I167@MSTR_SCONN.SCONN288_H44441004(CHIPS)':
 'VDD'<4>: CDS_PINID='VDD(4)';
NODE_NAME     J1B1 223
 '@BASEBOARD_FAB2_LIB.BASEBOARD_FAB2(SCH_1):PAGE83_I167@MSTR_SCONN.SCONN288_H44441004(CHIPS)':
 'VDD'<5>: CDS_PINID='VDD(5)';
NODE_NAME     J1B1 220
 '@BASEBOARD_FAB2_LIB.BASEBOARD_FAB2(SCH_1):PAGE83_I167@MSTR_SCONN.SCONN288_H44441004(CHIPS)':
 'VDD'<6>: CDS_PINID='VDD(6)';
NODE_NAME     J1B1 217
 '@BASEBOARD_FAB2_LIB.BASEBOARD_FAB2(SCH_1):PAGE83_I167@MSTR_SCONN.SCONN288_H44441004(CHIPS)':
 'VDD'<7>: CDS_PINID='VDD(7)';
NODE_NAME     J1B1 215
 '@BASEBOARD_FAB2_LIB.BASEBOARD_FAB2(SCH_1):PAGE83_I167@MSTR_SCONN.SCONN288_H44441004(CHIPS)':
 'VDD'<8>: CDS_PINID='VDD(8)';
NODE_NAME     J1B1 212
 '@BASEBOARD_FAB2_LIB.BASEBOARD_FAB2(SCH_1):PAGE83_I167@MSTR_SCONN.SCONN288_H44441004(CHIPS)':
 'VDD'<9>: CDS_PINID='VDD(9)';
NODE_NAME     J1B1 209
 '@BASEBOARD_FAB2_LIB.BASEBOARD_FAB2(SCH_1):PAGE83_I167@MSTR_SCONN.SCONN288_H44441004(CHIPS)':
 'VDD'<10>: CDS_PINID='VDD(10)';
NODE_NAME     J1B1 206
 '@BASEBOARD_FAB2_LIB.BASEBOARD_FAB2(SCH_1):PAGE83_I167@MSTR_SCONN.SCONN288_H44441004(CHIPS)':
 'VDD'<11>: CDS_PINID='VDD(11)';
NODE_NAME     J1B1 204
 '@BASEBOARD_FAB2_LIB.BASEBOARD_FAB2(SCH_1):PAGE83_I167@MSTR_SCONN.SCONN288_H44441004(CHIPS)':
 'VDD'<12>: CDS_PINID='VDD(12)';
NODE_NAME     J1B1 92
 '@BASEBOARD_FAB2_LIB.BASEBOARD_FAB2(SCH_1):PAGE83_I167@MSTR_SCONN.SCONN288_H44441004(CHIPS)':
 'VDD'<13>: CDS_PINID='VDD(13)';
NODE_NAME     J1B1 90
 '@BASEBOARD_FAB2_LIB.BASEBOARD_FAB2(SCH_1):PAGE83_I167@MSTR_SCONN.SCONN288_H44441004(CHIPS)':
 'VDD'<14>: CDS_PINID='VDD(14)';
NODE_NAME     J1B1 88
 '@BASEBOARD_FAB2_LIB.BASEBOARD_FAB2(SCH_1):PAGE83_I167@MSTR_SCONN.SCONN288_H44441004(CHIPS)':
 'VDD'<15>: CDS_PINID='VDD(15)';
NODE_NAME     J1B1 85
 '@BASEBOARD_FAB2_LIB.BASEBOARD_FAB2(SCH_1):PAGE83_I167@MSTR_SCONN.SCONN288_H44441004(CHIPS)':
 'VDD'<16>: CDS_PINID='VDD(16)';
NODE_NAME     J1B1 83
 '@BASEBOARD_FAB2_LIB.BASEBOARD_FAB2(SCH_1):PAGE83_I167@MSTR_SCONN.SCONN288_H44441004(CHIPS)':
 'VDD'<17>: CDS_PINID='VDD(17)';
NODE_NAME     J1B1 80
 '@BASEBOARD_FAB2_LIB.BASEBOARD_FAB2(SCH_1):PAGE83_I167@MSTR_SCONN.SCONN288_H44441004(CHIPS)':
 'VDD'<18>: CDS_PINID='VDD(18)';
NODE_NAME     J1B1 76
 '@BASEBOARD_FAB2_LIB.BASEBOARD_FAB2(SCH_1):PAGE83_I167@MSTR_SCONN.SCONN288_H44441004(CHIPS)':
 'VDD'<19>: CDS_PINID='VDD(19)';
NODE_NAME     J1B1 73
 '@BASEBOARD_FAB2_LIB.BASEBOARD_FAB2(SCH_1):PAGE83_I167@MSTR_SCONN.SCONN288_H44441004(CHIPS)':
 'VDD'<20>: CDS_PINID='VDD(20)';
NODE_NAME     J1B1 70
 '@BASEBOARD_FAB2_LIB.BASEBOARD_FAB2(SCH_1):PAGE83_I167@MSTR_SCONN.SCONN288_H44441004(CHIPS)':
 'VDD'<21>: CDS_PINID='VDD(21)';
NODE_NAME     J1B1 67
 '@BASEBOARD_FAB2_LIB.BASEBOARD_FAB2(SCH_1):PAGE83_I167@MSTR_SCONN.SCONN288_H44441004(CHIPS)':
 'VDD'<22>: CDS_PINID='VDD(22)';
NODE_NAME     J1B1 64
 '@BASEBOARD_FAB2_LIB.BASEBOARD_FAB2(SCH_1):PAGE83_I167@MSTR_SCONN.SCONN288_H44441004(CHIPS)':
 'VDD'<23>: CDS_PINID='VDD(23)';
NODE_NAME     J1B1 61
 '@BASEBOARD_FAB2_LIB.BASEBOARD_FAB2(SCH_1):PAGE83_I167@MSTR_SCONN.SCONN288_H44441004(CHIPS)':
 'VDD'<24>: CDS_PINID='VDD(24)';
NODE_NAME     J1B1 59
 '@BASEBOARD_FAB2_LIB.BASEBOARD_FAB2(SCH_1):PAGE83_I167@MSTR_SCONN.SCONN288_H44441004(CHIPS)':
 'VDD'<25>: CDS_PINID='VDD(25)';
NODE_NAME     J9M1 236
 '@BASEBOARD_FAB2_LIB.BASEBOARD_FAB2(SCH_1):PAGE84_I57@MSTR_SCONN.SCONN288_H44441003(CHIPS)':
 'VDD'<0>: CDS_PINID='VDD(0)';
NODE_NAME     J9M1 233
 '@BASEBOARD_FAB2_LIB.BASEBOARD_FAB2(SCH_1):PAGE84_I57@MSTR_SCONN.SCONN288_H44441003(CHIPS)':
 'VDD'<1>: CDS_PINID='VDD(1)';
NODE_NAME     J9M1 231
 '@BASEBOARD_FAB2_LIB.BASEBOARD_FAB2(SCH_1):PAGE84_I57@MSTR_SCONN.SCONN288_H44441003(CHIPS)':
 'VDD'<2>: CDS_PINID='VDD(2)';
NODE_NAME     J9M1 229
 '@BASEBOARD_FAB2_LIB.BASEBOARD_FAB2(SCH_1):PAGE84_I57@MSTR_SCONN.SCONN288_H44441003(CHIPS)':
 'VDD'<3>: CDS_PINID='VDD(3)';
NODE_NAME     J9M1 226
 '@BASEBOARD_FAB2_LIB.BASEBOARD_FAB2(SCH_1):PAGE84_I57@MSTR_SCONN.SCONN288_H44441003(CHIPS)':
 'VDD'<4>: CDS_PINID='VDD(4)';
NODE_NAME     J9M1 223
 '@BASEBOARD_FAB2_LIB.BASEBOARD_FAB2(SCH_1):PAGE84_I57@MSTR_SCONN.SCONN288_H44441003(CHIPS)':
 'VDD'<5>: CDS_PINID='VDD(5)';
NODE_NAME     J9M1 220
 '@BASEBOARD_FAB2_LIB.BASEBOARD_FAB2(SCH_1):PAGE84_I57@MSTR_SCONN.SCONN288_H44441003(CHIPS)':
 'VDD'<6>: CDS_PINID='VDD(6)';
NODE_NAME     J9M1 217
 '@BASEBOARD_FAB2_LIB.BASEBOARD_FAB2(SCH_1):PAGE84_I57@MSTR_SCONN.SCONN288_H44441003(CHIPS)':
 'VDD'<7>: CDS_PINID='VDD(7)';
NODE_NAME     J9M1 215
 '@BASEBOARD_FAB2_LIB.BASEBOARD_FAB2(SCH_1):PAGE84_I57@MSTR_SCONN.SCONN288_H44441003(CHIPS)':
 'VDD'<8>: CDS_PINID='VDD(8)';
NODE_NAME     J9M1 212
 '@BASEBOARD_FAB2_LIB.BASEBOARD_FAB2(SCH_1):PAGE84_I57@MSTR_SCONN.SCONN288_H44441003(CHIPS)':
 'VDD'<9>: CDS_PINID='VDD(9)';
NODE_NAME     J9M1 209
 '@BASEBOARD_FAB2_LIB.BASEBOARD_FAB2(SCH_1):PAGE84_I57@MSTR_SCONN.SCONN288_H44441003(CHIPS)':
 'VDD'<10>: CDS_PINID='VDD(10)';
NODE_NAME     J9M1 206
 '@BASEBOARD_FAB2_LIB.BASEBOARD_FAB2(SCH_1):PAGE84_I57@MSTR_SCONN.SCONN288_H44441003(CHIPS)':
 'VDD'<11>: CDS_PINID='VDD(11)';
NODE_NAME     J9M1 204
 '@BASEBOARD_FAB2_LIB.BASEBOARD_FAB2(SCH_1):PAGE84_I57@MSTR_SCONN.SCONN288_H44441003(CHIPS)':
 'VDD'<12>: CDS_PINID='VDD(12)';
NODE_NAME     J9M1 92
 '@BASEBOARD_FAB2_LIB.BASEBOARD_FAB2(SCH_1):PAGE84_I57@MSTR_SCONN.SCONN288_H44441003(CHIPS)':
 'VDD'<13>: CDS_PINID='VDD(13)';
NODE_NAME     J9M1 90
 '@BASEBOARD_FAB2_LIB.BASEBOARD_FAB2(SCH_1):PAGE84_I57@MSTR_SCONN.SCONN288_H44441003(CHIPS)':
 'VDD'<14>: CDS_PINID='VDD(14)';
NODE_NAME     J9M1 88
 '@BASEBOARD_FAB2_LIB.BASEBOARD_FAB2(SCH_1):PAGE84_I57@MSTR_SCONN.SCONN288_H44441003(CHIPS)':
 'VDD'<15>: CDS_PINID='VDD(15)';
NODE_NAME     J9M1 85
 '@BASEBOARD_FAB2_LIB.BASEBOARD_FAB2(SCH_1):PAGE84_I57@MSTR_SCONN.SCONN288_H44441003(CHIPS)':
 'VDD'<16>: CDS_PINID='VDD(16)';
NODE_NAME     J9M1 83
 '@BASEBOARD_FAB2_LIB.BASEBOARD_FAB2(SCH_1):PAGE84_I57@MSTR_SCONN.SCONN288_H44441003(CHIPS)':
 'VDD'<17>: CDS_PINID='VDD(17)';
NODE_NAME     J9M1 80
 '@BASEBOARD_FAB2_LIB.BASEBOARD_FAB2(SCH_1):PAGE84_I57@MSTR_SCONN.SCONN288_H44441003(CHIPS)':
 'VDD'<18>: CDS_PINID='VDD(18)';
NODE_NAME     J9M1 76
 '@BASEBOARD_FAB2_LIB.BASEBOARD_FAB2(SCH_1):PAGE84_I57@MSTR_SCONN.SCONN288_H44441003(CHIPS)':
 'VDD'<19>: CDS_PINID='VDD(19)';
NODE_NAME     J9M1 73
 '@BASEBOARD_FAB2_LIB.BASEBOARD_FAB2(SCH_1):PAGE84_I57@MSTR_SCONN.SCONN288_H44441003(CHIPS)':
 'VDD'<20>: CDS_PINID='VDD(20)';
NODE_NAME     J9M1 70
 '@BASEBOARD_FAB2_LIB.BASEBOARD_FAB2(SCH_1):PAGE84_I57@MSTR_SCONN.SCONN288_H44441003(CHIPS)':
 'VDD'<21>: CDS_PINID='VDD(21)';
NODE_NAME     J9M1 67
 '@BASEBOARD_FAB2_LIB.BASEBOARD_FAB2(SCH_1):PAGE84_I57@MSTR_SCONN.SCONN288_H44441003(CHIPS)':
 'VDD'<22>: CDS_PINID='VDD(22)';
NODE_NAME     J9M1 64
 '@BASEBOARD_FAB2_LIB.BASEBOARD_FAB2(SCH_1):PAGE84_I57@MSTR_SCONN.SCONN288_H44441003(CHIPS)':
 'VDD'<23>: CDS_PINID='VDD(23)';
NODE_NAME     J9M1 61
 '@BASEBOARD_FAB2_LIB.BASEBOARD_FAB2(SCH_1):PAGE84_I57@MSTR_SCONN.SCONN288_H44441003(CHIPS)':
 'VDD'<24>: CDS_PINID='VDD(24)';
NODE_NAME     J9M1 59
 '@BASEBOARD_FAB2_LIB.BASEBOARD_FAB2(SCH_1):PAGE84_I57@MSTR_SCONN.SCONN288_H44441003(CHIPS)':
 'VDD'<25>: CDS_PINID='VDD(25)';
NODE_NAME     J1A2 236
 '@BASEBOARD_FAB2_LIB.BASEBOARD_FAB2(SCH_1):PAGE85_I172@MSTR_SCONN.SCONN288_H44441004(CHIPS)':
 'VDD'<0>: CDS_PINID='VDD(0)';
NODE_NAME     J1A2 233
 '@BASEBOARD_FAB2_LIB.BASEBOARD_FAB2(SCH_1):PAGE85_I172@MSTR_SCONN.SCONN288_H44441004(CHIPS)':
 'VDD'<1>: CDS_PINID='VDD(1)';
NODE_NAME     J1A2 231
 '@BASEBOARD_FAB2_LIB.BASEBOARD_FAB2(SCH_1):PAGE85_I172@MSTR_SCONN.SCONN288_H44441004(CHIPS)':
 'VDD'<2>: CDS_PINID='VDD(2)';
NODE_NAME     J1A2 229
 '@BASEBOARD_FAB2_LIB.BASEBOARD_FAB2(SCH_1):PAGE85_I172@MSTR_SCONN.SCONN288_H44441004(CHIPS)':
 'VDD'<3>: CDS_PINID='VDD(3)';
NODE_NAME     J1A2 226
 '@BASEBOARD_FAB2_LIB.BASEBOARD_FAB2(SCH_1):PAGE85_I172@MSTR_SCONN.SCONN288_H44441004(CHIPS)':
 'VDD'<4>: CDS_PINID='VDD(4)';
NODE_NAME     J1A2 223
 '@BASEBOARD_FAB2_LIB.BASEBOARD_FAB2(SCH_1):PAGE85_I172@MSTR_SCONN.SCONN288_H44441004(CHIPS)':
 'VDD'<5>: CDS_PINID='VDD(5)';
NODE_NAME     J1A2 220
 '@BASEBOARD_FAB2_LIB.BASEBOARD_FAB2(SCH_1):PAGE85_I172@MSTR_SCONN.SCONN288_H44441004(CHIPS)':
 'VDD'<6>: CDS_PINID='VDD(6)';
NODE_NAME     J1A2 217
 '@BASEBOARD_FAB2_LIB.BASEBOARD_FAB2(SCH_1):PAGE85_I172@MSTR_SCONN.SCONN288_H44441004(CHIPS)':
 'VDD'<7>: CDS_PINID='VDD(7)';
NODE_NAME     J1A2 215
 '@BASEBOARD_FAB2_LIB.BASEBOARD_FAB2(SCH_1):PAGE85_I172@MSTR_SCONN.SCONN288_H44441004(CHIPS)':
 'VDD'<8>: CDS_PINID='VDD(8)';
NODE_NAME     J1A2 212
 '@BASEBOARD_FAB2_LIB.BASEBOARD_FAB2(SCH_1):PAGE85_I172@MSTR_SCONN.SCONN288_H44441004(CHIPS)':
 'VDD'<9>: CDS_PINID='VDD(9)';
NODE_NAME     J1A2 209
 '@BASEBOARD_FAB2_LIB.BASEBOARD_FAB2(SCH_1):PAGE85_I172@MSTR_SCONN.SCONN288_H44441004(CHIPS)':
 'VDD'<10>: CDS_PINID='VDD(10)';
NODE_NAME     J1A2 206
 '@BASEBOARD_FAB2_LIB.BASEBOARD_FAB2(SCH_1):PAGE85_I172@MSTR_SCONN.SCONN288_H44441004(CHIPS)':
 'VDD'<11>: CDS_PINID='VDD(11)';
NODE_NAME     J1A2 204
 '@BASEBOARD_FAB2_LIB.BASEBOARD_FAB2(SCH_1):PAGE85_I172@MSTR_SCONN.SCONN288_H44441004(CHIPS)':
 'VDD'<12>: CDS_PINID='VDD(12)';
NODE_NAME     J1A2 92
 '@BASEBOARD_FAB2_LIB.BASEBOARD_FAB2(SCH_1):PAGE85_I172@MSTR_SCONN.SCONN288_H44441004(CHIPS)':
 'VDD'<13>: CDS_PINID='VDD(13)';
NODE_NAME     J1A2 90
 '@BASEBOARD_FAB2_LIB.BASEBOARD_FAB2(SCH_1):PAGE85_I172@MSTR_SCONN.SCONN288_H44441004(CHIPS)':
 'VDD'<14>: CDS_PINID='VDD(14)';
NODE_NAME     J1A2 88
 '@BASEBOARD_FAB2_LIB.BASEBOARD_FAB2(SCH_1):PAGE85_I172@MSTR_SCONN.SCONN288_H44441004(CHIPS)':
 'VDD'<15>: CDS_PINID='VDD(15)';
NODE_NAME     J1A2 85
 '@BASEBOARD_FAB2_LIB.BASEBOARD_FAB2(SCH_1):PAGE85_I172@MSTR_SCONN.SCONN288_H44441004(CHIPS)':
 'VDD'<16>: CDS_PINID='VDD(16)';
NODE_NAME     J1A2 83
 '@BASEBOARD_FAB2_LIB.BASEBOARD_FAB2(SCH_1):PAGE85_I172@MSTR_SCONN.SCONN288_H44441004(CHIPS)':
 'VDD'<17>: CDS_PINID='VDD(17)';
NODE_NAME     J1A2 80
 '@BASEBOARD_FAB2_LIB.BASEBOARD_FAB2(SCH_1):PAGE85_I172@MSTR_SCONN.SCONN288_H44441004(CHIPS)':
 'VDD'<18>: CDS_PINID='VDD(18)';
NODE_NAME     J1A2 76
 '@BASEBOARD_FAB2_LIB.BASEBOARD_FAB2(SCH_1):PAGE85_I172@MSTR_SCONN.SCONN288_H44441004(CHIPS)':
 'VDD'<19>: CDS_PINID='VDD(19)';
NODE_NAME     J1A2 73
 '@BASEBOARD_FAB2_LIB.BASEBOARD_FAB2(SCH_1):PAGE85_I172@MSTR_SCONN.SCONN288_H44441004(CHIPS)':
 'VDD'<20>: CDS_PINID='VDD(20)';
NODE_NAME     J1A2 70
 '@BASEBOARD_FAB2_LIB.BASEBOARD_FAB2(SCH_1):PAGE85_I172@MSTR_SCONN.SCONN288_H44441004(CHIPS)':
 'VDD'<21>: CDS_PINID='VDD(21)';
NODE_NAME     J1A2 67
 '@BASEBOARD_FAB2_LIB.BASEBOARD_FAB2(SCH_1):PAGE85_I172@MSTR_SCONN.SCONN288_H44441004(CHIPS)':
 'VDD'<22>: CDS_PINID='VDD(22)';
NODE_NAME     J1A2 64
 '@BASEBOARD_FAB2_LIB.BASEBOARD_FAB2(SCH_1):PAGE85_I172@MSTR_SCONN.SCONN288_H44441004(CHIPS)':
 'VDD'<23>: CDS_PINID='VDD(23)';
NODE_NAME     J1A2 61
 '@BASEBOARD_FAB2_LIB.BASEBOARD_FAB2(SCH_1):PAGE85_I172@MSTR_SCONN.SCONN288_H44441004(CHIPS)':
 'VDD'<24>: CDS_PINID='VDD(24)';
NODE_NAME     J1A2 59
 '@BASEBOARD_FAB2_LIB.BASEBOARD_FAB2(SCH_1):PAGE85_I172@MSTR_SCONN.SCONN288_H44441004(CHIPS)':
 'VDD'<25>: CDS_PINID='VDD(25)';
NODE_NAME     J9L2 236
 '@BASEBOARD_FAB2_LIB.BASEBOARD_FAB2(SCH_1):PAGE86_I55@MSTR_SCONN.SCONN288_H44441003(CHIPS)':
 'VDD'<0>: CDS_PINID='VDD(0)';
NODE_NAME     J9L2 233
 '@BASEBOARD_FAB2_LIB.BASEBOARD_FAB2(SCH_1):PAGE86_I55@MSTR_SCONN.SCONN288_H44441003(CHIPS)':
 'VDD'<1>: CDS_PINID='VDD(1)';
NODE_NAME     J9L2 231
 '@BASEBOARD_FAB2_LIB.BASEBOARD_FAB2(SCH_1):PAGE86_I55@MSTR_SCONN.SCONN288_H44441003(CHIPS)':
 'VDD'<2>: CDS_PINID='VDD(2)';
NODE_NAME     J9L2 229
 '@BASEBOARD_FAB2_LIB.BASEBOARD_FAB2(SCH_1):PAGE86_I55@MSTR_SCONN.SCONN288_H44441003(CHIPS)':
 'VDD'<3>: CDS_PINID='VDD(3)';
NODE_NAME     J9L2 226
 '@BASEBOARD_FAB2_LIB.BASEBOARD_FAB2(SCH_1):PAGE86_I55@MSTR_SCONN.SCONN288_H44441003(CHIPS)':
 'VDD'<4>: CDS_PINID='VDD(4)';
NODE_NAME     J9L2 223
 '@BASEBOARD_FAB2_LIB.BASEBOARD_FAB2(SCH_1):PAGE86_I55@MSTR_SCONN.SCONN288_H44441003(CHIPS)':
 'VDD'<5>: CDS_PINID='VDD(5)';
NODE_NAME     J9L2 220
 '@BASEBOARD_FAB2_LIB.BASEBOARD_FAB2(SCH_1):PAGE86_I55@MSTR_SCONN.SCONN288_H44441003(CHIPS)':
 'VDD'<6>: CDS_PINID='VDD(6)';
NODE_NAME     J9L2 217
 '@BASEBOARD_FAB2_LIB.BASEBOARD_FAB2(SCH_1):PAGE86_I55@MSTR_SCONN.SCONN288_H44441003(CHIPS)':
 'VDD'<7>: CDS_PINID='VDD(7)';
NODE_NAME     J9L2 215
 '@BASEBOARD_FAB2_LIB.BASEBOARD_FAB2(SCH_1):PAGE86_I55@MSTR_SCONN.SCONN288_H44441003(CHIPS)':
 'VDD'<8>: CDS_PINID='VDD(8)';
NODE_NAME     J9L2 212
 '@BASEBOARD_FAB2_LIB.BASEBOARD_FAB2(SCH_1):PAGE86_I55@MSTR_SCONN.SCONN288_H44441003(CHIPS)':
 'VDD'<9>: CDS_PINID='VDD(9)';
NODE_NAME     J9L2 209
 '@BASEBOARD_FAB2_LIB.BASEBOARD_FAB2(SCH_1):PAGE86_I55@MSTR_SCONN.SCONN288_H44441003(CHIPS)':
 'VDD'<10>: CDS_PINID='VDD(10)';
NODE_NAME     J9L2 206
 '@BASEBOARD_FAB2_LIB.BASEBOARD_FAB2(SCH_1):PAGE86_I55@MSTR_SCONN.SCONN288_H44441003(CHIPS)':
 'VDD'<11>: CDS_PINID='VDD(11)';
NODE_NAME     J9L2 204
 '@BASEBOARD_FAB2_LIB.BASEBOARD_FAB2(SCH_1):PAGE86_I55@MSTR_SCONN.SCONN288_H44441003(CHIPS)':
 'VDD'<12>: CDS_PINID='VDD(12)';
NODE_NAME     J9L2 92
 '@BASEBOARD_FAB2_LIB.BASEBOARD_FAB2(SCH_1):PAGE86_I55@MSTR_SCONN.SCONN288_H44441003(CHIPS)':
 'VDD'<13>: CDS_PINID='VDD(13)';
NODE_NAME     J9L2 90
 '@BASEBOARD_FAB2_LIB.BASEBOARD_FAB2(SCH_1):PAGE86_I55@MSTR_SCONN.SCONN288_H44441003(CHIPS)':
 'VDD'<14>: CDS_PINID='VDD(14)';
NODE_NAME     J9L2 88
 '@BASEBOARD_FAB2_LIB.BASEBOARD_FAB2(SCH_1):PAGE86_I55@MSTR_SCONN.SCONN288_H44441003(CHIPS)':
 'VDD'<15>: CDS_PINID='VDD(15)';
NODE_NAME     J9L2 85
 '@BASEBOARD_FAB2_LIB.BASEBOARD_FAB2(SCH_1):PAGE86_I55@MSTR_SCONN.SCONN288_H44441003(CHIPS)':
 'VDD'<16>: CDS_PINID='VDD(16)';
NODE_NAME     J9L2 83
 '@BASEBOARD_FAB2_LIB.BASEBOARD_FAB2(SCH_1):PAGE86_I55@MSTR_SCONN.SCONN288_H44441003(CHIPS)':
 'VDD'<17>: CDS_PINID='VDD(17)';
NODE_NAME     J9L2 80
 '@BASEBOARD_FAB2_LIB.BASEBOARD_FAB2(SCH_1):PAGE86_I55@MSTR_SCONN.SCONN288_H44441003(CHIPS)':
 'VDD'<18>: CDS_PINID='VDD(18)';
NODE_NAME     J9L2 76
 '@BASEBOARD_FAB2_LIB.BASEBOARD_FAB2(SCH_1):PAGE86_I55@MSTR_SCONN.SCONN288_H44441003(CHIPS)':
 'VDD'<19>: CDS_PINID='VDD(19)';
NODE_NAME     J9L2 73
 '@BASEBOARD_FAB2_LIB.BASEBOARD_FAB2(SCH_1):PAGE86_I55@MSTR_SCONN.SCONN288_H44441003(CHIPS)':
 'VDD'<20>: CDS_PINID='VDD(20)';
NODE_NAME     J9L2 70
 '@BASEBOARD_FAB2_LIB.BASEBOARD_FAB2(SCH_1):PAGE86_I55@MSTR_SCONN.SCONN288_H44441003(CHIPS)':
 'VDD'<21>: CDS_PINID='VDD(21)';
NODE_NAME     J9L2 67
 '@BASEBOARD_FAB2_LIB.BASEBOARD_FAB2(SCH_1):PAGE86_I55@MSTR_SCONN.SCONN288_H44441003(CHIPS)':
 'VDD'<22>: CDS_PINID='VDD(22)';
NODE_NAME     J9L2 64
 '@BASEBOARD_FAB2_LIB.BASEBOARD_FAB2(SCH_1):PAGE86_I55@MSTR_SCONN.SCONN288_H44441003(CHIPS)':
 'VDD'<23>: CDS_PINID='VDD(23)';
NODE_NAME     J9L2 61
 '@BASEBOARD_FAB2_LIB.BASEBOARD_FAB2(SCH_1):PAGE86_I55@MSTR_SCONN.SCONN288_H44441003(CHIPS)':
 'VDD'<24>: CDS_PINID='VDD(24)';
NODE_NAME     J9L2 59
 '@BASEBOARD_FAB2_LIB.BASEBOARD_FAB2(SCH_1):PAGE86_I55@MSTR_SCONN.SCONN288_H44441003(CHIPS)':
 'VDD'<25>: CDS_PINID='VDD(25)';
NODE_NAME     J1A1 236
 '@BASEBOARD_FAB2_LIB.BASEBOARD_FAB2(SCH_1):PAGE87_I169@MSTR_SCONN.SCONN288_H44441004(CHIPS)':
 'VDD'<0>: CDS_PINID='VDD(0)';
NODE_NAME     J1A1 233
 '@BASEBOARD_FAB2_LIB.BASEBOARD_FAB2(SCH_1):PAGE87_I169@MSTR_SCONN.SCONN288_H44441004(CHIPS)':
 'VDD'<1>: CDS_PINID='VDD(1)';
NODE_NAME     J1A1 231
 '@BASEBOARD_FAB2_LIB.BASEBOARD_FAB2(SCH_1):PAGE87_I169@MSTR_SCONN.SCONN288_H44441004(CHIPS)':
 'VDD'<2>: CDS_PINID='VDD(2)';
NODE_NAME     J1A1 229
 '@BASEBOARD_FAB2_LIB.BASEBOARD_FAB2(SCH_1):PAGE87_I169@MSTR_SCONN.SCONN288_H44441004(CHIPS)':
 'VDD'<3>: CDS_PINID='VDD(3)';
NODE_NAME     J1A1 226
 '@BASEBOARD_FAB2_LIB.BASEBOARD_FAB2(SCH_1):PAGE87_I169@MSTR_SCONN.SCONN288_H44441004(CHIPS)':
 'VDD'<4>: CDS_PINID='VDD(4)';
NODE_NAME     J1A1 223
 '@BASEBOARD_FAB2_LIB.BASEBOARD_FAB2(SCH_1):PAGE87_I169@MSTR_SCONN.SCONN288_H44441004(CHIPS)':
 'VDD'<5>: CDS_PINID='VDD(5)';
NODE_NAME     J1A1 220
 '@BASEBOARD_FAB2_LIB.BASEBOARD_FAB2(SCH_1):PAGE87_I169@MSTR_SCONN.SCONN288_H44441004(CHIPS)':
 'VDD'<6>: CDS_PINID='VDD(6)';
NODE_NAME     J1A1 217
 '@BASEBOARD_FAB2_LIB.BASEBOARD_FAB2(SCH_1):PAGE87_I169@MSTR_SCONN.SCONN288_H44441004(CHIPS)':
 'VDD'<7>: CDS_PINID='VDD(7)';
NODE_NAME     J1A1 215
 '@BASEBOARD_FAB2_LIB.BASEBOARD_FAB2(SCH_1):PAGE87_I169@MSTR_SCONN.SCONN288_H44441004(CHIPS)':
 'VDD'<8>: CDS_PINID='VDD(8)';
NODE_NAME     J1A1 212
 '@BASEBOARD_FAB2_LIB.BASEBOARD_FAB2(SCH_1):PAGE87_I169@MSTR_SCONN.SCONN288_H44441004(CHIPS)':
 'VDD'<9>: CDS_PINID='VDD(9)';
NODE_NAME     J1A1 209
 '@BASEBOARD_FAB2_LIB.BASEBOARD_FAB2(SCH_1):PAGE87_I169@MSTR_SCONN.SCONN288_H44441004(CHIPS)':
 'VDD'<10>: CDS_PINID='VDD(10)';
NODE_NAME     J1A1 206
 '@BASEBOARD_FAB2_LIB.BASEBOARD_FAB2(SCH_1):PAGE87_I169@MSTR_SCONN.SCONN288_H44441004(CHIPS)':
 'VDD'<11>: CDS_PINID='VDD(11)';
NODE_NAME     J1A1 204
 '@BASEBOARD_FAB2_LIB.BASEBOARD_FAB2(SCH_1):PAGE87_I169@MSTR_SCONN.SCONN288_H44441004(CHIPS)':
 'VDD'<12>: CDS_PINID='VDD(12)';
NODE_NAME     J1A1 92
 '@BASEBOARD_FAB2_LIB.BASEBOARD_FAB2(SCH_1):PAGE87_I169@MSTR_SCONN.SCONN288_H44441004(CHIPS)':
 'VDD'<13>: CDS_PINID='VDD(13)';
NODE_NAME     J1A1 90
 '@BASEBOARD_FAB2_LIB.BASEBOARD_FAB2(SCH_1):PAGE87_I169@MSTR_SCONN.SCONN288_H44441004(CHIPS)':
 'VDD'<14>: CDS_PINID='VDD(14)';
NODE_NAME     J1A1 88
 '@BASEBOARD_FAB2_LIB.BASEBOARD_FAB2(SCH_1):PAGE87_I169@MSTR_SCONN.SCONN288_H44441004(CHIPS)':
 'VDD'<15>: CDS_PINID='VDD(15)';
NODE_NAME     J1A1 85
 '@BASEBOARD_FAB2_LIB.BASEBOARD_FAB2(SCH_1):PAGE87_I169@MSTR_SCONN.SCONN288_H44441004(CHIPS)':
 'VDD'<16>: CDS_PINID='VDD(16)';
NODE_NAME     J1A1 83
 '@BASEBOARD_FAB2_LIB.BASEBOARD_FAB2(SCH_1):PAGE87_I169@MSTR_SCONN.SCONN288_H44441004(CHIPS)':
 'VDD'<17>: CDS_PINID='VDD(17)';
NODE_NAME     J1A1 80
 '@BASEBOARD_FAB2_LIB.BASEBOARD_FAB2(SCH_1):PAGE87_I169@MSTR_SCONN.SCONN288_H44441004(CHIPS)':
 'VDD'<18>: CDS_PINID='VDD(18)';
NODE_NAME     J1A1 76
 '@BASEBOARD_FAB2_LIB.BASEBOARD_FAB2(SCH_1):PAGE87_I169@MSTR_SCONN.SCONN288_H44441004(CHIPS)':
 'VDD'<19>: CDS_PINID='VDD(19)';
NODE_NAME     J1A1 73
 '@BASEBOARD_FAB2_LIB.BASEBOARD_FAB2(SCH_1):PAGE87_I169@MSTR_SCONN.SCONN288_H44441004(CHIPS)':
 'VDD'<20>: CDS_PINID='VDD(20)';
NODE_NAME     J1A1 70
 '@BASEBOARD_FAB2_LIB.BASEBOARD_FAB2(SCH_1):PAGE87_I169@MSTR_SCONN.SCONN288_H44441004(CHIPS)':
 'VDD'<21>: CDS_PINID='VDD(21)';
NODE_NAME     J1A1 67
 '@BASEBOARD_FAB2_LIB.BASEBOARD_FAB2(SCH_1):PAGE87_I169@MSTR_SCONN.SCONN288_H44441004(CHIPS)':
 'VDD'<22>: CDS_PINID='VDD(22)';
NODE_NAME     J1A1 64
 '@BASEBOARD_FAB2_LIB.BASEBOARD_FAB2(SCH_1):PAGE87_I169@MSTR_SCONN.SCONN288_H44441004(CHIPS)':
 'VDD'<23>: CDS_PINID='VDD(23)';
NODE_NAME     J1A1 61
 '@BASEBOARD_FAB2_LIB.BASEBOARD_FAB2(SCH_1):PAGE87_I169@MSTR_SCONN.SCONN288_H44441004(CHIPS)':
 'VDD'<24>: CDS_PINID='VDD(24)';
NODE_NAME     J1A1 59
 '@BASEBOARD_FAB2_LIB.BASEBOARD_FAB2(SCH_1):PAGE87_I169@MSTR_SCONN.SCONN288_H44441004(CHIPS)':
 'VDD'<25>: CDS_PINID='VDD(25)';
NODE_NAME     J9L1 236
 '@BASEBOARD_FAB2_LIB.BASEBOARD_FAB2(SCH_1):PAGE88_I168@MSTR_SCONN.SCONN288_H44441003(CHIPS)':
 'VDD'<0>: CDS_PINID='VDD(0)';
NODE_NAME     J9L1 233
 '@BASEBOARD_FAB2_LIB.BASEBOARD_FAB2(SCH_1):PAGE88_I168@MSTR_SCONN.SCONN288_H44441003(CHIPS)':
 'VDD'<1>: CDS_PINID='VDD(1)';
NODE_NAME     J9L1 231
 '@BASEBOARD_FAB2_LIB.BASEBOARD_FAB2(SCH_1):PAGE88_I168@MSTR_SCONN.SCONN288_H44441003(CHIPS)':
 'VDD'<2>: CDS_PINID='VDD(2)';
NODE_NAME     J9L1 229
 '@BASEBOARD_FAB2_LIB.BASEBOARD_FAB2(SCH_1):PAGE88_I168@MSTR_SCONN.SCONN288_H44441003(CHIPS)':
 'VDD'<3>: CDS_PINID='VDD(3)';
NODE_NAME     J9L1 226
 '@BASEBOARD_FAB2_LIB.BASEBOARD_FAB2(SCH_1):PAGE88_I168@MSTR_SCONN.SCONN288_H44441003(CHIPS)':
 'VDD'<4>: CDS_PINID='VDD(4)';
NODE_NAME     J9L1 223
 '@BASEBOARD_FAB2_LIB.BASEBOARD_FAB2(SCH_1):PAGE88_I168@MSTR_SCONN.SCONN288_H44441003(CHIPS)':
 'VDD'<5>: CDS_PINID='VDD(5)';
NODE_NAME     J9L1 220
 '@BASEBOARD_FAB2_LIB.BASEBOARD_FAB2(SCH_1):PAGE88_I168@MSTR_SCONN.SCONN288_H44441003(CHIPS)':
 'VDD'<6>: CDS_PINID='VDD(6)';
NODE_NAME     J9L1 217
 '@BASEBOARD_FAB2_LIB.BASEBOARD_FAB2(SCH_1):PAGE88_I168@MSTR_SCONN.SCONN288_H44441003(CHIPS)':
 'VDD'<7>: CDS_PINID='VDD(7)';
NODE_NAME     J9L1 215
 '@BASEBOARD_FAB2_LIB.BASEBOARD_FAB2(SCH_1):PAGE88_I168@MSTR_SCONN.SCONN288_H44441003(CHIPS)':
 'VDD'<8>: CDS_PINID='VDD(8)';
NODE_NAME     J9L1 212
 '@BASEBOARD_FAB2_LIB.BASEBOARD_FAB2(SCH_1):PAGE88_I168@MSTR_SCONN.SCONN288_H44441003(CHIPS)':
 'VDD'<9>: CDS_PINID='VDD(9)';
NODE_NAME     J9L1 209
 '@BASEBOARD_FAB2_LIB.BASEBOARD_FAB2(SCH_1):PAGE88_I168@MSTR_SCONN.SCONN288_H44441003(CHIPS)':
 'VDD'<10>: CDS_PINID='VDD(10)';
NODE_NAME     J9L1 206
 '@BASEBOARD_FAB2_LIB.BASEBOARD_FAB2(SCH_1):PAGE88_I168@MSTR_SCONN.SCONN288_H44441003(CHIPS)':
 'VDD'<11>: CDS_PINID='VDD(11)';
NODE_NAME     J9L1 204
 '@BASEBOARD_FAB2_LIB.BASEBOARD_FAB2(SCH_1):PAGE88_I168@MSTR_SCONN.SCONN288_H44441003(CHIPS)':
 'VDD'<12>: CDS_PINID='VDD(12)';
NODE_NAME     J9L1 92
 '@BASEBOARD_FAB2_LIB.BASEBOARD_FAB2(SCH_1):PAGE88_I168@MSTR_SCONN.SCONN288_H44441003(CHIPS)':
 'VDD'<13>: CDS_PINID='VDD(13)';
NODE_NAME     J9L1 90
 '@BASEBOARD_FAB2_LIB.BASEBOARD_FAB2(SCH_1):PAGE88_I168@MSTR_SCONN.SCONN288_H44441003(CHIPS)':
 'VDD'<14>: CDS_PINID='VDD(14)';
NODE_NAME     J9L1 88
 '@BASEBOARD_FAB2_LIB.BASEBOARD_FAB2(SCH_1):PAGE88_I168@MSTR_SCONN.SCONN288_H44441003(CHIPS)':
 'VDD'<15>: CDS_PINID='VDD(15)';
NODE_NAME     J9L1 85
 '@BASEBOARD_FAB2_LIB.BASEBOARD_FAB2(SCH_1):PAGE88_I168@MSTR_SCONN.SCONN288_H44441003(CHIPS)':
 'VDD'<16>: CDS_PINID='VDD(16)';
NODE_NAME     J9L1 83
 '@BASEBOARD_FAB2_LIB.BASEBOARD_FAB2(SCH_1):PAGE88_I168@MSTR_SCONN.SCONN288_H44441003(CHIPS)':
 'VDD'<17>: CDS_PINID='VDD(17)';
NODE_NAME     J9L1 80
 '@BASEBOARD_FAB2_LIB.BASEBOARD_FAB2(SCH_1):PAGE88_I168@MSTR_SCONN.SCONN288_H44441003(CHIPS)':
 'VDD'<18>: CDS_PINID='VDD(18)';
NODE_NAME     J9L1 76
 '@BASEBOARD_FAB2_LIB.BASEBOARD_FAB2(SCH_1):PAGE88_I168@MSTR_SCONN.SCONN288_H44441003(CHIPS)':
 'VDD'<19>: CDS_PINID='VDD(19)';
NODE_NAME     J9L1 73
 '@BASEBOARD_FAB2_LIB.BASEBOARD_FAB2(SCH_1):PAGE88_I168@MSTR_SCONN.SCONN288_H44441003(CHIPS)':
 'VDD'<20>: CDS_PINID='VDD(20)';
NODE_NAME     J9L1 70
 '@BASEBOARD_FAB2_LIB.BASEBOARD_FAB2(SCH_1):PAGE88_I168@MSTR_SCONN.SCONN288_H44441003(CHIPS)':
 'VDD'<21>: CDS_PINID='VDD(21)';
NODE_NAME     J9L1 67
 '@BASEBOARD_FAB2_LIB.BASEBOARD_FAB2(SCH_1):PAGE88_I168@MSTR_SCONN.SCONN288_H44441003(CHIPS)':
 'VDD'<22>: CDS_PINID='VDD(22)';
NODE_NAME     J9L1 64
 '@BASEBOARD_FAB2_LIB.BASEBOARD_FAB2(SCH_1):PAGE88_I168@MSTR_SCONN.SCONN288_H44441003(CHIPS)':
 'VDD'<23>: CDS_PINID='VDD(23)';
NODE_NAME     J9L1 61
 '@BASEBOARD_FAB2_LIB.BASEBOARD_FAB2(SCH_1):PAGE88_I168@MSTR_SCONN.SCONN288_H44441003(CHIPS)':
 'VDD'<24>: CDS_PINID='VDD(24)';
NODE_NAME     J9L1 59
 '@BASEBOARD_FAB2_LIB.BASEBOARD_FAB2(SCH_1):PAGE88_I168@MSTR_SCONN.SCONN288_H44441003(CHIPS)':
 'VDD'<25>: CDS_PINID='VDD(25)';
NODE_NAME     R7M9 1
 '@BASEBOARD_FAB2_LIB.BASEBOARD_FAB2(SCH_1):PAGE96_I28@MSTR_DISCRETE.RES(CHIPS)':
 'A': CDS_PINID='A';
NODE_NAME     R9M1 1
 '@BASEBOARD_FAB2_LIB.BASEBOARD_FAB2(SCH_1):PAGE100_I11@MSTR_DISCRETE.RES(CHIPS)':
 'A': CDS_PINID='A';
NODE_NAME     R9L7 1
 '@BASEBOARD_FAB2_LIB.BASEBOARD_FAB2(SCH_1):PAGE100_I22@MSTR_DISCRETE.RES(CHIPS)':
 'A': CDS_PINID='A';
NODE_NAME     R9L2 1
 '@BASEBOARD_FAB2_LIB.BASEBOARD_FAB2(SCH_1):PAGE100_I38@MSTR_DISCRETE.RES(CHIPS)':
 'A': CDS_PINID='A';
NODE_NAME     C1A12 1
 '@BASEBOARD_FAB2_LIB.BASEBOARD_FAB2(SCH_1):PAGE227_I6@MSTR_DISCRETE.CAP(CHIPS)':
 'A': CDS_PINID='A';
NODE_NAME     C1A1 1
 '@BASEBOARD_FAB2_LIB.BASEBOARD_FAB2(SCH_1):PAGE227_I68@MSTR_DISCRETE.CAP(CHIPS)':
 'A': CDS_PINID='A';
NODE_NAME     EU1A2 1
 '@BASEBOARD_FAB2_LIB.BASEBOARD_FAB2(SCH_1):PAGE227_I101@MSTR_DISCRETE.IR354XX(CHIPS)':
 'VOS': CDS_PINID='VOS';
NODE_NAME     EU1A1 1
 '@BASEBOARD_FAB2_LIB.BASEBOARD_FAB2(SCH_1):PAGE227_I102@MSTR_DISCRETE.IR354XX(CHIPS)':
 'VOS': CDS_PINID='VOS';
NODE_NAME     R1A1 1
 '@BASEBOARD_FAB2_LIB.BASEBOARD_FAB2(SCH_1):PAGE228_I58@MSTR_DISCRETE.RES(CHIPS)':
 'A': CDS_PINID='A';
NODE_NAME     C9L9 1
 '@BASEBOARD_FAB2_LIB.BASEBOARD_FAB2(SCH_1):PAGE228_I75@MSTR_DISCRETE.CAPP(CHIPS)':
 'A': CDS_PINID='A';
NODE_NAME     C9L12 1
 '@BASEBOARD_FAB2_LIB.BASEBOARD_FAB2(SCH_1):PAGE228_I76@MSTR_DISCRETE.CAPP(CHIPS)':
 'A': CDS_PINID='A';
NODE_NAME     C9L4 1
 '@BASEBOARD_FAB2_LIB.BASEBOARD_FAB2(SCH_1):PAGE228_I77@MSTR_DISCRETE.CAPP(CHIPS)':
 'A': CDS_PINID='A';
NODE_NAME     C9L2 1
 '@BASEBOARD_FAB2_LIB.BASEBOARD_FAB2(SCH_1):PAGE228_I78@MSTR_DISCRETE.CAPP(CHIPS)':
 'A': CDS_PINID='A';
NODE_NAME     C8M8 1
 '@BASEBOARD_FAB2_LIB.BASEBOARD_FAB2(SCH_1):PAGE228_I198@DEV_DISCRETE.CAP_A(CHIPS)':
 'A': CDS_PINID='A';
NODE_NAME     C2A5 1
 '@BASEBOARD_FAB2_LIB.BASEBOARD_FAB2(SCH_1):PAGE228_I199@DEV_DISCRETE.CAP_A(CHIPS)':
 'A': CDS_PINID='A';
NODE_NAME     C2B1 1
 '@BASEBOARD_FAB2_LIB.BASEBOARD_FAB2(SCH_1):PAGE228_I200@DEV_DISCRETE.CAP_A(CHIPS)':
 'A': CDS_PINID='A';
NODE_NAME     C8L12 1
 '@BASEBOARD_FAB2_LIB.BASEBOARD_FAB2(SCH_1):PAGE228_I201@DEV_DISCRETE.CAP_A(CHIPS)':
 'A': CDS_PINID='A';
NODE_NAME     C7M5 1
 '@BASEBOARD_FAB2_LIB.BASEBOARD_FAB2(SCH_1):PAGE228_I202@DEV_DISCRETE.CAP_A(CHIPS)':
 'A': CDS_PINID='A';
NODE_NAME     C8M10 1
 '@BASEBOARD_FAB2_LIB.BASEBOARD_FAB2(SCH_1):PAGE228_I203@DEV_DISCRETE.CAP_A(CHIPS)':
 'A': CDS_PINID='A';
NODE_NAME     C2B2 1
 '@BASEBOARD_FAB2_LIB.BASEBOARD_FAB2(SCH_1):PAGE228_I204@DEV_DISCRETE.CAP_A(CHIPS)':
 'A': CDS_PINID='A';
NODE_NAME     C8M9 1
 '@BASEBOARD_FAB2_LIB.BASEBOARD_FAB2(SCH_1):PAGE228_I205@DEV_DISCRETE.CAP_A(CHIPS)':
 'A': CDS_PINID='A';
NODE_NAME     C8M2 1
 '@BASEBOARD_FAB2_LIB.BASEBOARD_FAB2(SCH_1):PAGE228_I206@DEV_DISCRETE.CAP_A(CHIPS)':
 'A': CDS_PINID='A';
NODE_NAME     SH7L2 2
 '@BASEBOARD_FAB2_LIB.BASEBOARD_FAB2(SCH_1):PAGE228_I245@MSTR_MISC.SHUNT(CHIPS)':
 'B':NET_SHORT='VSENSE_PVDDQ_KLM_P:PVDDQ_KLM',
 CDS_PINID='B';
NODE_NAME     C5G103 1
 '@BASEBOARD_FAB2_LIB.BASEBOARD_FAB2(SCH_1):PAGE243_I71@DEV_DISCRETE.CAP_A(CHIPS)':
 'A': CDS_PINID='A';
NODE_NAME     C5G104 1
 '@BASEBOARD_FAB2_LIB.BASEBOARD_FAB2(SCH_1):PAGE243_I72@DEV_DISCRETE.CAP_A(CHIPS)':
 'A': CDS_PINID='A';
NODE_NAME     C5G105 1
 '@BASEBOARD_FAB2_LIB.BASEBOARD_FAB2(SCH_1):PAGE243_I73@DEV_DISCRETE.CAP_A(CHIPS)':
 'A': CDS_PINID='A';
NODE_NAME     C5G102 1
 '@BASEBOARD_FAB2_LIB.BASEBOARD_FAB2(SCH_1):PAGE243_I74@DEV_DISCRETE.CAP_A(CHIPS)':
 'A': CDS_PINID='A';
NODE_NAME     C5G101 1
 '@BASEBOARD_FAB2_LIB.BASEBOARD_FAB2(SCH_1):PAGE243_I75@DEV_DISCRETE.CAP_A(CHIPS)':
 'A': CDS_PINID='A';
NODE_NAME     C5G100 1
 '@BASEBOARD_FAB2_LIB.BASEBOARD_FAB2(SCH_1):PAGE243_I76@DEV_DISCRETE.CAP_A(CHIPS)':
 'A': CDS_PINID='A';
NODE_NAME     C5G99 1
 '@BASEBOARD_FAB2_LIB.BASEBOARD_FAB2(SCH_1):PAGE243_I77@DEV_DISCRETE.CAP_A(CHIPS)':
 'A': CDS_PINID='A';
NODE_NAME     C5G98 1
 '@BASEBOARD_FAB2_LIB.BASEBOARD_FAB2(SCH_1):PAGE243_I78@DEV_DISCRETE.CAP_A(CHIPS)':
 'A': CDS_PINID='A';
NODE_NAME     C5G97 1
 '@BASEBOARD_FAB2_LIB.BASEBOARD_FAB2(SCH_1):PAGE243_I79@DEV_DISCRETE.CAP_A(CHIPS)':
 'A': CDS_PINID='A';
NODE_NAME     C5G114 1
 '@BASEBOARD_FAB2_LIB.BASEBOARD_FAB2(SCH_1):PAGE243_I80@DEV_DISCRETE.CAP_A(CHIPS)':
 'A': CDS_PINID='A';
NODE_NAME     C5G113 1
 '@BASEBOARD_FAB2_LIB.BASEBOARD_FAB2(SCH_1):PAGE243_I81@DEV_DISCRETE.CAP_A(CHIPS)':
 'A': CDS_PINID='A';
NODE_NAME     C5G112 1
 '@BASEBOARD_FAB2_LIB.BASEBOARD_FAB2(SCH_1):PAGE243_I82@DEV_DISCRETE.CAP_A(CHIPS)':
 'A': CDS_PINID='A';
NODE_NAME     C5G111 1
 '@BASEBOARD_FAB2_LIB.BASEBOARD_FAB2(SCH_1):PAGE243_I83@DEV_DISCRETE.CAP_A(CHIPS)':
 'A': CDS_PINID='A';
NODE_NAME     C5G110 1
 '@BASEBOARD_FAB2_LIB.BASEBOARD_FAB2(SCH_1):PAGE243_I84@DEV_DISCRETE.CAP_A(CHIPS)':
 'A': CDS_PINID='A';
NODE_NAME     C5G109 1
 '@BASEBOARD_FAB2_LIB.BASEBOARD_FAB2(SCH_1):PAGE243_I85@DEV_DISCRETE.CAP_A(CHIPS)':
 'A': CDS_PINID='A';
NODE_NAME     C5G108 1
 '@BASEBOARD_FAB2_LIB.BASEBOARD_FAB2(SCH_1):PAGE243_I86@DEV_DISCRETE.CAP_A(CHIPS)':
 'A': CDS_PINID='A';
NODE_NAME     C5G107 1
 '@BASEBOARD_FAB2_LIB.BASEBOARD_FAB2(SCH_1):PAGE243_I87@DEV_DISCRETE.CAP_A(CHIPS)':
 'A': CDS_PINID='A';
NODE_NAME     C5G106 1
 '@BASEBOARD_FAB2_LIB.BASEBOARD_FAB2(SCH_1):PAGE243_I88@DEV_DISCRETE.CAP_A(CHIPS)':
 'A': CDS_PINID='A';
NODE_NAME     C5G115 1
 '@BASEBOARD_FAB2_LIB.BASEBOARD_FAB2(SCH_1):PAGE243_I89@MSTR_DISCRETE.CAP(CHIPS)':
 'A': CDS_PINID='A';
NODE_NAME     C5G116 1
 '@BASEBOARD_FAB2_LIB.BASEBOARD_FAB2(SCH_1):PAGE243_I90@MSTR_DISCRETE.CAP(CHIPS)':
 'A': CDS_PINID='A';
NODE_NAME     R6L6 1
 '@BASEBOARD_FAB2_LIB.BASEBOARD_FAB2(SCH_1):PAGE230_I6@MSTR_DISCRETE.RES(CHIPS)':
 'A': CDS_PINID='A';
NODE_NAME     C6L5 1
 '@BASEBOARD_FAB2_LIB.BASEBOARD_FAB2(SCH_1):PAGE230_I35@MSTR_DISCRETE.CAP(CHIPS)':
 'A': CDS_PINID='A';
NODE_NAME     C4A15 1
 '@BASEBOARD_FAB2_LIB.BASEBOARD_FAB2(SCH_1):PAGE230_I17@MSTR_DISCRETE.CAP(CHIPS)':
 'A': CDS_PINID='A';
NODE_NAME     EU4A2 10
 '@BASEBOARD_FAB2_LIB.BASEBOARD_FAB2(SCH_1):PAGE230_I37@MSTR_VREG.MIC5166(CHIPS)':
 'VIN': CDS_PINID='VIN';
NODE_NAME     C3D1 1
 '@BASEBOARD_FAB2_LIB.BASEBOARD_FAB2(SCH_1):PAGE228_I255@DEV_DISCRETE.CAP_A(CHIPS)':
 'A': CDS_PINID='A';
NODE_NAME     C2D3 1
 '@BASEBOARD_FAB2_LIB.BASEBOARD_FAB2(SCH_1):PAGE228_I256@DEV_DISCRETE.CAP_A(CHIPS)':
 'A': CDS_PINID='A';
NODE_NAME     C2D2 1
 '@BASEBOARD_FAB2_LIB.BASEBOARD_FAB2(SCH_1):PAGE228_I257@DEV_DISCRETE.CAP_A(CHIPS)':
 'A': CDS_PINID='A';
NODE_NAME     C2D1 1
 '@BASEBOARD_FAB2_LIB.BASEBOARD_FAB2(SCH_1):PAGE228_I258@DEV_DISCRETE.CAP_A(CHIPS)':
 'A': CDS_PINID='A';
NODE_NAME     C2D7 1
 '@BASEBOARD_FAB2_LIB.BASEBOARD_FAB2(SCH_1):PAGE228_I264@DEV_DISCRETE.CAP_A(CHIPS)':
 'A': CDS_PINID='A';
NODE_NAME     C2D4 1
 '@BASEBOARD_FAB2_LIB.BASEBOARD_FAB2(SCH_1):PAGE228_I265@DEV_DISCRETE.CAP_A(CHIPS)':
 'A': CDS_PINID='A';
NODE_NAME     C2D5 1
 '@BASEBOARD_FAB2_LIB.BASEBOARD_FAB2(SCH_1):PAGE228_I266@DEV_DISCRETE.CAP_A(CHIPS)':
 'A': CDS_PINID='A';
NODE_NAME     C2D6 1
 '@BASEBOARD_FAB2_LIB.BASEBOARD_FAB2(SCH_1):PAGE228_I267@DEV_DISCRETE.CAP_A(CHIPS)':
 'A': CDS_PINID='A';
NODE_NAME     C7L5 1
 '@BASEBOARD_FAB2_LIB.BASEBOARD_FAB2(SCH_1):PAGE228_I268@DEV_DISCRETE.CAP_A(CHIPS)':
 'A': CDS_PINID='A';
NODE_NAME     C3A6 1
 '@BASEBOARD_FAB2_LIB.BASEBOARD_FAB2(SCH_1):PAGE228_I269@DEV_DISCRETE.CAP_A(CHIPS)':
 'A': CDS_PINID='A';
NODE_NAME     C3A5 1
 '@BASEBOARD_FAB2_LIB.BASEBOARD_FAB2(SCH_1):PAGE228_I270@DEV_DISCRETE.CAP_A(CHIPS)':
 'A': CDS_PINID='A';
NODE_NAME     C2A15 1
 '@BASEBOARD_FAB2_LIB.BASEBOARD_FAB2(SCH_1):PAGE228_I271@DEV_DISCRETE.CAP_A(CHIPS)':
 'A': CDS_PINID='A';
NODE_NAME     C2A14 1
 '@BASEBOARD_FAB2_LIB.BASEBOARD_FAB2(SCH_1):PAGE228_I272@DEV_DISCRETE.CAP_A(CHIPS)':
 'A': CDS_PINID='A';
NODE_NAME     C2A6 1
 '@BASEBOARD_FAB2_LIB.BASEBOARD_FAB2(SCH_1):PAGE228_I273@DEV_DISCRETE.CAP_A(CHIPS)':
 'A': CDS_PINID='A';
NODE_NAME     C2A7 1
 '@BASEBOARD_FAB2_LIB.BASEBOARD_FAB2(SCH_1):PAGE228_I274@DEV_DISCRETE.CAP_A(CHIPS)':
 'A': CDS_PINID='A';
NODE_NAME     C3A1 1
 '@BASEBOARD_FAB2_LIB.BASEBOARD_FAB2(SCH_1):PAGE228_I275@DEV_DISCRETE.CAP_A(CHIPS)':
 'A': CDS_PINID='A';
NODE_NAME     C3A2 1
 '@BASEBOARD_FAB2_LIB.BASEBOARD_FAB2(SCH_1):PAGE228_I276@DEV_DISCRETE.CAP_A(CHIPS)':
 'A': CDS_PINID='A';
NODE_NAME     C2A9 1
 '@BASEBOARD_FAB2_LIB.BASEBOARD_FAB2(SCH_1):PAGE228_I277@DEV_DISCRETE.CAP_A(CHIPS)':
 'A': CDS_PINID='A';
NODE_NAME     C2A10 1
 '@BASEBOARD_FAB2_LIB.BASEBOARD_FAB2(SCH_1):PAGE228_I278@DEV_DISCRETE.CAP_A(CHIPS)':
 'A': CDS_PINID='A';
NODE_NAME     C2A11 1
 '@BASEBOARD_FAB2_LIB.BASEBOARD_FAB2(SCH_1):PAGE228_I279@DEV_DISCRETE.CAP_A(CHIPS)':
 'A': CDS_PINID='A';
NODE_NAME     C2A13 1
 '@BASEBOARD_FAB2_LIB.BASEBOARD_FAB2(SCH_1):PAGE228_I280@DEV_DISCRETE.CAP_A(CHIPS)':
 'A': CDS_PINID='A';
NODE_NAME     C2A12 1
 '@BASEBOARD_FAB2_LIB.BASEBOARD_FAB2(SCH_1):PAGE228_I281@DEV_DISCRETE.CAP_A(CHIPS)':
 'A': CDS_PINID='A';
NODE_NAME     C2A1 1
 '@BASEBOARD_FAB2_LIB.BASEBOARD_FAB2(SCH_1):PAGE228_I282@DEV_DISCRETE.CAP_A(CHIPS)':
 'A': CDS_PINID='A';
NODE_NAME     C2A2 1
 '@BASEBOARD_FAB2_LIB.BASEBOARD_FAB2(SCH_1):PAGE228_I283@DEV_DISCRETE.CAP_A(CHIPS)':
 'A': CDS_PINID='A';
NODE_NAME     C8M1 1
 '@BASEBOARD_FAB2_LIB.BASEBOARD_FAB2(SCH_1):PAGE228_I284@DEV_DISCRETE.CAP_A(CHIPS)':
 'A': CDS_PINID='A';
NODE_NAME     C8L5 1
 '@BASEBOARD_FAB2_LIB.BASEBOARD_FAB2(SCH_1):PAGE228_I285@DEV_DISCRETE.CAP_A(CHIPS)':
 'A': CDS_PINID='A';
NODE_NAME     C8L6 1
 '@BASEBOARD_FAB2_LIB.BASEBOARD_FAB2(SCH_1):PAGE228_I286@DEV_DISCRETE.CAP_A(CHIPS)':
 'A': CDS_PINID='A';
NODE_NAME     C8L7 1
 '@BASEBOARD_FAB2_LIB.BASEBOARD_FAB2(SCH_1):PAGE228_I287@DEV_DISCRETE.CAP_A(CHIPS)':
 'A': CDS_PINID='A';
NODE_NAME     C7L4 1
 '@BASEBOARD_FAB2_LIB.BASEBOARD_FAB2(SCH_1):PAGE228_I288@DEV_DISCRETE.CAP_A(CHIPS)':
 'A': CDS_PINID='A';
NODE_NAME     C8L8 1
 '@BASEBOARD_FAB2_LIB.BASEBOARD_FAB2(SCH_1):PAGE228_I289@DEV_DISCRETE.CAP_A(CHIPS)':
 'A': CDS_PINID='A';
NODE_NAME     C8L9 1
 '@BASEBOARD_FAB2_LIB.BASEBOARD_FAB2(SCH_1):PAGE228_I290@DEV_DISCRETE.CAP_A(CHIPS)':
 'A': CDS_PINID='A';
NODE_NAME     C8M6 1
 '@BASEBOARD_FAB2_LIB.BASEBOARD_FAB2(SCH_1):PAGE228_I291@DEV_DISCRETE.CAP_A(CHIPS)':
 'A': CDS_PINID='A';
NODE_NAME     C2A4 1
 '@BASEBOARD_FAB2_LIB.BASEBOARD_FAB2(SCH_1):PAGE228_I292@DEV_DISCRETE.CAP_A(CHIPS)':
 'A': CDS_PINID='A';
NODE_NAME     C8M4 1
 '@BASEBOARD_FAB2_LIB.BASEBOARD_FAB2(SCH_1):PAGE228_I293@DEV_DISCRETE.CAP_A(CHIPS)':
 'A': CDS_PINID='A';
NODE_NAME     C7M2 1
 '@BASEBOARD_FAB2_LIB.BASEBOARD_FAB2(SCH_1):PAGE228_I294@DEV_DISCRETE.CAP_A(CHIPS)':
 'A': CDS_PINID='A';
NODE_NAME     C7M1 1
 '@BASEBOARD_FAB2_LIB.BASEBOARD_FAB2(SCH_1):PAGE228_I295@DEV_DISCRETE.CAP_A(CHIPS)':
 'A': CDS_PINID='A';
NODE_NAME     C2A3 1
 '@BASEBOARD_FAB2_LIB.BASEBOARD_FAB2(SCH_1):PAGE228_I296@DEV_DISCRETE.CAP_A(CHIPS)':
 'A': CDS_PINID='A';
NODE_NAME     C8L10 1
 '@BASEBOARD_FAB2_LIB.BASEBOARD_FAB2(SCH_1):PAGE228_I297@DEV_DISCRETE.CAP_A(CHIPS)':
 'A': CDS_PINID='A';
NODE_NAME     C8M5 1
 '@BASEBOARD_FAB2_LIB.BASEBOARD_FAB2(SCH_1):PAGE228_I298@DEV_DISCRETE.CAP_A(CHIPS)':
 'A': CDS_PINID='A';
NODE_NAME     C8M3 1
 '@BASEBOARD_FAB2_LIB.BASEBOARD_FAB2(SCH_1):PAGE228_I299@DEV_DISCRETE.CAP_A(CHIPS)':
 'A': CDS_PINID='A';
NODE_NAME     C8L1 1
 '@BASEBOARD_FAB2_LIB.BASEBOARD_FAB2(SCH_1):PAGE228_I301@MSTR_DISCRETE.CAP(CHIPS)':
 'A': CDS_PINID='A';
NODE_NAME     C8L11 1
 '@BASEBOARD_FAB2_LIB.BASEBOARD_FAB2(SCH_1):PAGE228_I302@MSTR_DISCRETE.CAP(CHIPS)':
 'A': CDS_PINID='A';
NODE_NAME     C8P2 1
 '@BASEBOARD_FAB2_LIB.BASEBOARD_FAB2(SCH_1):PAGE228_I303@MSTR_DISCRETE.CAP(CHIPS)':
 'A': CDS_PINID='A';
NODE_NAME     C8P1 1
 '@BASEBOARD_FAB2_LIB.BASEBOARD_FAB2(SCH_1):PAGE228_I304@MSTR_DISCRETE.CAP(CHIPS)':
 'A': CDS_PINID='A';
NODE_NAME     C7P2 1
 '@BASEBOARD_FAB2_LIB.BASEBOARD_FAB2(SCH_1):PAGE228_I305@MSTR_DISCRETE.CAP(CHIPS)':
 'A': CDS_PINID='A';
NODE_NAME     C8P3 1
 '@BASEBOARD_FAB2_LIB.BASEBOARD_FAB2(SCH_1):PAGE228_I306@MSTR_DISCRETE.CAP(CHIPS)':
 'A': CDS_PINID='A';
NODE_NAME     C8P4 1
 '@BASEBOARD_FAB2_LIB.BASEBOARD_FAB2(SCH_1):PAGE228_I307@MSTR_DISCRETE.CAP(CHIPS)':
 'A': CDS_PINID='A';
NODE_NAME     C7P1 1
 '@BASEBOARD_FAB2_LIB.BASEBOARD_FAB2(SCH_1):PAGE228_I308@MSTR_DISCRETE.CAP(CHIPS)':
 'A': CDS_PINID='A';
NODE_NAME     C2A8 1
 '@BASEBOARD_FAB2_LIB.BASEBOARD_FAB2(SCH_1):PAGE228_I309@MSTR_DISCRETE.CAP(CHIPS)':
 'A': CDS_PINID='A';
NODE_NAME     C8L2 1
 '@BASEBOARD_FAB2_LIB.BASEBOARD_FAB2(SCH_1):PAGE228_I310@MSTR_DISCRETE.CAP(CHIPS)':
 'A': CDS_PINID='A';
NODE_NAME     C8M11 1
 '@BASEBOARD_FAB2_LIB.BASEBOARD_FAB2(SCH_1):PAGE228_I311@MSTR_DISCRETE.CAP(CHIPS)':
 'A': CDS_PINID='A';
NODE_NAME     C8M7 1
 '@BASEBOARD_FAB2_LIB.BASEBOARD_FAB2(SCH_1):PAGE228_I312@MSTR_DISCRETE.CAP(CHIPS)':
 'A': CDS_PINID='A';
NODE_NAME     C2A16 1
 '@BASEBOARD_FAB2_LIB.BASEBOARD_FAB2(SCH_1):PAGE228_I313@MSTR_DISCRETE.CAP(CHIPS)':
 'A': CDS_PINID='A';
NODE_NAME     C7L1 1
 '@BASEBOARD_FAB2_LIB.BASEBOARD_FAB2(SCH_1):PAGE228_I314@MSTR_DISCRETE.CAP(CHIPS)':
 'A': CDS_PINID='A';
NODE_NAME     L1A2 2
 '@BASEBOARD_FAB2_LIB.BASEBOARD_FAB2(SCH_1):PAGE227_I152@W_HDL.IND-120NH-30-GP(CHIPS)':
 'F': CDS_PINID='F';
NODE_NAME     L1A1 2
 '@BASEBOARD_FAB2_LIB.BASEBOARD_FAB2(SCH_1):PAGE227_I153@W_HDL.IND-120NH-30-GP(CHIPS)':
 'F': CDS_PINID='F';
NET_NAME
'PVNN_PCH_STBY'
 '@BASEBOARD_FAB2_LIB.BASEBOARD_FAB2(SCH_1):PVNN_PCH_STBY':
 C_SIGNAL='@baseboard_fab2_lib.baseboard_fab2(sch_1):pvnn_pch_stby';
NODE_NAME     U7C1 AU36
 '@BASEBOARD_FAB2_LIB.BASEBOARD_FAB2(SCH_1):PAGE123_I21@MSTR_U_PROC.LBG_CORE_QAT_EXT_D(CHIPS)':
 'VCCPRIM_AVID'<0>: CDS_PINID='VCCPRIM_AVID(0)';
NODE_NAME     U7C1 AU34
 '@BASEBOARD_FAB2_LIB.BASEBOARD_FAB2(SCH_1):PAGE123_I21@MSTR_U_PROC.LBG_CORE_QAT_EXT_D(CHIPS)':
 'VCCPRIM_AVID'<1>: CDS_PINID='VCCPRIM_AVID(1)';
NODE_NAME     U7C1 AU32
 '@BASEBOARD_FAB2_LIB.BASEBOARD_FAB2(SCH_1):PAGE123_I21@MSTR_U_PROC.LBG_CORE_QAT_EXT_D(CHIPS)':
 'VCCPRIM_AVID'<2>: CDS_PINID='VCCPRIM_AVID(2)';
NODE_NAME     U7C1 AT36
 '@BASEBOARD_FAB2_LIB.BASEBOARD_FAB2(SCH_1):PAGE123_I21@MSTR_U_PROC.LBG_CORE_QAT_EXT_D(CHIPS)':
 'VCCPRIM_AVID'<3>: CDS_PINID='VCCPRIM_AVID(3)';
NODE_NAME     U7C1 AT34
 '@BASEBOARD_FAB2_LIB.BASEBOARD_FAB2(SCH_1):PAGE123_I21@MSTR_U_PROC.LBG_CORE_QAT_EXT_D(CHIPS)':
 'VCCPRIM_AVID'<4>: CDS_PINID='VCCPRIM_AVID(4)';
NODE_NAME     U7C1 AT32
 '@BASEBOARD_FAB2_LIB.BASEBOARD_FAB2(SCH_1):PAGE123_I21@MSTR_U_PROC.LBG_CORE_QAT_EXT_D(CHIPS)':
 'VCCPRIM_AVID'<5>: CDS_PINID='VCCPRIM_AVID(5)';
NODE_NAME     U7C1 AP39
 '@BASEBOARD_FAB2_LIB.BASEBOARD_FAB2(SCH_1):PAGE123_I21@MSTR_U_PROC.LBG_CORE_QAT_EXT_D(CHIPS)':
 'VCCPRIM_AVID'<6>: CDS_PINID='VCCPRIM_AVID(6)';
NODE_NAME     U7C1 AP37
 '@BASEBOARD_FAB2_LIB.BASEBOARD_FAB2(SCH_1):PAGE123_I21@MSTR_U_PROC.LBG_CORE_QAT_EXT_D(CHIPS)':
 'VCCPRIM_AVID'<7>: CDS_PINID='VCCPRIM_AVID(7)';
NODE_NAME     U7C1 AP36
 '@BASEBOARD_FAB2_LIB.BASEBOARD_FAB2(SCH_1):PAGE123_I21@MSTR_U_PROC.LBG_CORE_QAT_EXT_D(CHIPS)':
 'VCCPRIM_AVID'<8>: CDS_PINID='VCCPRIM_AVID(8)';
NODE_NAME     U7C1 AP34
 '@BASEBOARD_FAB2_LIB.BASEBOARD_FAB2(SCH_1):PAGE123_I21@MSTR_U_PROC.LBG_CORE_QAT_EXT_D(CHIPS)':
 'VCCPRIM_AVID'<9>: CDS_PINID='VCCPRIM_AVID(9)';
NODE_NAME     U7C1 AP32
 '@BASEBOARD_FAB2_LIB.BASEBOARD_FAB2(SCH_1):PAGE123_I21@MSTR_U_PROC.LBG_CORE_QAT_EXT_D(CHIPS)':
 'VCCPRIM_AVID'<10>: CDS_PINID='VCCPRIM_AVID(10)';
NODE_NAME     U7C1 AM39
 '@BASEBOARD_FAB2_LIB.BASEBOARD_FAB2(SCH_1):PAGE123_I21@MSTR_U_PROC.LBG_CORE_QAT_EXT_D(CHIPS)':
 'VCCPRIM_AVID'<11>: CDS_PINID='VCCPRIM_AVID(11)';
NODE_NAME     U7C1 AM37
 '@BASEBOARD_FAB2_LIB.BASEBOARD_FAB2(SCH_1):PAGE123_I21@MSTR_U_PROC.LBG_CORE_QAT_EXT_D(CHIPS)':
 'VCCPRIM_AVID'<12>: CDS_PINID='VCCPRIM_AVID(12)';
NODE_NAME     U7C1 AM36
 '@BASEBOARD_FAB2_LIB.BASEBOARD_FAB2(SCH_1):PAGE123_I21@MSTR_U_PROC.LBG_CORE_QAT_EXT_D(CHIPS)':
 'VCCPRIM_AVID'<13>: CDS_PINID='VCCPRIM_AVID(13)';
NODE_NAME     U7C1 AM34
 '@BASEBOARD_FAB2_LIB.BASEBOARD_FAB2(SCH_1):PAGE123_I21@MSTR_U_PROC.LBG_CORE_QAT_EXT_D(CHIPS)':
 'VCCPRIM_AVID'<14>: CDS_PINID='VCCPRIM_AVID(14)';
NODE_NAME     U7C1 AM32
 '@BASEBOARD_FAB2_LIB.BASEBOARD_FAB2(SCH_1):PAGE123_I21@MSTR_U_PROC.LBG_CORE_QAT_EXT_D(CHIPS)':
 'VCCPRIM_AVID'<15>: CDS_PINID='VCCPRIM_AVID(15)';
NODE_NAME     U7C1 AK39
 '@BASEBOARD_FAB2_LIB.BASEBOARD_FAB2(SCH_1):PAGE123_I21@MSTR_U_PROC.LBG_CORE_QAT_EXT_D(CHIPS)':
 'VCCPRIM_AVID'<16>: CDS_PINID='VCCPRIM_AVID(16)';
NODE_NAME     U7C1 AK37
 '@BASEBOARD_FAB2_LIB.BASEBOARD_FAB2(SCH_1):PAGE123_I21@MSTR_U_PROC.LBG_CORE_QAT_EXT_D(CHIPS)':
 'VCCPRIM_AVID'<17>: CDS_PINID='VCCPRIM_AVID(17)';
NODE_NAME     U7C1 AK34
 '@BASEBOARD_FAB2_LIB.BASEBOARD_FAB2(SCH_1):PAGE123_I21@MSTR_U_PROC.LBG_CORE_QAT_EXT_D(CHIPS)':
 'VCCPRIM_AVID'<18>: CDS_PINID='VCCPRIM_AVID(18)';
NODE_NAME     U7C1 AG39
 '@BASEBOARD_FAB2_LIB.BASEBOARD_FAB2(SCH_1):PAGE123_I21@MSTR_U_PROC.LBG_CORE_QAT_EXT_D(CHIPS)':
 'VCCPRIM_AVID'<19>: CDS_PINID='VCCPRIM_AVID(19)';
NODE_NAME     U7C1 AG37
 '@BASEBOARD_FAB2_LIB.BASEBOARD_FAB2(SCH_1):PAGE123_I21@MSTR_U_PROC.LBG_CORE_QAT_EXT_D(CHIPS)':
 'VCCPRIM_AVID'<20>: CDS_PINID='VCCPRIM_AVID(20)';
NODE_NAME     U7C1 AG36
 '@BASEBOARD_FAB2_LIB.BASEBOARD_FAB2(SCH_1):PAGE123_I21@MSTR_U_PROC.LBG_CORE_QAT_EXT_D(CHIPS)':
 'VCCPRIM_AVID'<21>: CDS_PINID='VCCPRIM_AVID(21)';
NODE_NAME     U7C1 AG34
 '@BASEBOARD_FAB2_LIB.BASEBOARD_FAB2(SCH_1):PAGE123_I21@MSTR_U_PROC.LBG_CORE_QAT_EXT_D(CHIPS)':
 'VCCPRIM_AVID'<22>: CDS_PINID='VCCPRIM_AVID(22)';
NODE_NAME     U7C1 AG32
 '@BASEBOARD_FAB2_LIB.BASEBOARD_FAB2(SCH_1):PAGE123_I21@MSTR_U_PROC.LBG_CORE_QAT_EXT_D(CHIPS)':
 'VCCPRIM_AVID'<23>: CDS_PINID='VCCPRIM_AVID(23)';
NODE_NAME     U7C1 AE41
 '@BASEBOARD_FAB2_LIB.BASEBOARD_FAB2(SCH_1):PAGE123_I21@MSTR_U_PROC.LBG_CORE_QAT_EXT_D(CHIPS)':
 'VCCPRIM_AVID'<24>: CDS_PINID='VCCPRIM_AVID(24)';
NODE_NAME     U7C1 AE39
 '@BASEBOARD_FAB2_LIB.BASEBOARD_FAB2(SCH_1):PAGE123_I21@MSTR_U_PROC.LBG_CORE_QAT_EXT_D(CHIPS)':
 'VCCPRIM_AVID'<25>: CDS_PINID='VCCPRIM_AVID(25)';
NODE_NAME     U7C1 AE37
 '@BASEBOARD_FAB2_LIB.BASEBOARD_FAB2(SCH_1):PAGE123_I21@MSTR_U_PROC.LBG_CORE_QAT_EXT_D(CHIPS)':
 'VCCPRIM_AVID'<26>: CDS_PINID='VCCPRIM_AVID(26)';
NODE_NAME     U7C1 AE36
 '@BASEBOARD_FAB2_LIB.BASEBOARD_FAB2(SCH_1):PAGE123_I21@MSTR_U_PROC.LBG_CORE_QAT_EXT_D(CHIPS)':
 'VCCPRIM_AVID'<27>: CDS_PINID='VCCPRIM_AVID(27)';
NODE_NAME     U7C1 AE34
 '@BASEBOARD_FAB2_LIB.BASEBOARD_FAB2(SCH_1):PAGE123_I21@MSTR_U_PROC.LBG_CORE_QAT_EXT_D(CHIPS)':
 'VCCPRIM_AVID'<28>: CDS_PINID='VCCPRIM_AVID(28)';
NODE_NAME     U7C1 AE32
 '@BASEBOARD_FAB2_LIB.BASEBOARD_FAB2(SCH_1):PAGE123_I21@MSTR_U_PROC.LBG_CORE_QAT_EXT_D(CHIPS)':
 'VCCPRIM_AVID'<29>: CDS_PINID='VCCPRIM_AVID(29)';
NODE_NAME     U7C1 AE30
 '@BASEBOARD_FAB2_LIB.BASEBOARD_FAB2(SCH_1):PAGE123_I21@MSTR_U_PROC.LBG_CORE_QAT_EXT_D(CHIPS)':
 'VCCPRIM_AVID'<30>: CDS_PINID='VCCPRIM_AVID(30)';
NODE_NAME     U7C1 U27
 '@BASEBOARD_FAB2_LIB.BASEBOARD_FAB2(SCH_1):PAGE123_I21@MSTR_U_PROC.LBG_CORE_QAT_EXT_D(CHIPS)':
 'VCCPRIM_AVID'<31>: CDS_PINID='VCCPRIM_AVID(31)';
NODE_NAME     U7C1 AC41
 '@BASEBOARD_FAB2_LIB.BASEBOARD_FAB2(SCH_1):PAGE123_I21@MSTR_U_PROC.LBG_CORE_QAT_EXT_D(CHIPS)':
 'VCCPRIM_AVID'<32>: CDS_PINID='VCCPRIM_AVID(32)';
NODE_NAME     U7C1 AC39
 '@BASEBOARD_FAB2_LIB.BASEBOARD_FAB2(SCH_1):PAGE123_I21@MSTR_U_PROC.LBG_CORE_QAT_EXT_D(CHIPS)':
 'VCCPRIM_AVID'<33>: CDS_PINID='VCCPRIM_AVID(33)';
NODE_NAME     U7C1 AC37
 '@BASEBOARD_FAB2_LIB.BASEBOARD_FAB2(SCH_1):PAGE123_I21@MSTR_U_PROC.LBG_CORE_QAT_EXT_D(CHIPS)':
 'VCCPRIM_AVID'<34>: CDS_PINID='VCCPRIM_AVID(34)';
NODE_NAME     U7C1 AC36
 '@BASEBOARD_FAB2_LIB.BASEBOARD_FAB2(SCH_1):PAGE123_I21@MSTR_U_PROC.LBG_CORE_QAT_EXT_D(CHIPS)':
 'VCCPRIM_AVID'<35>: CDS_PINID='VCCPRIM_AVID(35)';
NODE_NAME     U7C1 AC34
 '@BASEBOARD_FAB2_LIB.BASEBOARD_FAB2(SCH_1):PAGE123_I21@MSTR_U_PROC.LBG_CORE_QAT_EXT_D(CHIPS)':
 'VCCPRIM_AVID'<36>: CDS_PINID='VCCPRIM_AVID(36)';
NODE_NAME     U7C1 AC32
 '@BASEBOARD_FAB2_LIB.BASEBOARD_FAB2(SCH_1):PAGE123_I21@MSTR_U_PROC.LBG_CORE_QAT_EXT_D(CHIPS)':
 'VCCPRIM_AVID'<37>: CDS_PINID='VCCPRIM_AVID(37)';
NODE_NAME     U7C1 AC30
 '@BASEBOARD_FAB2_LIB.BASEBOARD_FAB2(SCH_1):PAGE123_I21@MSTR_U_PROC.LBG_CORE_QAT_EXT_D(CHIPS)':
 'VCCPRIM_AVID'<38>: CDS_PINID='VCCPRIM_AVID(38)';
NODE_NAME     U7C1 AC29
 '@BASEBOARD_FAB2_LIB.BASEBOARD_FAB2(SCH_1):PAGE123_I21@MSTR_U_PROC.LBG_CORE_QAT_EXT_D(CHIPS)':
 'VCCPRIM_AVID'<39>: CDS_PINID='VCCPRIM_AVID(39)';
NODE_NAME     U7C1 AA41
 '@BASEBOARD_FAB2_LIB.BASEBOARD_FAB2(SCH_1):PAGE123_I21@MSTR_U_PROC.LBG_CORE_QAT_EXT_D(CHIPS)':
 'VCCPRIM_AVID'<40>: CDS_PINID='VCCPRIM_AVID(40)';
NODE_NAME     U7C1 AA39
 '@BASEBOARD_FAB2_LIB.BASEBOARD_FAB2(SCH_1):PAGE123_I21@MSTR_U_PROC.LBG_CORE_QAT_EXT_D(CHIPS)':
 'VCCPRIM_AVID'<41>: CDS_PINID='VCCPRIM_AVID(41)';
NODE_NAME     U7C1 AA37
 '@BASEBOARD_FAB2_LIB.BASEBOARD_FAB2(SCH_1):PAGE123_I21@MSTR_U_PROC.LBG_CORE_QAT_EXT_D(CHIPS)':
 'VCCPRIM_AVID'<42>: CDS_PINID='VCCPRIM_AVID(42)';
NODE_NAME     U7C1 AA36
 '@BASEBOARD_FAB2_LIB.BASEBOARD_FAB2(SCH_1):PAGE123_I21@MSTR_U_PROC.LBG_CORE_QAT_EXT_D(CHIPS)':
 'VCCPRIM_AVID'<43>: CDS_PINID='VCCPRIM_AVID(43)';
NODE_NAME     U7C1 AA34
 '@BASEBOARD_FAB2_LIB.BASEBOARD_FAB2(SCH_1):PAGE123_I21@MSTR_U_PROC.LBG_CORE_QAT_EXT_D(CHIPS)':
 'VCCPRIM_AVID'<44>: CDS_PINID='VCCPRIM_AVID(44)';
NODE_NAME     U7C1 AA32
 '@BASEBOARD_FAB2_LIB.BASEBOARD_FAB2(SCH_1):PAGE123_I21@MSTR_U_PROC.LBG_CORE_QAT_EXT_D(CHIPS)':
 'VCCPRIM_AVID'<45>: CDS_PINID='VCCPRIM_AVID(45)';
NODE_NAME     U7C1 AA30
 '@BASEBOARD_FAB2_LIB.BASEBOARD_FAB2(SCH_1):PAGE123_I21@MSTR_U_PROC.LBG_CORE_QAT_EXT_D(CHIPS)':
 'VCCPRIM_AVID'<46>: CDS_PINID='VCCPRIM_AVID(46)';
NODE_NAME     U7C1 AA29
 '@BASEBOARD_FAB2_LIB.BASEBOARD_FAB2(SCH_1):PAGE123_I21@MSTR_U_PROC.LBG_CORE_QAT_EXT_D(CHIPS)':
 'VCCPRIM_AVID'<47>: CDS_PINID='VCCPRIM_AVID(47)';
NODE_NAME     U7C1 Y41
 '@BASEBOARD_FAB2_LIB.BASEBOARD_FAB2(SCH_1):PAGE123_I21@MSTR_U_PROC.LBG_CORE_QAT_EXT_D(CHIPS)':
 'VCCPRIM_AVID'<48>: CDS_PINID='VCCPRIM_AVID(48)';
NODE_NAME     U7C1 Y39
 '@BASEBOARD_FAB2_LIB.BASEBOARD_FAB2(SCH_1):PAGE123_I21@MSTR_U_PROC.LBG_CORE_QAT_EXT_D(CHIPS)':
 'VCCPRIM_AVID'<49>: CDS_PINID='VCCPRIM_AVID(49)';
NODE_NAME     U7C1 Y37
 '@BASEBOARD_FAB2_LIB.BASEBOARD_FAB2(SCH_1):PAGE123_I21@MSTR_U_PROC.LBG_CORE_QAT_EXT_D(CHIPS)':
 'VCCPRIM_AVID'<50>: CDS_PINID='VCCPRIM_AVID(50)';
NODE_NAME     U7C1 Y36
 '@BASEBOARD_FAB2_LIB.BASEBOARD_FAB2(SCH_1):PAGE123_I21@MSTR_U_PROC.LBG_CORE_QAT_EXT_D(CHIPS)':
 'VCCPRIM_AVID'<51>: CDS_PINID='VCCPRIM_AVID(51)';
NODE_NAME     U7C1 Y34
 '@BASEBOARD_FAB2_LIB.BASEBOARD_FAB2(SCH_1):PAGE123_I21@MSTR_U_PROC.LBG_CORE_QAT_EXT_D(CHIPS)':
 'VCCPRIM_AVID'<52>: CDS_PINID='VCCPRIM_AVID(52)';
NODE_NAME     U7C1 Y32
 '@BASEBOARD_FAB2_LIB.BASEBOARD_FAB2(SCH_1):PAGE123_I21@MSTR_U_PROC.LBG_CORE_QAT_EXT_D(CHIPS)':
 'VCCPRIM_AVID'<53>: CDS_PINID='VCCPRIM_AVID(53)';
NODE_NAME     U7C1 Y30
 '@BASEBOARD_FAB2_LIB.BASEBOARD_FAB2(SCH_1):PAGE123_I21@MSTR_U_PROC.LBG_CORE_QAT_EXT_D(CHIPS)':
 'VCCPRIM_AVID'<54>: CDS_PINID='VCCPRIM_AVID(54)';
NODE_NAME     U7C1 Y29
 '@BASEBOARD_FAB2_LIB.BASEBOARD_FAB2(SCH_1):PAGE123_I21@MSTR_U_PROC.LBG_CORE_QAT_EXT_D(CHIPS)':
 'VCCPRIM_AVID'<55>: CDS_PINID='VCCPRIM_AVID(55)';
NODE_NAME     U7C1 V40
 '@BASEBOARD_FAB2_LIB.BASEBOARD_FAB2(SCH_1):PAGE123_I21@MSTR_U_PROC.LBG_CORE_QAT_EXT_D(CHIPS)':
 'VCCPRIM_AVID'<56>: CDS_PINID='VCCPRIM_AVID(56)';
NODE_NAME     U7C1 V33
 '@BASEBOARD_FAB2_LIB.BASEBOARD_FAB2(SCH_1):PAGE123_I21@MSTR_U_PROC.LBG_CORE_QAT_EXT_D(CHIPS)':
 'VCCPRIM_AVID'<57>: CDS_PINID='VCCPRIM_AVID(57)';
NODE_NAME     U7C1 V29
 '@BASEBOARD_FAB2_LIB.BASEBOARD_FAB2(SCH_1):PAGE123_I21@MSTR_U_PROC.LBG_CORE_QAT_EXT_D(CHIPS)':
 'VCCPRIM_AVID'<58>: CDS_PINID='VCCPRIM_AVID(58)';
NODE_NAME     U7C1 U38
 '@BASEBOARD_FAB2_LIB.BASEBOARD_FAB2(SCH_1):PAGE123_I21@MSTR_U_PROC.LBG_CORE_QAT_EXT_D(CHIPS)':
 'VCCPRIM_AVID'<59>: CDS_PINID='VCCPRIM_AVID(59)';
NODE_NAME     U7C1 U35
 '@BASEBOARD_FAB2_LIB.BASEBOARD_FAB2(SCH_1):PAGE123_I21@MSTR_U_PROC.LBG_CORE_QAT_EXT_D(CHIPS)':
 'VCCPRIM_AVID'<60>: CDS_PINID='VCCPRIM_AVID(60)';
NODE_NAME     U7C1 U31
 '@BASEBOARD_FAB2_LIB.BASEBOARD_FAB2(SCH_1):PAGE123_I21@MSTR_U_PROC.LBG_CORE_QAT_EXT_D(CHIPS)':
 'VCCPRIM_AVID'<61>: CDS_PINID='VCCPRIM_AVID(61)';
NODE_NAME     U7C1 AK32
 '@BASEBOARD_FAB2_LIB.BASEBOARD_FAB2(SCH_1):PAGE123_I21@MSTR_U_PROC.LBG_CORE_QAT_EXT_D(CHIPS)':
 'VCCPRIM_AVID'<62>: CDS_PINID='VCCPRIM_AVID(62)';
NODE_NAME     C3L25 1
 '@BASEBOARD_FAB2_LIB.BASEBOARD_FAB2(SCH_1):PAGE132_I1@DEV_DISCRETE.CAP_A(CHIPS)':
 'A': CDS_PINID='A';
NODE_NAME     C3M7 1
 '@BASEBOARD_FAB2_LIB.BASEBOARD_FAB2(SCH_1):PAGE132_I2@DEV_DISCRETE.CAP_A(CHIPS)':
 'A': CDS_PINID='A';
NODE_NAME     C3L26 1
 '@BASEBOARD_FAB2_LIB.BASEBOARD_FAB2(SCH_1):PAGE132_I3@DEV_DISCRETE.CAP_A(CHIPS)':
 'A': CDS_PINID='A';
NODE_NAME     C3L27 1
 '@BASEBOARD_FAB2_LIB.BASEBOARD_FAB2(SCH_1):PAGE132_I4@DEV_DISCRETE.CAP_A(CHIPS)':
 'A': CDS_PINID='A';
NODE_NAME     C3M6 1
 '@BASEBOARD_FAB2_LIB.BASEBOARD_FAB2(SCH_1):PAGE132_I6@DEV_DISCRETE.CAP_A(CHIPS)':
 'A': CDS_PINID='A';
NODE_NAME     C7C9 1
 '@BASEBOARD_FAB2_LIB.BASEBOARD_FAB2(SCH_1):PAGE132_I7@DEV_DISCRETE.CAP_A(CHIPS)':
 'A': CDS_PINID='A';
NODE_NAME     C3N27 1
 '@BASEBOARD_FAB2_LIB.BASEBOARD_FAB2(SCH_1):PAGE132_I8@DEV_DISCRETE.CAP_A(CHIPS)':
 'A': CDS_PINID='A';
NODE_NAME     C3N30 1
 '@BASEBOARD_FAB2_LIB.BASEBOARD_FAB2(SCH_1):PAGE132_I9@DEV_DISCRETE.CAP_A(CHIPS)':
 'A': CDS_PINID='A';
NODE_NAME     C7A36 1
 '@BASEBOARD_FAB2_LIB.BASEBOARD_FAB2(SCH_1):PAGE132_I11@DEV_DISCRETE.CAP_A(CHIPS)':
 'A': CDS_PINID='A';
NODE_NAME     C3N12 1
 '@BASEBOARD_FAB2_LIB.BASEBOARD_FAB2(SCH_1):PAGE132_I12@DEV_DISCRETE.CAP_A(CHIPS)':
 'A': CDS_PINID='A';
NODE_NAME     C3N10 1
 '@BASEBOARD_FAB2_LIB.BASEBOARD_FAB2(SCH_1):PAGE132_I13@DEV_DISCRETE.CAP_A(CHIPS)':
 'A': CDS_PINID='A';
NODE_NAME     C3N24 1
 '@BASEBOARD_FAB2_LIB.BASEBOARD_FAB2(SCH_1):PAGE132_I16@DEV_DISCRETE.CAP_A(CHIPS)':
 'A': CDS_PINID='A';
NODE_NAME     C3N28 1
 '@BASEBOARD_FAB2_LIB.BASEBOARD_FAB2(SCH_1):PAGE132_I17@DEV_DISCRETE.CAP_A(CHIPS)':
 'A': CDS_PINID='A';
NODE_NAME     C3N11 1
 '@BASEBOARD_FAB2_LIB.BASEBOARD_FAB2(SCH_1):PAGE132_I19@DEV_DISCRETE.CAP_A(CHIPS)':
 'A': CDS_PINID='A';
NODE_NAME     C3N31 1
 '@BASEBOARD_FAB2_LIB.BASEBOARD_FAB2(SCH_1):PAGE132_I20@DEV_DISCRETE.CAP_A(CHIPS)':
 'A': CDS_PINID='A';
NODE_NAME     C7A33 1
 '@BASEBOARD_FAB2_LIB.BASEBOARD_FAB2(SCH_1):PAGE132_I23@MSTR_DISCRETE.CAP(CHIPS)':
 'A': CDS_PINID='A';
NODE_NAME     C7B4 1
 '@BASEBOARD_FAB2_LIB.BASEBOARD_FAB2(SCH_1):PAGE132_I24@MSTR_DISCRETE.CAP(CHIPS)':
 'A': CDS_PINID='A';
NODE_NAME     C2N9 1
 '@BASEBOARD_FAB2_LIB.BASEBOARD_FAB2(SCH_1):PAGE132_I26@DEV_DISCRETE.CAP_A(CHIPS)':
 'A': CDS_PINID='A';
NODE_NAME     C2N3 1
 '@BASEBOARD_FAB2_LIB.BASEBOARD_FAB2(SCH_1):PAGE132_I27@DEV_DISCRETE.CAP_A(CHIPS)':
 'A': CDS_PINID='A';
NODE_NAME     C2N4 1
 '@BASEBOARD_FAB2_LIB.BASEBOARD_FAB2(SCH_1):PAGE132_I28@DEV_DISCRETE.CAP_A(CHIPS)':
 'A': CDS_PINID='A';
NODE_NAME     C2N12 1
 '@BASEBOARD_FAB2_LIB.BASEBOARD_FAB2(SCH_1):PAGE132_I29@DEV_DISCRETE.CAP_A(CHIPS)':
 'A': CDS_PINID='A';
NODE_NAME     C2N11 1
 '@BASEBOARD_FAB2_LIB.BASEBOARD_FAB2(SCH_1):PAGE132_I30@DEV_DISCRETE.CAP_A(CHIPS)':
 'A': CDS_PINID='A';
NODE_NAME     C3N19 1
 '@BASEBOARD_FAB2_LIB.BASEBOARD_FAB2(SCH_1):PAGE132_I31@DEV_DISCRETE.CAP_A(CHIPS)':
 'A': CDS_PINID='A';
NODE_NAME     C3N3 1
 '@BASEBOARD_FAB2_LIB.BASEBOARD_FAB2(SCH_1):PAGE132_I32@DEV_DISCRETE.CAP_A(CHIPS)':
 'A': CDS_PINID='A';
NODE_NAME     C3N1 1
 '@BASEBOARD_FAB2_LIB.BASEBOARD_FAB2(SCH_1):PAGE132_I34@DEV_DISCRETE.CAP_A(CHIPS)':
 'A': CDS_PINID='A';
NODE_NAME     C3N7 1
 '@BASEBOARD_FAB2_LIB.BASEBOARD_FAB2(SCH_1):PAGE132_I35@DEV_DISCRETE.CAP_A(CHIPS)':
 'A': CDS_PINID='A';
NODE_NAME     C3N16 1
 '@BASEBOARD_FAB2_LIB.BASEBOARD_FAB2(SCH_1):PAGE132_I36@DEV_DISCRETE.CAP_A(CHIPS)':
 'A': CDS_PINID='A';
NODE_NAME     C7A32 1
 '@BASEBOARD_FAB2_LIB.BASEBOARD_FAB2(SCH_1):PAGE132_I38@MSTR_DISCRETE.CAP(CHIPS)':
 'A': CDS_PINID='A';
NODE_NAME     C7A31 1
 '@BASEBOARD_FAB2_LIB.BASEBOARD_FAB2(SCH_1):PAGE132_I40@MSTR_DISCRETE.CAP(CHIPS)':
 'A': CDS_PINID='A';
NODE_NAME     C3N18 1
 '@BASEBOARD_FAB2_LIB.BASEBOARD_FAB2(SCH_1):PAGE132_I42@DEV_DISCRETE.CAP_A(CHIPS)':
 'A': CDS_PINID='A';
NODE_NAME     C3N2 1
 '@BASEBOARD_FAB2_LIB.BASEBOARD_FAB2(SCH_1):PAGE132_I43@DEV_DISCRETE.CAP_A(CHIPS)':
 'A': CDS_PINID='A';
NODE_NAME     C3N6 1
 '@BASEBOARD_FAB2_LIB.BASEBOARD_FAB2(SCH_1):PAGE132_I44@DEV_DISCRETE.CAP_A(CHIPS)':
 'A': CDS_PINID='A';
NODE_NAME     C3N17 1
 '@BASEBOARD_FAB2_LIB.BASEBOARD_FAB2(SCH_1):PAGE132_I45@DEV_DISCRETE.CAP_A(CHIPS)':
 'A': CDS_PINID='A';
NODE_NAME     C3N4 1
 '@BASEBOARD_FAB2_LIB.BASEBOARD_FAB2(SCH_1):PAGE132_I46@DEV_DISCRETE.CAP_A(CHIPS)':
 'A': CDS_PINID='A';
NODE_NAME     C3N5 1
 '@BASEBOARD_FAB2_LIB.BASEBOARD_FAB2(SCH_1):PAGE132_I48@DEV_DISCRETE.CAP_A(CHIPS)':
 'A': CDS_PINID='A';
NODE_NAME     C3N15 1
 '@BASEBOARD_FAB2_LIB.BASEBOARD_FAB2(SCH_1):PAGE132_I49@DEV_DISCRETE.CAP_A(CHIPS)':
 'A': CDS_PINID='A';
NODE_NAME     C3N20 1
 '@BASEBOARD_FAB2_LIB.BASEBOARD_FAB2(SCH_1):PAGE132_I51@DEV_DISCRETE.CAP_A(CHIPS)':
 'A': CDS_PINID='A';
NODE_NAME     C3L23 1
 '@BASEBOARD_FAB2_LIB.BASEBOARD_FAB2(SCH_1):PAGE132_I52@DEV_DISCRETE.CAP_A(CHIPS)':
 'A': CDS_PINID='A';
NODE_NAME     C3L22 1
 '@BASEBOARD_FAB2_LIB.BASEBOARD_FAB2(SCH_1):PAGE132_I54@DEV_DISCRETE.CAP_A(CHIPS)':
 'A': CDS_PINID='A';
NODE_NAME     C3L24 1
 '@BASEBOARD_FAB2_LIB.BASEBOARD_FAB2(SCH_1):PAGE132_I56@DEV_DISCRETE.CAP_A(CHIPS)':
 'A': CDS_PINID='A';
NODE_NAME     FB1U4 2
 '@BASEBOARD_FAB2_LIB.BASEBOARD_FAB2(SCH_1):PAGE169_I155@MSTR_DISCRETE.FERRITE(CHIPS)':
 'B': CDS_PINID='B';
NODE_NAME     C7A30 1
 '@BASEBOARD_FAB2_LIB.BASEBOARD_FAB2(SCH_1):PAGE236_I9@MSTR_DISCRETE.CAP(CHIPS)':
 'A': CDS_PINID='A';
NODE_NAME     C3L18 1
 '@BASEBOARD_FAB2_LIB.BASEBOARD_FAB2(SCH_1):PAGE236_I71@MSTR_DISCRETE.CAPP(CHIPS)':
 'A': CDS_PINID='A';
NODE_NAME     C3L20 1
 '@BASEBOARD_FAB2_LIB.BASEBOARD_FAB2(SCH_1):PAGE236_I73@MSTR_DISCRETE.CAPP(CHIPS)':
 'A': CDS_PINID='A';
NODE_NAME     C3L21 1
 '@BASEBOARD_FAB2_LIB.BASEBOARD_FAB2(SCH_1):PAGE236_I74@MSTR_DISCRETE.CAPP(CHIPS)':
 'A': CDS_PINID='A';
NODE_NAME     C7A27 1
 '@BASEBOARD_FAB2_LIB.BASEBOARD_FAB2(SCH_1):PAGE236_I75@MSTR_DISCRETE.CAPP(CHIPS)':
 'A': CDS_PINID='A';
NODE_NAME     R7A13 2
 '@BASEBOARD_FAB2_LIB.BASEBOARD_FAB2(SCH_1):PAGE236_I90@MSTR_DISCRETE.RES(CHIPS)':
 'B': CDS_PINID='B';
NODE_NAME     EU7A3 1
 '@BASEBOARD_FAB2_LIB.BASEBOARD_FAB2(SCH_1):PAGE236_I116@MSTR_DISCRETE.IR354XX(CHIPS)':
 'VOS': CDS_PINID='VOS';
NODE_NAME     L7A2 2
 '@BASEBOARD_FAB2_LIB.BASEBOARD_FAB2(SCH_1):PAGE236_I178@W_HDL.IND-300NH-20-GP(CHIPS)':
 'F': CDS_PINID='F';
NET_NAME
'PVPP_ABC'
 '@BASEBOARD_FAB2_LIB.BASEBOARD_FAB2(SCH_1):PVPP_ABC':
 C_SIGNAL='@baseboard_fab2_lib.baseboard_fab2(sch_1):pvpp_abc';
NODE_NAME     U5D1 B11
 '@BASEBOARD_FAB2_LIB.BASEBOARD_FAB2(SCH_1):PAGE38_I34@CHPSET_LIB.SKX_EXT_B(CHIPS)':
 'CD_VPP'<0>: CDS_PINID='CD_VPP(0)';
NODE_NAME     U5D1 A12
 '@BASEBOARD_FAB2_LIB.BASEBOARD_FAB2(SCH_1):PAGE38_I34@CHPSET_LIB.SKX_EXT_B(CHIPS)':
 'CD_VPP'<1>: CDS_PINID='CD_VPP(1)';
NODE_NAME     U5D1 A10
 '@BASEBOARD_FAB2_LIB.BASEBOARD_FAB2(SCH_1):PAGE38_I34@CHPSET_LIB.SKX_EXT_B(CHIPS)':
 'CD_VPP'<2>: CDS_PINID='CD_VPP(2)';
NODE_NAME     U5D1 A8
 '@BASEBOARD_FAB2_LIB.BASEBOARD_FAB2(SCH_1):PAGE38_I34@CHPSET_LIB.SKX_EXT_B(CHIPS)':
 'CD_VPP'<3>: CDS_PINID='CD_VPP(3)';
NODE_NAME     J4G1 284
 '@BASEBOARD_FAB2_LIB.BASEBOARD_FAB2(SCH_1):PAGE43_I1@MSTR_SCONN.SCONN288_H44441004(CHIPS)':
 'VDDSPD': CDS_PINID='VDDSPD';
NODE_NAME     J4G1 287
 '@BASEBOARD_FAB2_LIB.BASEBOARD_FAB2(SCH_1):PAGE43_I260@MSTR_SCONN.SCONN288_H44441004(CHIPS)':
 'VPP'<0>: CDS_PINID='VPP(0)';
NODE_NAME     J4G1 286
 '@BASEBOARD_FAB2_LIB.BASEBOARD_FAB2(SCH_1):PAGE43_I260@MSTR_SCONN.SCONN288_H44441004(CHIPS)':
 'VPP'<1>: CDS_PINID='VPP(1)';
NODE_NAME     J4G1 288
 '@BASEBOARD_FAB2_LIB.BASEBOARD_FAB2(SCH_1):PAGE43_I260@MSTR_SCONN.SCONN288_H44441004(CHIPS)':
 'VPP'<2>: CDS_PINID='VPP(2)';
NODE_NAME     J4G1 143
 '@BASEBOARD_FAB2_LIB.BASEBOARD_FAB2(SCH_1):PAGE43_I260@MSTR_SCONN.SCONN288_H44441004(CHIPS)':
 'VPP'<3>: CDS_PINID='VPP(3)';
NODE_NAME     J4G1 142
 '@BASEBOARD_FAB2_LIB.BASEBOARD_FAB2(SCH_1):PAGE43_I260@MSTR_SCONN.SCONN288_H44441004(CHIPS)':
 'VPP'<4>: CDS_PINID='VPP(4)';
NODE_NAME     J6T1 139
 '@BASEBOARD_FAB2_LIB.BASEBOARD_FAB2(SCH_1):PAGE44_I13@MSTR_SCONN.SCONN288_H44441003(CHIPS)':
 'SA'<0>: CDS_PINID='SA(0)';
NODE_NAME     J6T1 284
 '@BASEBOARD_FAB2_LIB.BASEBOARD_FAB2(SCH_1):PAGE44_I13@MSTR_SCONN.SCONN288_H44441003(CHIPS)':
 'VDDSPD': CDS_PINID='VDDSPD';
NODE_NAME     J6T1 287
 '@BASEBOARD_FAB2_LIB.BASEBOARD_FAB2(SCH_1):PAGE44_I75@MSTR_SCONN.SCONN288_H44441003(CHIPS)':
 'VPP'<0>: CDS_PINID='VPP(0)';
NODE_NAME     J6T1 286
 '@BASEBOARD_FAB2_LIB.BASEBOARD_FAB2(SCH_1):PAGE44_I75@MSTR_SCONN.SCONN288_H44441003(CHIPS)':
 'VPP'<1>: CDS_PINID='VPP(1)';
NODE_NAME     J6T1 288
 '@BASEBOARD_FAB2_LIB.BASEBOARD_FAB2(SCH_1):PAGE44_I75@MSTR_SCONN.SCONN288_H44441003(CHIPS)':
 'VPP'<2>: CDS_PINID='VPP(2)';
NODE_NAME     J6T1 143
 '@BASEBOARD_FAB2_LIB.BASEBOARD_FAB2(SCH_1):PAGE44_I75@MSTR_SCONN.SCONN288_H44441003(CHIPS)':
 'VPP'<3>: CDS_PINID='VPP(3)';
NODE_NAME     J6T1 142
 '@BASEBOARD_FAB2_LIB.BASEBOARD_FAB2(SCH_1):PAGE44_I75@MSTR_SCONN.SCONN288_H44441003(CHIPS)':
 'VPP'<4>: CDS_PINID='VPP(4)';
NODE_NAME     J4G2 140
 '@BASEBOARD_FAB2_LIB.BASEBOARD_FAB2(SCH_1):PAGE45_I111@MSTR_SCONN.SCONN288_H44441004(CHIPS)':
 'SA'<1>: CDS_PINID='SA(1)';
NODE_NAME     J4G2 284
 '@BASEBOARD_FAB2_LIB.BASEBOARD_FAB2(SCH_1):PAGE45_I111@MSTR_SCONN.SCONN288_H44441004(CHIPS)':
 'VDDSPD': CDS_PINID='VDDSPD';
NODE_NAME     J4G2 287
 '@BASEBOARD_FAB2_LIB.BASEBOARD_FAB2(SCH_1):PAGE45_I169@MSTR_SCONN.SCONN288_H44441004(CHIPS)':
 'VPP'<0>: CDS_PINID='VPP(0)';
NODE_NAME     J4G2 286
 '@BASEBOARD_FAB2_LIB.BASEBOARD_FAB2(SCH_1):PAGE45_I169@MSTR_SCONN.SCONN288_H44441004(CHIPS)':
 'VPP'<1>: CDS_PINID='VPP(1)';
NODE_NAME     J4G2 288
 '@BASEBOARD_FAB2_LIB.BASEBOARD_FAB2(SCH_1):PAGE45_I169@MSTR_SCONN.SCONN288_H44441004(CHIPS)':
 'VPP'<2>: CDS_PINID='VPP(2)';
NODE_NAME     J4G2 143
 '@BASEBOARD_FAB2_LIB.BASEBOARD_FAB2(SCH_1):PAGE45_I169@MSTR_SCONN.SCONN288_H44441004(CHIPS)':
 'VPP'<3>: CDS_PINID='VPP(3)';
NODE_NAME     J4G2 142
 '@BASEBOARD_FAB2_LIB.BASEBOARD_FAB2(SCH_1):PAGE45_I169@MSTR_SCONN.SCONN288_H44441004(CHIPS)':
 'VPP'<4>: CDS_PINID='VPP(4)';
NODE_NAME     J6U1 139
 '@BASEBOARD_FAB2_LIB.BASEBOARD_FAB2(SCH_1):PAGE46_I14@MSTR_SCONN.SCONN288_H44441003(CHIPS)':
 'SA'<0>: CDS_PINID='SA(0)';
NODE_NAME     J6U1 140
 '@BASEBOARD_FAB2_LIB.BASEBOARD_FAB2(SCH_1):PAGE46_I14@MSTR_SCONN.SCONN288_H44441003(CHIPS)':
 'SA'<1>: CDS_PINID='SA(1)';
NODE_NAME     J6U1 284
 '@BASEBOARD_FAB2_LIB.BASEBOARD_FAB2(SCH_1):PAGE46_I14@MSTR_SCONN.SCONN288_H44441003(CHIPS)':
 'VDDSPD': CDS_PINID='VDDSPD';
NODE_NAME     J6U1 287
 '@BASEBOARD_FAB2_LIB.BASEBOARD_FAB2(SCH_1):PAGE46_I67@MSTR_SCONN.SCONN288_H44441003(CHIPS)':
 'VPP'<0>: CDS_PINID='VPP(0)';
NODE_NAME     J6U1 286
 '@BASEBOARD_FAB2_LIB.BASEBOARD_FAB2(SCH_1):PAGE46_I67@MSTR_SCONN.SCONN288_H44441003(CHIPS)':
 'VPP'<1>: CDS_PINID='VPP(1)';
NODE_NAME     J6U1 288
 '@BASEBOARD_FAB2_LIB.BASEBOARD_FAB2(SCH_1):PAGE46_I67@MSTR_SCONN.SCONN288_H44441003(CHIPS)':
 'VPP'<2>: CDS_PINID='VPP(2)';
NODE_NAME     J6U1 143
 '@BASEBOARD_FAB2_LIB.BASEBOARD_FAB2(SCH_1):PAGE46_I67@MSTR_SCONN.SCONN288_H44441003(CHIPS)':
 'VPP'<3>: CDS_PINID='VPP(3)';
NODE_NAME     J6U1 142
 '@BASEBOARD_FAB2_LIB.BASEBOARD_FAB2(SCH_1):PAGE46_I67@MSTR_SCONN.SCONN288_H44441003(CHIPS)':
 'VPP'<4>: CDS_PINID='VPP(4)';
NODE_NAME     J4G3 238
 '@BASEBOARD_FAB2_LIB.BASEBOARD_FAB2(SCH_1):PAGE47_I111@MSTR_SCONN.SCONN288_H44441004(CHIPS)':
 'SA'<2>: CDS_PINID='SA(2)';
NODE_NAME     J4G3 284
 '@BASEBOARD_FAB2_LIB.BASEBOARD_FAB2(SCH_1):PAGE47_I111@MSTR_SCONN.SCONN288_H44441004(CHIPS)':
 'VDDSPD': CDS_PINID='VDDSPD';
NODE_NAME     J4G3 287
 '@BASEBOARD_FAB2_LIB.BASEBOARD_FAB2(SCH_1):PAGE47_I179@MSTR_SCONN.SCONN288_H44441004(CHIPS)':
 'VPP'<0>: CDS_PINID='VPP(0)';
NODE_NAME     J4G3 286
 '@BASEBOARD_FAB2_LIB.BASEBOARD_FAB2(SCH_1):PAGE47_I179@MSTR_SCONN.SCONN288_H44441004(CHIPS)':
 'VPP'<1>: CDS_PINID='VPP(1)';
NODE_NAME     J4G3 288
 '@BASEBOARD_FAB2_LIB.BASEBOARD_FAB2(SCH_1):PAGE47_I179@MSTR_SCONN.SCONN288_H44441004(CHIPS)':
 'VPP'<2>: CDS_PINID='VPP(2)';
NODE_NAME     J4G3 143
 '@BASEBOARD_FAB2_LIB.BASEBOARD_FAB2(SCH_1):PAGE47_I179@MSTR_SCONN.SCONN288_H44441004(CHIPS)':
 'VPP'<3>: CDS_PINID='VPP(3)';
NODE_NAME     J4G3 142
 '@BASEBOARD_FAB2_LIB.BASEBOARD_FAB2(SCH_1):PAGE47_I179@MSTR_SCONN.SCONN288_H44441004(CHIPS)':
 'VPP'<4>: CDS_PINID='VPP(4)';
NODE_NAME     J6U2 139
 '@BASEBOARD_FAB2_LIB.BASEBOARD_FAB2(SCH_1):PAGE48_I111@MSTR_SCONN.SCONN288_H44441003(CHIPS)':
 'SA'<0>: CDS_PINID='SA(0)';
NODE_NAME     J6U2 238
 '@BASEBOARD_FAB2_LIB.BASEBOARD_FAB2(SCH_1):PAGE48_I111@MSTR_SCONN.SCONN288_H44441003(CHIPS)':
 'SA'<2>: CDS_PINID='SA(2)';
NODE_NAME     J6U2 284
 '@BASEBOARD_FAB2_LIB.BASEBOARD_FAB2(SCH_1):PAGE48_I111@MSTR_SCONN.SCONN288_H44441003(CHIPS)':
 'VDDSPD': CDS_PINID='VDDSPD';
NODE_NAME     J6U2 287
 '@BASEBOARD_FAB2_LIB.BASEBOARD_FAB2(SCH_1):PAGE48_I171@MSTR_SCONN.SCONN288_H44441003(CHIPS)':
 'VPP'<0>: CDS_PINID='VPP(0)';
NODE_NAME     J6U2 286
 '@BASEBOARD_FAB2_LIB.BASEBOARD_FAB2(SCH_1):PAGE48_I171@MSTR_SCONN.SCONN288_H44441003(CHIPS)':
 'VPP'<1>: CDS_PINID='VPP(1)';
NODE_NAME     J6U2 288
 '@BASEBOARD_FAB2_LIB.BASEBOARD_FAB2(SCH_1):PAGE48_I171@MSTR_SCONN.SCONN288_H44441003(CHIPS)':
 'VPP'<2>: CDS_PINID='VPP(2)';
NODE_NAME     J6U2 143
 '@BASEBOARD_FAB2_LIB.BASEBOARD_FAB2(SCH_1):PAGE48_I171@MSTR_SCONN.SCONN288_H44441003(CHIPS)':
 'VPP'<3>: CDS_PINID='VPP(3)';
NODE_NAME     J6U2 142
 '@BASEBOARD_FAB2_LIB.BASEBOARD_FAB2(SCH_1):PAGE48_I171@MSTR_SCONN.SCONN288_H44441003(CHIPS)':
 'VPP'<4>: CDS_PINID='VPP(4)';
NODE_NAME     R6F3 1
 '@BASEBOARD_FAB2_LIB.BASEBOARD_FAB2(SCH_1):PAGE89_I7@MSTR_DISCRETE.RES(CHIPS)':
 'A': CDS_PINID='A';
NODE_NAME     J8B1 21
 '@BASEBOARD_FAB2_LIB.BASEBOARD_FAB2(SCH_1):PAGE91_I1@MSTR_SCONN.SCONN24_H46321001(CHIPS)':
 'IO21': CDS_PINID='IO21';
NODE_NAME     R8B8 1
 '@BASEBOARD_FAB2_LIB.BASEBOARD_FAB2(SCH_1):PAGE91_I14@MSTR_DISCRETE.RES(CHIPS)':
 'A': CDS_PINID='A';
NODE_NAME     R8B10 1
 '@BASEBOARD_FAB2_LIB.BASEBOARD_FAB2(SCH_1):PAGE91_I16@MSTR_DISCRETE.RES(CHIPS)':
 'A': CDS_PINID='A';
NODE_NAME     R8B16 1
 '@BASEBOARD_FAB2_LIB.BASEBOARD_FAB2(SCH_1):PAGE91_I17@MSTR_DISCRETE.RES(CHIPS)':
 'A': CDS_PINID='A';
NODE_NAME     R8B17 1
 '@BASEBOARD_FAB2_LIB.BASEBOARD_FAB2(SCH_1):PAGE91_I18@MSTR_DISCRETE.RES(CHIPS)':
 'A': CDS_PINID='A';
NODE_NAME     R8B18 1
 '@BASEBOARD_FAB2_LIB.BASEBOARD_FAB2(SCH_1):PAGE91_I20@MSTR_DISCRETE.RES(CHIPS)':
 'A': CDS_PINID='A';
NODE_NAME     R8B19 1
 '@BASEBOARD_FAB2_LIB.BASEBOARD_FAB2(SCH_1):PAGE91_I21@MSTR_DISCRETE.RES(CHIPS)':
 'A': CDS_PINID='A';
NODE_NAME     R8B5 1
 '@BASEBOARD_FAB2_LIB.BASEBOARD_FAB2(SCH_1):PAGE91_I22@MSTR_DISCRETE.RES(CHIPS)':
 'A': CDS_PINID='A';
NODE_NAME     R8B3 1
 '@BASEBOARD_FAB2_LIB.BASEBOARD_FAB2(SCH_1):PAGE91_I24@MSTR_DISCRETE.RES(CHIPS)':
 'A': CDS_PINID='A';
NODE_NAME     R8B13 1
 '@BASEBOARD_FAB2_LIB.BASEBOARD_FAB2(SCH_1):PAGE91_I34@MSTR_DISCRETE.RES(CHIPS)':
 'A': CDS_PINID='A';
NODE_NAME     R8B11 1
 '@BASEBOARD_FAB2_LIB.BASEBOARD_FAB2(SCH_1):PAGE91_I35@MSTR_DISCRETE.RES(CHIPS)':
 'A': CDS_PINID='A';
NODE_NAME     R8B7 1
 '@BASEBOARD_FAB2_LIB.BASEBOARD_FAB2(SCH_1):PAGE91_I36@MSTR_DISCRETE.RES(CHIPS)':
 'A': CDS_PINID='A';
NODE_NAME     R8B6 1
 '@BASEBOARD_FAB2_LIB.BASEBOARD_FAB2(SCH_1):PAGE91_I37@MSTR_DISCRETE.RES(CHIPS)':
 'A': CDS_PINID='A';
NODE_NAME     R4U3 1
 '@BASEBOARD_FAB2_LIB.BASEBOARD_FAB2(SCH_1):PAGE94_I94@MSTR_DISCRETE.RES(CHIPS)':
 'A': CDS_PINID='A';
NODE_NAME     R4U2 1
 '@BASEBOARD_FAB2_LIB.BASEBOARD_FAB2(SCH_1):PAGE94_I100@MSTR_DISCRETE.RES(CHIPS)':
 'A': CDS_PINID='A';
NODE_NAME     C6F3 1
 '@BASEBOARD_FAB2_LIB.BASEBOARD_FAB2(SCH_1):PAGE99_I7@DEV_DISCRETE.CAP_A(CHIPS)':
 'A': CDS_PINID='A';
NODE_NAME     R4T8 1
 '@BASEBOARD_FAB2_LIB.BASEBOARD_FAB2(SCH_1):PAGE99_I11@MSTR_DISCRETE.RES(CHIPS)':
 'A': CDS_PINID='A';
NODE_NAME     R4T7 1
 '@BASEBOARD_FAB2_LIB.BASEBOARD_FAB2(SCH_1):PAGE99_I13@MSTR_DISCRETE.RES(CHIPS)':
 'A': CDS_PINID='A';
NODE_NAME     U6F1 8
 '@BASEBOARD_FAB2_LIB.BASEBOARD_FAB2(SCH_1):PAGE99_I15@MSTR_DIGITAL.PCA9617(CHIPS)':
 'VCCB': CDS_PINID='VCCB';
NODE_NAME     R3R16 1
 '@BASEBOARD_FAB2_LIB.BASEBOARD_FAB2(SCH_1):PAGE192_I48@MSTR_DISCRETE.RES(CHIPS)':
 'A': CDS_PINID='A';
NODE_NAME     C6F6 1
 '@BASEBOARD_FAB2_LIB.BASEBOARD_FAB2(SCH_1):PAGE231_I122@MSTR_DISCRETE.CAP(CHIPS)':
 'A': CDS_PINID='A';
NODE_NAME     C4T6 1
 '@BASEBOARD_FAB2_LIB.BASEBOARD_FAB2(SCH_1):PAGE231_I124@MSTR_DISCRETE.CAP(CHIPS)':
 'A': CDS_PINID='A';
NODE_NAME     C4T5 1
 '@BASEBOARD_FAB2_LIB.BASEBOARD_FAB2(SCH_1):PAGE231_I125@MSTR_DISCRETE.CAP(CHIPS)':
 'A': CDS_PINID='A';
NODE_NAME     C6G1 1
 '@BASEBOARD_FAB2_LIB.BASEBOARD_FAB2(SCH_1):PAGE231_I126@MSTR_DISCRETE.CAP(CHIPS)':
 'A': CDS_PINID='A';
NODE_NAME     C6G2 1
 '@BASEBOARD_FAB2_LIB.BASEBOARD_FAB2(SCH_1):PAGE231_I128@MSTR_DISCRETE.CAP(CHIPS)':
 'A': CDS_PINID='A';
NODE_NAME     C4U2 1
 '@BASEBOARD_FAB2_LIB.BASEBOARD_FAB2(SCH_1):PAGE231_I129@MSTR_DISCRETE.CAP(CHIPS)':
 'A': CDS_PINID='A';
NODE_NAME     C4U1 1
 '@BASEBOARD_FAB2_LIB.BASEBOARD_FAB2(SCH_1):PAGE231_I130@MSTR_DISCRETE.CAP(CHIPS)':
 'A': CDS_PINID='A';
NODE_NAME     C6G4 1
 '@BASEBOARD_FAB2_LIB.BASEBOARD_FAB2(SCH_1):PAGE231_I131@MSTR_DISCRETE.CAP(CHIPS)':
 'A': CDS_PINID='A';
NODE_NAME     C6G5 1
 '@BASEBOARD_FAB2_LIB.BASEBOARD_FAB2(SCH_1):PAGE231_I145@MSTR_DISCRETE.CAP(CHIPS)':
 'A': CDS_PINID='A';
NODE_NAME     C4U4 1
 '@BASEBOARD_FAB2_LIB.BASEBOARD_FAB2(SCH_1):PAGE231_I146@MSTR_DISCRETE.CAP(CHIPS)':
 'A': CDS_PINID='A';
NODE_NAME     C4U3 1
 '@BASEBOARD_FAB2_LIB.BASEBOARD_FAB2(SCH_1):PAGE231_I148@MSTR_DISCRETE.CAP(CHIPS)':
 'A': CDS_PINID='A';
NODE_NAME     C6F5 1
 '@BASEBOARD_FAB2_LIB.BASEBOARD_FAB2(SCH_1):PAGE231_I149@MSTR_DISCRETE.CAP(CHIPS)':
 'A': CDS_PINID='A';
NODE_NAME     R7F12 1
 '@BASEBOARD_FAB2_LIB.BASEBOARD_FAB2(SCH_1):PAGE231_I168@MSTR_DISCRETE.RES(CHIPS)':
 'A': CDS_PINID='A';
NODE_NAME     R7F10 1
 '@BASEBOARD_FAB2_LIB.BASEBOARD_FAB2(SCH_1):PAGE231_I177@MSTR_DISCRETE.RES(CHIPS)':
 'A': CDS_PINID='A';
NODE_NAME     L7F1 2
 '@BASEBOARD_FAB2_LIB.BASEBOARD_FAB2(SCH_1):PAGE231_I178@MSTR_DISCRETE.INDUCTOR(CHIPS)':
 'INB': CDS_PINID='INB';
NODE_NAME     C6F4 1
 '@BASEBOARD_FAB2_LIB.BASEBOARD_FAB2(SCH_1):PAGE231_I180@MSTR_DISCRETE.CAPP(CHIPS)':
 'A': CDS_PINID='A';
NODE_NAME     C3T7 1
 '@BASEBOARD_FAB2_LIB.BASEBOARD_FAB2(SCH_1):PAGE231_I184@MSTR_DISCRETE.CAP(CHIPS)':
 'A': CDS_PINID='A';
NODE_NAME     C3T9 1
 '@BASEBOARD_FAB2_LIB.BASEBOARD_FAB2(SCH_1):PAGE231_I186@MSTR_DISCRETE.CAP(CHIPS)':
 'A': CDS_PINID='A';
NODE_NAME     C4T3 1
 '@BASEBOARD_FAB2_LIB.BASEBOARD_FAB2(SCH_1):PAGE231_I217@MSTR_DISCRETE.CAPP(CHIPS)':
 'A': CDS_PINID='A';
NODE_NAME     R6W29 1
 '@BASEBOARD_FAB2_LIB.BASEBOARD_FAB2(SCH_1):PAGE89_I40@MSTR_DISCRETE.RES(CHIPS)':
 'A': CDS_PINID='A';
NET_NAME
'PVPP_DEF'
 '@BASEBOARD_FAB2_LIB.BASEBOARD_FAB2(SCH_1):PVPP_DEF':
 C_SIGNAL='@baseboard_fab2_lib.baseboard_fab2(sch_1):pvpp_def';
NODE_NAME     J4B1 284
 '@BASEBOARD_FAB2_LIB.BASEBOARD_FAB2(SCH_1):PAGE49_I111@MSTR_SCONN.SCONN288_H44441004(CHIPS)':
 'VDDSPD': CDS_PINID='VDDSPD';
NODE_NAME     J4B1 287
 '@BASEBOARD_FAB2_LIB.BASEBOARD_FAB2(SCH_1):PAGE49_I169@MSTR_SCONN.SCONN288_H44441004(CHIPS)':
 'VPP'<0>: CDS_PINID='VPP(0)';
NODE_NAME     J4B1 286
 '@BASEBOARD_FAB2_LIB.BASEBOARD_FAB2(SCH_1):PAGE49_I169@MSTR_SCONN.SCONN288_H44441004(CHIPS)':
 'VPP'<1>: CDS_PINID='VPP(1)';
NODE_NAME     J4B1 288
 '@BASEBOARD_FAB2_LIB.BASEBOARD_FAB2(SCH_1):PAGE49_I169@MSTR_SCONN.SCONN288_H44441004(CHIPS)':
 'VPP'<2>: CDS_PINID='VPP(2)';
NODE_NAME     J4B1 143
 '@BASEBOARD_FAB2_LIB.BASEBOARD_FAB2(SCH_1):PAGE49_I169@MSTR_SCONN.SCONN288_H44441004(CHIPS)':
 'VPP'<3>: CDS_PINID='VPP(3)';
NODE_NAME     J4B1 142
 '@BASEBOARD_FAB2_LIB.BASEBOARD_FAB2(SCH_1):PAGE49_I169@MSTR_SCONN.SCONN288_H44441004(CHIPS)':
 'VPP'<4>: CDS_PINID='VPP(4)';
NODE_NAME     J6M1 287
 '@BASEBOARD_FAB2_LIB.BASEBOARD_FAB2(SCH_1):PAGE50_I50@MSTR_SCONN.SCONN288_H44441003(CHIPS)':
 'VPP'<0>: CDS_PINID='VPP(0)';
NODE_NAME     J6M1 286
 '@BASEBOARD_FAB2_LIB.BASEBOARD_FAB2(SCH_1):PAGE50_I50@MSTR_SCONN.SCONN288_H44441003(CHIPS)':
 'VPP'<1>: CDS_PINID='VPP(1)';
NODE_NAME     J6M1 288
 '@BASEBOARD_FAB2_LIB.BASEBOARD_FAB2(SCH_1):PAGE50_I50@MSTR_SCONN.SCONN288_H44441003(CHIPS)':
 'VPP'<2>: CDS_PINID='VPP(2)';
NODE_NAME     J6M1 143
 '@BASEBOARD_FAB2_LIB.BASEBOARD_FAB2(SCH_1):PAGE50_I50@MSTR_SCONN.SCONN288_H44441003(CHIPS)':
 'VPP'<3>: CDS_PINID='VPP(3)';
NODE_NAME     J6M1 142
 '@BASEBOARD_FAB2_LIB.BASEBOARD_FAB2(SCH_1):PAGE50_I50@MSTR_SCONN.SCONN288_H44441003(CHIPS)':
 'VPP'<4>: CDS_PINID='VPP(4)';
NODE_NAME     J6M1 139
 '@BASEBOARD_FAB2_LIB.BASEBOARD_FAB2(SCH_1):PAGE50_I158@MSTR_SCONN.SCONN288_H44441003(CHIPS)':
 'SA'<0>: CDS_PINID='SA(0)';
NODE_NAME     J6M1 284
 '@BASEBOARD_FAB2_LIB.BASEBOARD_FAB2(SCH_1):PAGE50_I158@MSTR_SCONN.SCONN288_H44441003(CHIPS)':
 'VDDSPD': CDS_PINID='VDDSPD';
NODE_NAME     J4A2 140
 '@BASEBOARD_FAB2_LIB.BASEBOARD_FAB2(SCH_1):PAGE51_I111@MSTR_SCONN.SCONN288_H44441004(CHIPS)':
 'SA'<1>: CDS_PINID='SA(1)';
NODE_NAME     J4A2 284
 '@BASEBOARD_FAB2_LIB.BASEBOARD_FAB2(SCH_1):PAGE51_I111@MSTR_SCONN.SCONN288_H44441004(CHIPS)':
 'VDDSPD': CDS_PINID='VDDSPD';
NODE_NAME     J4A2 287
 '@BASEBOARD_FAB2_LIB.BASEBOARD_FAB2(SCH_1):PAGE51_I167@MSTR_SCONN.SCONN288_H44441004(CHIPS)':
 'VPP'<0>: CDS_PINID='VPP(0)';
NODE_NAME     J4A2 286
 '@BASEBOARD_FAB2_LIB.BASEBOARD_FAB2(SCH_1):PAGE51_I167@MSTR_SCONN.SCONN288_H44441004(CHIPS)':
 'VPP'<1>: CDS_PINID='VPP(1)';
NODE_NAME     J4A2 288
 '@BASEBOARD_FAB2_LIB.BASEBOARD_FAB2(SCH_1):PAGE51_I167@MSTR_SCONN.SCONN288_H44441004(CHIPS)':
 'VPP'<2>: CDS_PINID='VPP(2)';
NODE_NAME     J4A2 143
 '@BASEBOARD_FAB2_LIB.BASEBOARD_FAB2(SCH_1):PAGE51_I167@MSTR_SCONN.SCONN288_H44441004(CHIPS)':
 'VPP'<3>: CDS_PINID='VPP(3)';
NODE_NAME     J4A2 142
 '@BASEBOARD_FAB2_LIB.BASEBOARD_FAB2(SCH_1):PAGE51_I167@MSTR_SCONN.SCONN288_H44441004(CHIPS)':
 'VPP'<4>: CDS_PINID='VPP(4)';
NODE_NAME     J6L2 139
 '@BASEBOARD_FAB2_LIB.BASEBOARD_FAB2(SCH_1):PAGE52_I12@MSTR_SCONN.SCONN288_H44441003(CHIPS)':
 'SA'<0>: CDS_PINID='SA(0)';
NODE_NAME     J6L2 140
 '@BASEBOARD_FAB2_LIB.BASEBOARD_FAB2(SCH_1):PAGE52_I12@MSTR_SCONN.SCONN288_H44441003(CHIPS)':
 'SA'<1>: CDS_PINID='SA(1)';
NODE_NAME     J6L2 284
 '@BASEBOARD_FAB2_LIB.BASEBOARD_FAB2(SCH_1):PAGE52_I12@MSTR_SCONN.SCONN288_H44441003(CHIPS)':
 'VDDSPD': CDS_PINID='VDDSPD';
NODE_NAME     J6L2 287
 '@BASEBOARD_FAB2_LIB.BASEBOARD_FAB2(SCH_1):PAGE52_I55@MSTR_SCONN.SCONN288_H44441003(CHIPS)':
 'VPP'<0>: CDS_PINID='VPP(0)';
NODE_NAME     J6L2 286
 '@BASEBOARD_FAB2_LIB.BASEBOARD_FAB2(SCH_1):PAGE52_I55@MSTR_SCONN.SCONN288_H44441003(CHIPS)':
 'VPP'<1>: CDS_PINID='VPP(1)';
NODE_NAME     J6L2 288
 '@BASEBOARD_FAB2_LIB.BASEBOARD_FAB2(SCH_1):PAGE52_I55@MSTR_SCONN.SCONN288_H44441003(CHIPS)':
 'VPP'<2>: CDS_PINID='VPP(2)';
NODE_NAME     J6L2 143
 '@BASEBOARD_FAB2_LIB.BASEBOARD_FAB2(SCH_1):PAGE52_I55@MSTR_SCONN.SCONN288_H44441003(CHIPS)':
 'VPP'<3>: CDS_PINID='VPP(3)';
NODE_NAME     J6L2 142
 '@BASEBOARD_FAB2_LIB.BASEBOARD_FAB2(SCH_1):PAGE52_I55@MSTR_SCONN.SCONN288_H44441003(CHIPS)':
 'VPP'<4>: CDS_PINID='VPP(4)';
NODE_NAME     J4A1 238
 '@BASEBOARD_FAB2_LIB.BASEBOARD_FAB2(SCH_1):PAGE53_I111@MSTR_SCONN.SCONN288_H44441004(CHIPS)':
 'SA'<2>: CDS_PINID='SA(2)';
NODE_NAME     J4A1 284
 '@BASEBOARD_FAB2_LIB.BASEBOARD_FAB2(SCH_1):PAGE53_I111@MSTR_SCONN.SCONN288_H44441004(CHIPS)':
 'VDDSPD': CDS_PINID='VDDSPD';
NODE_NAME     J4A1 287
 '@BASEBOARD_FAB2_LIB.BASEBOARD_FAB2(SCH_1):PAGE53_I171@MSTR_SCONN.SCONN288_H44441004(CHIPS)':
 'VPP'<0>: CDS_PINID='VPP(0)';
NODE_NAME     J4A1 286
 '@BASEBOARD_FAB2_LIB.BASEBOARD_FAB2(SCH_1):PAGE53_I171@MSTR_SCONN.SCONN288_H44441004(CHIPS)':
 'VPP'<1>: CDS_PINID='VPP(1)';
NODE_NAME     J4A1 288
 '@BASEBOARD_FAB2_LIB.BASEBOARD_FAB2(SCH_1):PAGE53_I171@MSTR_SCONN.SCONN288_H44441004(CHIPS)':
 'VPP'<2>: CDS_PINID='VPP(2)';
NODE_NAME     J4A1 143
 '@BASEBOARD_FAB2_LIB.BASEBOARD_FAB2(SCH_1):PAGE53_I171@MSTR_SCONN.SCONN288_H44441004(CHIPS)':
 'VPP'<3>: CDS_PINID='VPP(3)';
NODE_NAME     J4A1 142
 '@BASEBOARD_FAB2_LIB.BASEBOARD_FAB2(SCH_1):PAGE53_I171@MSTR_SCONN.SCONN288_H44441004(CHIPS)':
 'VPP'<4>: CDS_PINID='VPP(4)';
NODE_NAME     J6L1 139
 '@BASEBOARD_FAB2_LIB.BASEBOARD_FAB2(SCH_1):PAGE54_I111@MSTR_SCONN.SCONN288_H44441003(CHIPS)':
 'SA'<0>: CDS_PINID='SA(0)';
NODE_NAME     J6L1 238
 '@BASEBOARD_FAB2_LIB.BASEBOARD_FAB2(SCH_1):PAGE54_I111@MSTR_SCONN.SCONN288_H44441003(CHIPS)':
 'SA'<2>: CDS_PINID='SA(2)';
NODE_NAME     J6L1 284
 '@BASEBOARD_FAB2_LIB.BASEBOARD_FAB2(SCH_1):PAGE54_I111@MSTR_SCONN.SCONN288_H44441003(CHIPS)':
 'VDDSPD': CDS_PINID='VDDSPD';
NODE_NAME     J6L1 287
 '@BASEBOARD_FAB2_LIB.BASEBOARD_FAB2(SCH_1):PAGE54_I170@MSTR_SCONN.SCONN288_H44441003(CHIPS)':
 'VPP'<0>: CDS_PINID='VPP(0)';
NODE_NAME     J6L1 286
 '@BASEBOARD_FAB2_LIB.BASEBOARD_FAB2(SCH_1):PAGE54_I170@MSTR_SCONN.SCONN288_H44441003(CHIPS)':
 'VPP'<1>: CDS_PINID='VPP(1)';
NODE_NAME     J6L1 288
 '@BASEBOARD_FAB2_LIB.BASEBOARD_FAB2(SCH_1):PAGE54_I170@MSTR_SCONN.SCONN288_H44441003(CHIPS)':
 'VPP'<2>: CDS_PINID='VPP(2)';
NODE_NAME     J6L1 143
 '@BASEBOARD_FAB2_LIB.BASEBOARD_FAB2(SCH_1):PAGE54_I170@MSTR_SCONN.SCONN288_H44441003(CHIPS)':
 'VPP'<3>: CDS_PINID='VPP(3)';
NODE_NAME     J6L1 142
 '@BASEBOARD_FAB2_LIB.BASEBOARD_FAB2(SCH_1):PAGE54_I170@MSTR_SCONN.SCONN288_H44441003(CHIPS)':
 'VPP'<4>: CDS_PINID='VPP(4)';
NODE_NAME     C7E2 1
 '@BASEBOARD_FAB2_LIB.BASEBOARD_FAB2(SCH_1):PAGE99_I32@DEV_DISCRETE.CAP_A(CHIPS)':
 'A': CDS_PINID='A';
NODE_NAME     U7E1 8
 '@BASEBOARD_FAB2_LIB.BASEBOARD_FAB2(SCH_1):PAGE99_I61@MSTR_DIGITAL.PCA9617(CHIPS)':
 'VCCB': CDS_PINID='VCCB';
NODE_NAME     R3R12 1
 '@BASEBOARD_FAB2_LIB.BASEBOARD_FAB2(SCH_1):PAGE99_I101@MSTR_DISCRETE.RES(CHIPS)':
 'A': CDS_PINID='A';
NODE_NAME     R3R5 1
 '@BASEBOARD_FAB2_LIB.BASEBOARD_FAB2(SCH_1):PAGE99_I103@MSTR_DISCRETE.RES(CHIPS)':
 'A': CDS_PINID='A';
NODE_NAME     C4L2 1
 '@BASEBOARD_FAB2_LIB.BASEBOARD_FAB2(SCH_1):PAGE232_I102@MSTR_DISCRETE.CAP(CHIPS)':
 'A': CDS_PINID='A';
NODE_NAME     C6A3 1
 '@BASEBOARD_FAB2_LIB.BASEBOARD_FAB2(SCH_1):PAGE232_I104@MSTR_DISCRETE.CAP(CHIPS)':
 'A': CDS_PINID='A';
NODE_NAME     C6A2 1
 '@BASEBOARD_FAB2_LIB.BASEBOARD_FAB2(SCH_1):PAGE232_I105@MSTR_DISCRETE.CAP(CHIPS)':
 'A': CDS_PINID='A';
NODE_NAME     C4L3 1
 '@BASEBOARD_FAB2_LIB.BASEBOARD_FAB2(SCH_1):PAGE232_I106@MSTR_DISCRETE.CAP(CHIPS)':
 'A': CDS_PINID='A';
NODE_NAME     C4L4 1
 '@BASEBOARD_FAB2_LIB.BASEBOARD_FAB2(SCH_1):PAGE232_I108@MSTR_DISCRETE.CAP(CHIPS)':
 'A': CDS_PINID='A';
NODE_NAME     C6A7 1
 '@BASEBOARD_FAB2_LIB.BASEBOARD_FAB2(SCH_1):PAGE232_I109@MSTR_DISCRETE.CAP(CHIPS)':
 'A': CDS_PINID='A';
NODE_NAME     C6A6 1
 '@BASEBOARD_FAB2_LIB.BASEBOARD_FAB2(SCH_1):PAGE232_I110@MSTR_DISCRETE.CAP(CHIPS)':
 'A': CDS_PINID='A';
NODE_NAME     C4M3 1
 '@BASEBOARD_FAB2_LIB.BASEBOARD_FAB2(SCH_1):PAGE232_I111@MSTR_DISCRETE.CAP(CHIPS)':
 'A': CDS_PINID='A';
NODE_NAME     C4M4 1
 '@BASEBOARD_FAB2_LIB.BASEBOARD_FAB2(SCH_1):PAGE232_I125@MSTR_DISCRETE.CAP(CHIPS)':
 'A': CDS_PINID='A';
NODE_NAME     C6B2 1
 '@BASEBOARD_FAB2_LIB.BASEBOARD_FAB2(SCH_1):PAGE232_I126@MSTR_DISCRETE.CAP(CHIPS)':
 'A': CDS_PINID='A';
NODE_NAME     C6B1 1
 '@BASEBOARD_FAB2_LIB.BASEBOARD_FAB2(SCH_1):PAGE232_I128@MSTR_DISCRETE.CAP(CHIPS)':
 'A': CDS_PINID='A';
NODE_NAME     C4L1 1
 '@BASEBOARD_FAB2_LIB.BASEBOARD_FAB2(SCH_1):PAGE232_I129@MSTR_DISCRETE.CAP(CHIPS)':
 'A': CDS_PINID='A';
NODE_NAME     R7B10 1
 '@BASEBOARD_FAB2_LIB.BASEBOARD_FAB2(SCH_1):PAGE232_I227@MSTR_DISCRETE.RES(CHIPS)':
 'A': CDS_PINID='A';
NODE_NAME     C6B7 1
 '@BASEBOARD_FAB2_LIB.BASEBOARD_FAB2(SCH_1):PAGE232_I229@MSTR_DISCRETE.CAPP(CHIPS)':
 'A': CDS_PINID='A';
NODE_NAME     C6B3 1
 '@BASEBOARD_FAB2_LIB.BASEBOARD_FAB2(SCH_1):PAGE232_I236@MSTR_DISCRETE.CAP(CHIPS)':
 'A': CDS_PINID='A';
NODE_NAME     C7B7 1
 '@BASEBOARD_FAB2_LIB.BASEBOARD_FAB2(SCH_1):PAGE232_I238@MSTR_DISCRETE.CAP(CHIPS)':
 'A': CDS_PINID='A';
NODE_NAME     L7B1 2
 '@BASEBOARD_FAB2_LIB.BASEBOARD_FAB2(SCH_1):PAGE232_I239@MSTR_DISCRETE.INDUCTOR(CHIPS)':
 'INB': CDS_PINID='INB';
NODE_NAME     C4M1 1
 '@BASEBOARD_FAB2_LIB.BASEBOARD_FAB2(SCH_1):PAGE232_I267@MSTR_DISCRETE.CAPP(CHIPS)':
 'A': CDS_PINID='A';
NODE_NAME     R7B11 1
 '@BASEBOARD_FAB2_LIB.BASEBOARD_FAB2(SCH_1):PAGE232_I299@MSTR_DISCRETE.RES(CHIPS)':
 'A': CDS_PINID='A';
NET_NAME
'PVPP_GHJ'
 '@BASEBOARD_FAB2_LIB.BASEBOARD_FAB2(SCH_1):PVPP_GHJ':
 C_SIGNAL='@baseboard_fab2_lib.baseboard_fab2(sch_1):pvpp_ghj';
NODE_NAME     U2D1 B11
 '@BASEBOARD_FAB2_LIB.BASEBOARD_FAB2(SCH_1):PAGE72_I33@CHPSET_LIB.SKX_EXT_B(CHIPS)':
 'CD_VPP'<0>: CDS_PINID='CD_VPP(0)';
NODE_NAME     U2D1 A12
 '@BASEBOARD_FAB2_LIB.BASEBOARD_FAB2(SCH_1):PAGE72_I33@CHPSET_LIB.SKX_EXT_B(CHIPS)':
 'CD_VPP'<1>: CDS_PINID='CD_VPP(1)';
NODE_NAME     U2D1 A10
 '@BASEBOARD_FAB2_LIB.BASEBOARD_FAB2(SCH_1):PAGE72_I33@CHPSET_LIB.SKX_EXT_B(CHIPS)':
 'CD_VPP'<2>: CDS_PINID='CD_VPP(2)';
NODE_NAME     U2D1 A8
 '@BASEBOARD_FAB2_LIB.BASEBOARD_FAB2(SCH_1):PAGE72_I33@CHPSET_LIB.SKX_EXT_B(CHIPS)':
 'CD_VPP'<3>: CDS_PINID='CD_VPP(3)';
NODE_NAME     J1G1 284
 '@BASEBOARD_FAB2_LIB.BASEBOARD_FAB2(SCH_1):PAGE77_I111@MSTR_SCONN.SCONN288_H44441004(CHIPS)':
 'VDDSPD': CDS_PINID='VDDSPD';
NODE_NAME     J1G1 287
 '@BASEBOARD_FAB2_LIB.BASEBOARD_FAB2(SCH_1):PAGE77_I171@MSTR_SCONN.SCONN288_H44441004(CHIPS)':
 'VPP'<0>: CDS_PINID='VPP(0)';
NODE_NAME     J1G1 286
 '@BASEBOARD_FAB2_LIB.BASEBOARD_FAB2(SCH_1):PAGE77_I171@MSTR_SCONN.SCONN288_H44441004(CHIPS)':
 'VPP'<1>: CDS_PINID='VPP(1)';
NODE_NAME     J1G1 288
 '@BASEBOARD_FAB2_LIB.BASEBOARD_FAB2(SCH_1):PAGE77_I171@MSTR_SCONN.SCONN288_H44441004(CHIPS)':
 'VPP'<2>: CDS_PINID='VPP(2)';
NODE_NAME     J1G1 143
 '@BASEBOARD_FAB2_LIB.BASEBOARD_FAB2(SCH_1):PAGE77_I171@MSTR_SCONN.SCONN288_H44441004(CHIPS)':
 'VPP'<3>: CDS_PINID='VPP(3)';
NODE_NAME     J1G1 142
 '@BASEBOARD_FAB2_LIB.BASEBOARD_FAB2(SCH_1):PAGE77_I171@MSTR_SCONN.SCONN288_H44441004(CHIPS)':
 'VPP'<4>: CDS_PINID='VPP(4)';
NODE_NAME     J9T1 139
 '@BASEBOARD_FAB2_LIB.BASEBOARD_FAB2(SCH_1):PAGE78_I13@MSTR_SCONN.SCONN288_H44441003(CHIPS)':
 'SA'<0>: CDS_PINID='SA(0)';
NODE_NAME     J9T1 284
 '@BASEBOARD_FAB2_LIB.BASEBOARD_FAB2(SCH_1):PAGE78_I13@MSTR_SCONN.SCONN288_H44441003(CHIPS)':
 'VDDSPD': CDS_PINID='VDDSPD';
NODE_NAME     J9T1 287
 '@BASEBOARD_FAB2_LIB.BASEBOARD_FAB2(SCH_1):PAGE78_I75@MSTR_SCONN.SCONN288_H44441003(CHIPS)':
 'VPP'<0>: CDS_PINID='VPP(0)';
NODE_NAME     J9T1 286
 '@BASEBOARD_FAB2_LIB.BASEBOARD_FAB2(SCH_1):PAGE78_I75@MSTR_SCONN.SCONN288_H44441003(CHIPS)':
 'VPP'<1>: CDS_PINID='VPP(1)';
NODE_NAME     J9T1 288
 '@BASEBOARD_FAB2_LIB.BASEBOARD_FAB2(SCH_1):PAGE78_I75@MSTR_SCONN.SCONN288_H44441003(CHIPS)':
 'VPP'<2>: CDS_PINID='VPP(2)';
NODE_NAME     J9T1 143
 '@BASEBOARD_FAB2_LIB.BASEBOARD_FAB2(SCH_1):PAGE78_I75@MSTR_SCONN.SCONN288_H44441003(CHIPS)':
 'VPP'<3>: CDS_PINID='VPP(3)';
NODE_NAME     J9T1 142
 '@BASEBOARD_FAB2_LIB.BASEBOARD_FAB2(SCH_1):PAGE78_I75@MSTR_SCONN.SCONN288_H44441003(CHIPS)':
 'VPP'<4>: CDS_PINID='VPP(4)';
NODE_NAME     J1G2 140
 '@BASEBOARD_FAB2_LIB.BASEBOARD_FAB2(SCH_1):PAGE79_I111@MSTR_SCONN.SCONN288_H44441004(CHIPS)':
 'SA'<1>: CDS_PINID='SA(1)';
NODE_NAME     J1G2 284
 '@BASEBOARD_FAB2_LIB.BASEBOARD_FAB2(SCH_1):PAGE79_I111@MSTR_SCONN.SCONN288_H44441004(CHIPS)':
 'VDDSPD': CDS_PINID='VDDSPD';
NODE_NAME     J1G2 287
 '@BASEBOARD_FAB2_LIB.BASEBOARD_FAB2(SCH_1):PAGE79_I169@MSTR_SCONN.SCONN288_H44441004(CHIPS)':
 'VPP'<0>: CDS_PINID='VPP(0)';
NODE_NAME     J1G2 286
 '@BASEBOARD_FAB2_LIB.BASEBOARD_FAB2(SCH_1):PAGE79_I169@MSTR_SCONN.SCONN288_H44441004(CHIPS)':
 'VPP'<1>: CDS_PINID='VPP(1)';
NODE_NAME     J1G2 288
 '@BASEBOARD_FAB2_LIB.BASEBOARD_FAB2(SCH_1):PAGE79_I169@MSTR_SCONN.SCONN288_H44441004(CHIPS)':
 'VPP'<2>: CDS_PINID='VPP(2)';
NODE_NAME     J1G2 143
 '@BASEBOARD_FAB2_LIB.BASEBOARD_FAB2(SCH_1):PAGE79_I169@MSTR_SCONN.SCONN288_H44441004(CHIPS)':
 'VPP'<3>: CDS_PINID='VPP(3)';
NODE_NAME     J1G2 142
 '@BASEBOARD_FAB2_LIB.BASEBOARD_FAB2(SCH_1):PAGE79_I169@MSTR_SCONN.SCONN288_H44441004(CHIPS)':
 'VPP'<4>: CDS_PINID='VPP(4)';
NODE_NAME     J9U1 139
 '@BASEBOARD_FAB2_LIB.BASEBOARD_FAB2(SCH_1):PAGE80_I24@MSTR_SCONN.SCONN288_H44441003(CHIPS)':
 'SA'<0>: CDS_PINID='SA(0)';
NODE_NAME     J9U1 140
 '@BASEBOARD_FAB2_LIB.BASEBOARD_FAB2(SCH_1):PAGE80_I24@MSTR_SCONN.SCONN288_H44441003(CHIPS)':
 'SA'<1>: CDS_PINID='SA(1)';
NODE_NAME     J9U1 284
 '@BASEBOARD_FAB2_LIB.BASEBOARD_FAB2(SCH_1):PAGE80_I24@MSTR_SCONN.SCONN288_H44441003(CHIPS)':
 'VDDSPD': CDS_PINID='VDDSPD';
NODE_NAME     J9U1 287
 '@BASEBOARD_FAB2_LIB.BASEBOARD_FAB2(SCH_1):PAGE80_I56@MSTR_SCONN.SCONN288_H44441003(CHIPS)':
 'VPP'<0>: CDS_PINID='VPP(0)';
NODE_NAME     J9U1 286
 '@BASEBOARD_FAB2_LIB.BASEBOARD_FAB2(SCH_1):PAGE80_I56@MSTR_SCONN.SCONN288_H44441003(CHIPS)':
 'VPP'<1>: CDS_PINID='VPP(1)';
NODE_NAME     J9U1 288
 '@BASEBOARD_FAB2_LIB.BASEBOARD_FAB2(SCH_1):PAGE80_I56@MSTR_SCONN.SCONN288_H44441003(CHIPS)':
 'VPP'<2>: CDS_PINID='VPP(2)';
NODE_NAME     J9U1 143
 '@BASEBOARD_FAB2_LIB.BASEBOARD_FAB2(SCH_1):PAGE80_I56@MSTR_SCONN.SCONN288_H44441003(CHIPS)':
 'VPP'<3>: CDS_PINID='VPP(3)';
NODE_NAME     J9U1 142
 '@BASEBOARD_FAB2_LIB.BASEBOARD_FAB2(SCH_1):PAGE80_I56@MSTR_SCONN.SCONN288_H44441003(CHIPS)':
 'VPP'<4>: CDS_PINID='VPP(4)';
NODE_NAME     J1G3 287
 '@BASEBOARD_FAB2_LIB.BASEBOARD_FAB2(SCH_1):PAGE81_I169@MSTR_SCONN.SCONN288_H44441004(CHIPS)':
 'VPP'<0>: CDS_PINID='VPP(0)';
NODE_NAME     J1G3 286
 '@BASEBOARD_FAB2_LIB.BASEBOARD_FAB2(SCH_1):PAGE81_I169@MSTR_SCONN.SCONN288_H44441004(CHIPS)':
 'VPP'<1>: CDS_PINID='VPP(1)';
NODE_NAME     J1G3 288
 '@BASEBOARD_FAB2_LIB.BASEBOARD_FAB2(SCH_1):PAGE81_I169@MSTR_SCONN.SCONN288_H44441004(CHIPS)':
 'VPP'<2>: CDS_PINID='VPP(2)';
NODE_NAME     J1G3 143
 '@BASEBOARD_FAB2_LIB.BASEBOARD_FAB2(SCH_1):PAGE81_I169@MSTR_SCONN.SCONN288_H44441004(CHIPS)':
 'VPP'<3>: CDS_PINID='VPP(3)';
NODE_NAME     J1G3 142
 '@BASEBOARD_FAB2_LIB.BASEBOARD_FAB2(SCH_1):PAGE81_I169@MSTR_SCONN.SCONN288_H44441004(CHIPS)':
 'VPP'<4>: CDS_PINID='VPP(4)';
NODE_NAME     J1G3 238
 '@BASEBOARD_FAB2_LIB.BASEBOARD_FAB2(SCH_1):PAGE81_I186@MSTR_SCONN.SCONN288_H44441004(CHIPS)':
 'SA'<2>: CDS_PINID='SA(2)';
NODE_NAME     J1G3 284
 '@BASEBOARD_FAB2_LIB.BASEBOARD_FAB2(SCH_1):PAGE81_I186@MSTR_SCONN.SCONN288_H44441004(CHIPS)':
 'VDDSPD': CDS_PINID='VDDSPD';
NODE_NAME     J9U2 287
 '@BASEBOARD_FAB2_LIB.BASEBOARD_FAB2(SCH_1):PAGE82_I171@MSTR_SCONN.SCONN288_H44441003(CHIPS)':
 'VPP'<0>: CDS_PINID='VPP(0)';
NODE_NAME     J9U2 286
 '@BASEBOARD_FAB2_LIB.BASEBOARD_FAB2(SCH_1):PAGE82_I171@MSTR_SCONN.SCONN288_H44441003(CHIPS)':
 'VPP'<1>: CDS_PINID='VPP(1)';
NODE_NAME     J9U2 288
 '@BASEBOARD_FAB2_LIB.BASEBOARD_FAB2(SCH_1):PAGE82_I171@MSTR_SCONN.SCONN288_H44441003(CHIPS)':
 'VPP'<2>: CDS_PINID='VPP(2)';
NODE_NAME     J9U2 143
 '@BASEBOARD_FAB2_LIB.BASEBOARD_FAB2(SCH_1):PAGE82_I171@MSTR_SCONN.SCONN288_H44441003(CHIPS)':
 'VPP'<3>: CDS_PINID='VPP(3)';
NODE_NAME     J9U2 142
 '@BASEBOARD_FAB2_LIB.BASEBOARD_FAB2(SCH_1):PAGE82_I171@MSTR_SCONN.SCONN288_H44441003(CHIPS)':
 'VPP'<4>: CDS_PINID='VPP(4)';
NODE_NAME     J9U2 139
 '@BASEBOARD_FAB2_LIB.BASEBOARD_FAB2(SCH_1):PAGE82_I187@MSTR_SCONN.SCONN288_H44441003(CHIPS)':
 'SA'<0>: CDS_PINID='SA(0)';
NODE_NAME     J9U2 238
 '@BASEBOARD_FAB2_LIB.BASEBOARD_FAB2(SCH_1):PAGE82_I187@MSTR_SCONN.SCONN288_H44441003(CHIPS)':
 'SA'<2>: CDS_PINID='SA(2)';
NODE_NAME     J9U2 284
 '@BASEBOARD_FAB2_LIB.BASEBOARD_FAB2(SCH_1):PAGE82_I187@MSTR_SCONN.SCONN288_H44441003(CHIPS)':
 'VDDSPD': CDS_PINID='VDDSPD';
NODE_NAME     C4G25 1
 '@BASEBOARD_FAB2_LIB.BASEBOARD_FAB2(SCH_1):PAGE99_I41@DEV_DISCRETE.CAP_A(CHIPS)':
 'A': CDS_PINID='A';
NODE_NAME     U4G1 8
 '@BASEBOARD_FAB2_LIB.BASEBOARD_FAB2(SCH_1):PAGE99_I63@MSTR_DIGITAL.PCA9617(CHIPS)':
 'VCCB': CDS_PINID='VCCB';
NODE_NAME     R6U18 1
 '@BASEBOARD_FAB2_LIB.BASEBOARD_FAB2(SCH_1):PAGE99_I104@MSTR_DISCRETE.RES(CHIPS)':
 'A': CDS_PINID='A';
NODE_NAME     R6U17 1
 '@BASEBOARD_FAB2_LIB.BASEBOARD_FAB2(SCH_1):PAGE99_I106@MSTR_DISCRETE.RES(CHIPS)':
 'A': CDS_PINID='A';
NODE_NAME     C7U4 1
 '@BASEBOARD_FAB2_LIB.BASEBOARD_FAB2(SCH_1):PAGE233_I109@MSTR_DISCRETE.CAP(CHIPS)':
 'A': CDS_PINID='A';
NODE_NAME     C7U5 1
 '@BASEBOARD_FAB2_LIB.BASEBOARD_FAB2(SCH_1):PAGE233_I111@MSTR_DISCRETE.CAP(CHIPS)':
 'A': CDS_PINID='A';
NODE_NAME     C7T2 1
 '@BASEBOARD_FAB2_LIB.BASEBOARD_FAB2(SCH_1):PAGE233_I112@MSTR_DISCRETE.CAP(CHIPS)':
 'A': CDS_PINID='A';
NODE_NAME     C7T3 1
 '@BASEBOARD_FAB2_LIB.BASEBOARD_FAB2(SCH_1):PAGE233_I113@MSTR_DISCRETE.CAP(CHIPS)':
 'A': CDS_PINID='A';
NODE_NAME     C7U6 1
 '@BASEBOARD_FAB2_LIB.BASEBOARD_FAB2(SCH_1):PAGE233_I115@MSTR_DISCRETE.CAP(CHIPS)':
 'A': CDS_PINID='A';
NODE_NAME     C3F3 1
 '@BASEBOARD_FAB2_LIB.BASEBOARD_FAB2(SCH_1):PAGE233_I116@MSTR_DISCRETE.CAP(CHIPS)':
 'A': CDS_PINID='A';
NODE_NAME     C3F4 1
 '@BASEBOARD_FAB2_LIB.BASEBOARD_FAB2(SCH_1):PAGE233_I117@MSTR_DISCRETE.CAP(CHIPS)':
 'A': CDS_PINID='A';
NODE_NAME     C3G3 1
 '@BASEBOARD_FAB2_LIB.BASEBOARD_FAB2(SCH_1):PAGE233_I118@MSTR_DISCRETE.CAP(CHIPS)':
 'A': CDS_PINID='A';
NODE_NAME     C3G7 1
 '@BASEBOARD_FAB2_LIB.BASEBOARD_FAB2(SCH_1):PAGE233_I132@MSTR_DISCRETE.CAP(CHIPS)':
 'A': CDS_PINID='A';
NODE_NAME     C3G4 1
 '@BASEBOARD_FAB2_LIB.BASEBOARD_FAB2(SCH_1):PAGE233_I133@MSTR_DISCRETE.CAP(CHIPS)':
 'A': CDS_PINID='A';
NODE_NAME     C3G8 1
 '@BASEBOARD_FAB2_LIB.BASEBOARD_FAB2(SCH_1):PAGE233_I135@MSTR_DISCRETE.CAP(CHIPS)':
 'A': CDS_PINID='A';
NODE_NAME     C7U3 1
 '@BASEBOARD_FAB2_LIB.BASEBOARD_FAB2(SCH_1):PAGE233_I136@MSTR_DISCRETE.CAP(CHIPS)':
 'A': CDS_PINID='A';
NODE_NAME     R4G6 1
 '@BASEBOARD_FAB2_LIB.BASEBOARD_FAB2(SCH_1):PAGE233_I211@MSTR_DISCRETE.RES(CHIPS)':
 'A': CDS_PINID='A';
NODE_NAME     C4F7 1
 '@BASEBOARD_FAB2_LIB.BASEBOARD_FAB2(SCH_1):PAGE233_I217@MSTR_DISCRETE.CAPP(CHIPS)':
 'A': CDS_PINID='A';
NODE_NAME     C6U3 1
 '@BASEBOARD_FAB2_LIB.BASEBOARD_FAB2(SCH_1):PAGE233_I221@MSTR_DISCRETE.CAP(CHIPS)':
 'A': CDS_PINID='A';
NODE_NAME     C6U2 1
 '@BASEBOARD_FAB2_LIB.BASEBOARD_FAB2(SCH_1):PAGE233_I223@MSTR_DISCRETE.CAP(CHIPS)':
 'A': CDS_PINID='A';
NODE_NAME     C4F11 1
 '@BASEBOARD_FAB2_LIB.BASEBOARD_FAB2(SCH_1):PAGE233_I256@MSTR_DISCRETE.CAPP(CHIPS)':
 'A': CDS_PINID='A';
NODE_NAME     R4G8 1
 '@BASEBOARD_FAB2_LIB.BASEBOARD_FAB2(SCH_1):PAGE233_I271@MSTR_DISCRETE.RES(CHIPS)':
 'A': CDS_PINID='A';
NODE_NAME     L4G1 2
 '@BASEBOARD_FAB2_LIB.BASEBOARD_FAB2(SCH_1):PAGE233_I277@MSTR_DISCRETE.INDUCTOR(CHIPS)':
 'INB': CDS_PINID='INB';
NET_NAME
'PVPP_KLM'
 '@BASEBOARD_FAB2_LIB.BASEBOARD_FAB2(SCH_1):PVPP_KLM':
 C_SIGNAL='@baseboard_fab2_lib.baseboard_fab2(sch_1):pvpp_klm';
NODE_NAME     J1B1 284
 '@BASEBOARD_FAB2_LIB.BASEBOARD_FAB2(SCH_1):PAGE83_I111@MSTR_SCONN.SCONN288_H44441004(CHIPS)':
 'VDDSPD': CDS_PINID='VDDSPD';
NODE_NAME     J1B1 287
 '@BASEBOARD_FAB2_LIB.BASEBOARD_FAB2(SCH_1):PAGE83_I167@MSTR_SCONN.SCONN288_H44441004(CHIPS)':
 'VPP'<0>: CDS_PINID='VPP(0)';
NODE_NAME     J1B1 286
 '@BASEBOARD_FAB2_LIB.BASEBOARD_FAB2(SCH_1):PAGE83_I167@MSTR_SCONN.SCONN288_H44441004(CHIPS)':
 'VPP'<1>: CDS_PINID='VPP(1)';
NODE_NAME     J1B1 288
 '@BASEBOARD_FAB2_LIB.BASEBOARD_FAB2(SCH_1):PAGE83_I167@MSTR_SCONN.SCONN288_H44441004(CHIPS)':
 'VPP'<2>: CDS_PINID='VPP(2)';
NODE_NAME     J1B1 143
 '@BASEBOARD_FAB2_LIB.BASEBOARD_FAB2(SCH_1):PAGE83_I167@MSTR_SCONN.SCONN288_H44441004(CHIPS)':
 'VPP'<3>: CDS_PINID='VPP(3)';
NODE_NAME     J1B1 142
 '@BASEBOARD_FAB2_LIB.BASEBOARD_FAB2(SCH_1):PAGE83_I167@MSTR_SCONN.SCONN288_H44441004(CHIPS)':
 'VPP'<4>: CDS_PINID='VPP(4)';
NODE_NAME     J9M1 139
 '@BASEBOARD_FAB2_LIB.BASEBOARD_FAB2(SCH_1):PAGE84_I14@MSTR_SCONN.SCONN288_H44441003(CHIPS)':
 'SA'<0>: CDS_PINID='SA(0)';
NODE_NAME     J9M1 284
 '@BASEBOARD_FAB2_LIB.BASEBOARD_FAB2(SCH_1):PAGE84_I14@MSTR_SCONN.SCONN288_H44441003(CHIPS)':
 'VDDSPD': CDS_PINID='VDDSPD';
NODE_NAME     J9M1 287
 '@BASEBOARD_FAB2_LIB.BASEBOARD_FAB2(SCH_1):PAGE84_I57@MSTR_SCONN.SCONN288_H44441003(CHIPS)':
 'VPP'<0>: CDS_PINID='VPP(0)';
NODE_NAME     J9M1 286
 '@BASEBOARD_FAB2_LIB.BASEBOARD_FAB2(SCH_1):PAGE84_I57@MSTR_SCONN.SCONN288_H44441003(CHIPS)':
 'VPP'<1>: CDS_PINID='VPP(1)';
NODE_NAME     J9M1 288
 '@BASEBOARD_FAB2_LIB.BASEBOARD_FAB2(SCH_1):PAGE84_I57@MSTR_SCONN.SCONN288_H44441003(CHIPS)':
 'VPP'<2>: CDS_PINID='VPP(2)';
NODE_NAME     J9M1 143
 '@BASEBOARD_FAB2_LIB.BASEBOARD_FAB2(SCH_1):PAGE84_I57@MSTR_SCONN.SCONN288_H44441003(CHIPS)':
 'VPP'<3>: CDS_PINID='VPP(3)';
NODE_NAME     J9M1 142
 '@BASEBOARD_FAB2_LIB.BASEBOARD_FAB2(SCH_1):PAGE84_I57@MSTR_SCONN.SCONN288_H44441003(CHIPS)':
 'VPP'<4>: CDS_PINID='VPP(4)';
NODE_NAME     J1A2 140
 '@BASEBOARD_FAB2_LIB.BASEBOARD_FAB2(SCH_1):PAGE85_I111@MSTR_SCONN.SCONN288_H44441004(CHIPS)':
 'SA'<1>: CDS_PINID='SA(1)';
NODE_NAME     J1A2 284
 '@BASEBOARD_FAB2_LIB.BASEBOARD_FAB2(SCH_1):PAGE85_I111@MSTR_SCONN.SCONN288_H44441004(CHIPS)':
 'VDDSPD': CDS_PINID='VDDSPD';
NODE_NAME     J1A2 287
 '@BASEBOARD_FAB2_LIB.BASEBOARD_FAB2(SCH_1):PAGE85_I172@MSTR_SCONN.SCONN288_H44441004(CHIPS)':
 'VPP'<0>: CDS_PINID='VPP(0)';
NODE_NAME     J1A2 286
 '@BASEBOARD_FAB2_LIB.BASEBOARD_FAB2(SCH_1):PAGE85_I172@MSTR_SCONN.SCONN288_H44441004(CHIPS)':
 'VPP'<1>: CDS_PINID='VPP(1)';
NODE_NAME     J1A2 288
 '@BASEBOARD_FAB2_LIB.BASEBOARD_FAB2(SCH_1):PAGE85_I172@MSTR_SCONN.SCONN288_H44441004(CHIPS)':
 'VPP'<2>: CDS_PINID='VPP(2)';
NODE_NAME     J1A2 143
 '@BASEBOARD_FAB2_LIB.BASEBOARD_FAB2(SCH_1):PAGE85_I172@MSTR_SCONN.SCONN288_H44441004(CHIPS)':
 'VPP'<3>: CDS_PINID='VPP(3)';
NODE_NAME     J1A2 142
 '@BASEBOARD_FAB2_LIB.BASEBOARD_FAB2(SCH_1):PAGE85_I172@MSTR_SCONN.SCONN288_H44441004(CHIPS)':
 'VPP'<4>: CDS_PINID='VPP(4)';
NODE_NAME     J9L2 139
 '@BASEBOARD_FAB2_LIB.BASEBOARD_FAB2(SCH_1):PAGE86_I12@MSTR_SCONN.SCONN288_H44441003(CHIPS)':
 'SA'<0>: CDS_PINID='SA(0)';
NODE_NAME     J9L2 140
 '@BASEBOARD_FAB2_LIB.BASEBOARD_FAB2(SCH_1):PAGE86_I12@MSTR_SCONN.SCONN288_H44441003(CHIPS)':
 'SA'<1>: CDS_PINID='SA(1)';
NODE_NAME     J9L2 284
 '@BASEBOARD_FAB2_LIB.BASEBOARD_FAB2(SCH_1):PAGE86_I12@MSTR_SCONN.SCONN288_H44441003(CHIPS)':
 'VDDSPD': CDS_PINID='VDDSPD';
NODE_NAME     J9L2 287
 '@BASEBOARD_FAB2_LIB.BASEBOARD_FAB2(SCH_1):PAGE86_I55@MSTR_SCONN.SCONN288_H44441003(CHIPS)':
 'VPP'<0>: CDS_PINID='VPP(0)';
NODE_NAME     J9L2 286
 '@BASEBOARD_FAB2_LIB.BASEBOARD_FAB2(SCH_1):PAGE86_I55@MSTR_SCONN.SCONN288_H44441003(CHIPS)':
 'VPP'<1>: CDS_PINID='VPP(1)';
NODE_NAME     J9L2 288
 '@BASEBOARD_FAB2_LIB.BASEBOARD_FAB2(SCH_1):PAGE86_I55@MSTR_SCONN.SCONN288_H44441003(CHIPS)':
 'VPP'<2>: CDS_PINID='VPP(2)';
NODE_NAME     J9L2 143
 '@BASEBOARD_FAB2_LIB.BASEBOARD_FAB2(SCH_1):PAGE86_I55@MSTR_SCONN.SCONN288_H44441003(CHIPS)':
 'VPP'<3>: CDS_PINID='VPP(3)';
NODE_NAME     J9L2 142
 '@BASEBOARD_FAB2_LIB.BASEBOARD_FAB2(SCH_1):PAGE86_I55@MSTR_SCONN.SCONN288_H44441003(CHIPS)':
 'VPP'<4>: CDS_PINID='VPP(4)';
NODE_NAME     J1A1 287
 '@BASEBOARD_FAB2_LIB.BASEBOARD_FAB2(SCH_1):PAGE87_I169@MSTR_SCONN.SCONN288_H44441004(CHIPS)':
 'VPP'<0>: CDS_PINID='VPP(0)';
NODE_NAME     J1A1 286
 '@BASEBOARD_FAB2_LIB.BASEBOARD_FAB2(SCH_1):PAGE87_I169@MSTR_SCONN.SCONN288_H44441004(CHIPS)':
 'VPP'<1>: CDS_PINID='VPP(1)';
NODE_NAME     J1A1 288
 '@BASEBOARD_FAB2_LIB.BASEBOARD_FAB2(SCH_1):PAGE87_I169@MSTR_SCONN.SCONN288_H44441004(CHIPS)':
 'VPP'<2>: CDS_PINID='VPP(2)';
NODE_NAME     J1A1 143
 '@BASEBOARD_FAB2_LIB.BASEBOARD_FAB2(SCH_1):PAGE87_I169@MSTR_SCONN.SCONN288_H44441004(CHIPS)':
 'VPP'<3>: CDS_PINID='VPP(3)';
NODE_NAME     J1A1 142
 '@BASEBOARD_FAB2_LIB.BASEBOARD_FAB2(SCH_1):PAGE87_I169@MSTR_SCONN.SCONN288_H44441004(CHIPS)':
 'VPP'<4>: CDS_PINID='VPP(4)';
NODE_NAME     J1A1 238
 '@BASEBOARD_FAB2_LIB.BASEBOARD_FAB2(SCH_1):PAGE87_I186@MSTR_SCONN.SCONN288_H44441004(CHIPS)':
 'SA'<2>: CDS_PINID='SA(2)';
NODE_NAME     J1A1 284
 '@BASEBOARD_FAB2_LIB.BASEBOARD_FAB2(SCH_1):PAGE87_I186@MSTR_SCONN.SCONN288_H44441004(CHIPS)':
 'VDDSPD': CDS_PINID='VDDSPD';
NODE_NAME     J9L1 139
 '@BASEBOARD_FAB2_LIB.BASEBOARD_FAB2(SCH_1):PAGE88_I111@MSTR_SCONN.SCONN288_H44441003(CHIPS)':
 'SA'<0>: CDS_PINID='SA(0)';
NODE_NAME     J9L1 238
 '@BASEBOARD_FAB2_LIB.BASEBOARD_FAB2(SCH_1):PAGE88_I111@MSTR_SCONN.SCONN288_H44441003(CHIPS)':
 'SA'<2>: CDS_PINID='SA(2)';
NODE_NAME     J9L1 284
 '@BASEBOARD_FAB2_LIB.BASEBOARD_FAB2(SCH_1):PAGE88_I111@MSTR_SCONN.SCONN288_H44441003(CHIPS)':
 'VDDSPD': CDS_PINID='VDDSPD';
NODE_NAME     J9L1 287
 '@BASEBOARD_FAB2_LIB.BASEBOARD_FAB2(SCH_1):PAGE88_I168@MSTR_SCONN.SCONN288_H44441003(CHIPS)':
 'VPP'<0>: CDS_PINID='VPP(0)';
NODE_NAME     J9L1 286
 '@BASEBOARD_FAB2_LIB.BASEBOARD_FAB2(SCH_1):PAGE88_I168@MSTR_SCONN.SCONN288_H44441003(CHIPS)':
 'VPP'<1>: CDS_PINID='VPP(1)';
NODE_NAME     J9L1 288
 '@BASEBOARD_FAB2_LIB.BASEBOARD_FAB2(SCH_1):PAGE88_I168@MSTR_SCONN.SCONN288_H44441003(CHIPS)':
 'VPP'<2>: CDS_PINID='VPP(2)';
NODE_NAME     J9L1 143
 '@BASEBOARD_FAB2_LIB.BASEBOARD_FAB2(SCH_1):PAGE88_I168@MSTR_SCONN.SCONN288_H44441003(CHIPS)':
 'VPP'<3>: CDS_PINID='VPP(3)';
NODE_NAME     J9L1 142
 '@BASEBOARD_FAB2_LIB.BASEBOARD_FAB2(SCH_1):PAGE88_I168@MSTR_SCONN.SCONN288_H44441003(CHIPS)':
 'VPP'<4>: CDS_PINID='VPP(4)';
NODE_NAME     C3B5 1
 '@BASEBOARD_FAB2_LIB.BASEBOARD_FAB2(SCH_1):PAGE99_I53@DEV_DISCRETE.CAP_A(CHIPS)':
 'A': CDS_PINID='A';
NODE_NAME     U3B1 8
 '@BASEBOARD_FAB2_LIB.BASEBOARD_FAB2(SCH_1):PAGE99_I75@MSTR_DIGITAL.PCA9617(CHIPS)':
 'VCCB': CDS_PINID='VCCB';
NODE_NAME     R7M6 1
 '@BASEBOARD_FAB2_LIB.BASEBOARD_FAB2(SCH_1):PAGE99_I107@MSTR_DISCRETE.RES(CHIPS)':
 'A': CDS_PINID='A';
NODE_NAME     R7M1 1
 '@BASEBOARD_FAB2_LIB.BASEBOARD_FAB2(SCH_1):PAGE99_I109@MSTR_DISCRETE.RES(CHIPS)':
 'A': CDS_PINID='A';
NODE_NAME     R6M9 1
 '@BASEBOARD_FAB2_LIB.BASEBOARD_FAB2(SCH_1):PAGE192_I49@MSTR_DISCRETE.RES(CHIPS)':
 'A': CDS_PINID='A';
NODE_NAME     C3B2 1
 '@BASEBOARD_FAB2_LIB.BASEBOARD_FAB2(SCH_1):PAGE234_I84@MSTR_DISCRETE.CAP(CHIPS)':
 'A': CDS_PINID='A';
NODE_NAME     C3A8 1
 '@BASEBOARD_FAB2_LIB.BASEBOARD_FAB2(SCH_1):PAGE234_I86@MSTR_DISCRETE.CAP(CHIPS)':
 'A': CDS_PINID='A';
NODE_NAME     C7L3 1
 '@BASEBOARD_FAB2_LIB.BASEBOARD_FAB2(SCH_1):PAGE234_I87@MSTR_DISCRETE.CAP(CHIPS)':
 'A': CDS_PINID='A';
NODE_NAME     C7L2 1
 '@BASEBOARD_FAB2_LIB.BASEBOARD_FAB2(SCH_1):PAGE234_I88@MSTR_DISCRETE.CAP(CHIPS)':
 'A': CDS_PINID='A';
NODE_NAME     C7L7 1
 '@BASEBOARD_FAB2_LIB.BASEBOARD_FAB2(SCH_1):PAGE234_I89@MSTR_DISCRETE.CAP(CHIPS)':
 'A': CDS_PINID='A';
NODE_NAME     C7L6 1
 '@BASEBOARD_FAB2_LIB.BASEBOARD_FAB2(SCH_1):PAGE234_I90@MSTR_DISCRETE.CAP(CHIPS)':
 'A': CDS_PINID='A';
NODE_NAME     C7M4 1
 '@BASEBOARD_FAB2_LIB.BASEBOARD_FAB2(SCH_1):PAGE234_I91@MSTR_DISCRETE.CAP(CHIPS)':
 'A': CDS_PINID='A';
NODE_NAME     C7M3 1
 '@BASEBOARD_FAB2_LIB.BASEBOARD_FAB2(SCH_1):PAGE234_I92@MSTR_DISCRETE.CAP(CHIPS)':
 'A': CDS_PINID='A';
NODE_NAME     C3A4 1
 '@BASEBOARD_FAB2_LIB.BASEBOARD_FAB2(SCH_1):PAGE234_I93@MSTR_DISCRETE.CAP(CHIPS)':
 'A': CDS_PINID='A';
NODE_NAME     C3B1 1
 '@BASEBOARD_FAB2_LIB.BASEBOARD_FAB2(SCH_1):PAGE234_I94@MSTR_DISCRETE.CAP(CHIPS)':
 'A': CDS_PINID='A';
NODE_NAME     C3A7 1
 '@BASEBOARD_FAB2_LIB.BASEBOARD_FAB2(SCH_1):PAGE234_I95@MSTR_DISCRETE.CAP(CHIPS)':
 'A': CDS_PINID='A';
NODE_NAME     C3A3 1
 '@BASEBOARD_FAB2_LIB.BASEBOARD_FAB2(SCH_1):PAGE234_I97@MSTR_DISCRETE.CAP(CHIPS)':
 'A': CDS_PINID='A';
NODE_NAME     L4A1 2
 '@BASEBOARD_FAB2_LIB.BASEBOARD_FAB2(SCH_1):PAGE234_I164@MSTR_DISCRETE.INDUCTOR(CHIPS)':
 'INB': CDS_PINID='INB';
NODE_NAME     C3B3 1
 '@BASEBOARD_FAB2_LIB.BASEBOARD_FAB2(SCH_1):PAGE234_I167@MSTR_DISCRETE.CAPP(CHIPS)':
 'A': CDS_PINID='A';
NODE_NAME     C4B3 1
 '@BASEBOARD_FAB2_LIB.BASEBOARD_FAB2(SCH_1):PAGE234_I177@MSTR_DISCRETE.CAP(CHIPS)':
 'A': CDS_PINID='A';
NODE_NAME     C4B2 1
 '@BASEBOARD_FAB2_LIB.BASEBOARD_FAB2(SCH_1):PAGE234_I180@MSTR_DISCRETE.CAP(CHIPS)':
 'A': CDS_PINID='A';
NODE_NAME     R4B2 1
 '@BASEBOARD_FAB2_LIB.BASEBOARD_FAB2(SCH_1):PAGE234_I183@MSTR_DISCRETE.RES(CHIPS)':
 'A': CDS_PINID='A';
NODE_NAME     C6L8 1
 '@BASEBOARD_FAB2_LIB.BASEBOARD_FAB2(SCH_1):PAGE234_I210@MSTR_DISCRETE.CAPP(CHIPS)':
 'A': CDS_PINID='A';
NODE_NAME     R4B3 1
 '@BASEBOARD_FAB2_LIB.BASEBOARD_FAB2(SCH_1):PAGE234_I214@MSTR_DISCRETE.RES(CHIPS)':
 'A': CDS_PINID='A';
NET_NAME
'PVSA_CPU0'
 '@BASEBOARD_FAB2_LIB.BASEBOARD_FAB2(SCH_1):PVSA_CPU0':
 C_SIGNAL='@baseboard_fab2_lib.baseboard_fab2(sch_1):pvsa_cpu0';
NODE_NAME     U5D1 CJ66
 '@BASEBOARD_FAB2_LIB.BASEBOARD_FAB2(SCH_1):PAGE38_I34@CHPSET_LIB.SKX_EXT_B(CHIPS)':
 'VCCSA'<0>: CDS_PINID='VCCSA(0)';
NODE_NAME     U5D1 CJ64
 '@BASEBOARD_FAB2_LIB.BASEBOARD_FAB2(SCH_1):PAGE38_I34@CHPSET_LIB.SKX_EXT_B(CHIPS)':
 'VCCSA'<1>: CDS_PINID='VCCSA(1)';
NODE_NAME     U5D1 CH75
 '@BASEBOARD_FAB2_LIB.BASEBOARD_FAB2(SCH_1):PAGE38_I34@CHPSET_LIB.SKX_EXT_B(CHIPS)':
 'VCCSA'<2>: CDS_PINID='VCCSA(2)';
NODE_NAME     U5D1 CH65
 '@BASEBOARD_FAB2_LIB.BASEBOARD_FAB2(SCH_1):PAGE38_I34@CHPSET_LIB.SKX_EXT_B(CHIPS)':
 'VCCSA'<3>: CDS_PINID='VCCSA(3)';
NODE_NAME     U5D1 CG74
 '@BASEBOARD_FAB2_LIB.BASEBOARD_FAB2(SCH_1):PAGE38_I34@CHPSET_LIB.SKX_EXT_B(CHIPS)':
 'VCCSA'<4>: CDS_PINID='VCCSA(4)';
NODE_NAME     U5D1 CG66
 '@BASEBOARD_FAB2_LIB.BASEBOARD_FAB2(SCH_1):PAGE38_I34@CHPSET_LIB.SKX_EXT_B(CHIPS)':
 'VCCSA'<5>: CDS_PINID='VCCSA(5)';
NODE_NAME     U5D1 CG64
 '@BASEBOARD_FAB2_LIB.BASEBOARD_FAB2(SCH_1):PAGE38_I34@CHPSET_LIB.SKX_EXT_B(CHIPS)':
 'VCCSA'<6>: CDS_PINID='VCCSA(6)';
NODE_NAME     U5D1 CF75
 '@BASEBOARD_FAB2_LIB.BASEBOARD_FAB2(SCH_1):PAGE38_I34@CHPSET_LIB.SKX_EXT_B(CHIPS)':
 'VCCSA'<7>: CDS_PINID='VCCSA(7)';
NODE_NAME     U5D1 CF73
 '@BASEBOARD_FAB2_LIB.BASEBOARD_FAB2(SCH_1):PAGE38_I34@CHPSET_LIB.SKX_EXT_B(CHIPS)':
 'VCCSA'<8>: CDS_PINID='VCCSA(8)';
NODE_NAME     U5D1 CF67
 '@BASEBOARD_FAB2_LIB.BASEBOARD_FAB2(SCH_1):PAGE38_I34@CHPSET_LIB.SKX_EXT_B(CHIPS)':
 'VCCSA'<9>: CDS_PINID='VCCSA(9)';
NODE_NAME     U5D1 CF65
 '@BASEBOARD_FAB2_LIB.BASEBOARD_FAB2(SCH_1):PAGE38_I34@CHPSET_LIB.SKX_EXT_B(CHIPS)':
 'VCCSA'<10>: CDS_PINID='VCCSA(10)';
NODE_NAME     U5D1 CE74
 '@BASEBOARD_FAB2_LIB.BASEBOARD_FAB2(SCH_1):PAGE38_I34@CHPSET_LIB.SKX_EXT_B(CHIPS)':
 'VCCSA'<11>: CDS_PINID='VCCSA(11)';
NODE_NAME     U5D1 CE72
 '@BASEBOARD_FAB2_LIB.BASEBOARD_FAB2(SCH_1):PAGE38_I34@CHPSET_LIB.SKX_EXT_B(CHIPS)':
 'VCCSA'<12>: CDS_PINID='VCCSA(12)';
NODE_NAME     U5D1 CE68
 '@BASEBOARD_FAB2_LIB.BASEBOARD_FAB2(SCH_1):PAGE38_I34@CHPSET_LIB.SKX_EXT_B(CHIPS)':
 'VCCSA'<13>: CDS_PINID='VCCSA(13)';
NODE_NAME     U5D1 CE66
 '@BASEBOARD_FAB2_LIB.BASEBOARD_FAB2(SCH_1):PAGE38_I34@CHPSET_LIB.SKX_EXT_B(CHIPS)':
 'VCCSA'<14>: CDS_PINID='VCCSA(14)';
NODE_NAME     U5D1 CE64
 '@BASEBOARD_FAB2_LIB.BASEBOARD_FAB2(SCH_1):PAGE38_I34@CHPSET_LIB.SKX_EXT_B(CHIPS)':
 'VCCSA'<15>: CDS_PINID='VCCSA(15)';
NODE_NAME     U5D1 CD71
 '@BASEBOARD_FAB2_LIB.BASEBOARD_FAB2(SCH_1):PAGE38_I34@CHPSET_LIB.SKX_EXT_B(CHIPS)':
 'VCCSA'<16>: CDS_PINID='VCCSA(16)';
NODE_NAME     U5D1 CD69
 '@BASEBOARD_FAB2_LIB.BASEBOARD_FAB2(SCH_1):PAGE38_I34@CHPSET_LIB.SKX_EXT_B(CHIPS)':
 'VCCSA'<17>: CDS_PINID='VCCSA(17)';
NODE_NAME     U5D1 CD67
 '@BASEBOARD_FAB2_LIB.BASEBOARD_FAB2(SCH_1):PAGE38_I34@CHPSET_LIB.SKX_EXT_B(CHIPS)':
 'VCCSA'<18>: CDS_PINID='VCCSA(18)';
NODE_NAME     U5D1 CD65
 '@BASEBOARD_FAB2_LIB.BASEBOARD_FAB2(SCH_1):PAGE38_I34@CHPSET_LIB.SKX_EXT_B(CHIPS)':
 'VCCSA'<19>: CDS_PINID='VCCSA(19)';
NODE_NAME     U5D1 CC70
 '@BASEBOARD_FAB2_LIB.BASEBOARD_FAB2(SCH_1):PAGE38_I34@CHPSET_LIB.SKX_EXT_B(CHIPS)':
 'VCCSA'<20>: CDS_PINID='VCCSA(20)';
NODE_NAME     U5D1 CC68
 '@BASEBOARD_FAB2_LIB.BASEBOARD_FAB2(SCH_1):PAGE38_I34@CHPSET_LIB.SKX_EXT_B(CHIPS)':
 'VCCSA'<21>: CDS_PINID='VCCSA(21)';
NODE_NAME     U5D1 CC66
 '@BASEBOARD_FAB2_LIB.BASEBOARD_FAB2(SCH_1):PAGE38_I34@CHPSET_LIB.SKX_EXT_B(CHIPS)':
 'VCCSA'<22>: CDS_PINID='VCCSA(22)';
NODE_NAME     U5D1 CB69
 '@BASEBOARD_FAB2_LIB.BASEBOARD_FAB2(SCH_1):PAGE38_I34@CHPSET_LIB.SKX_EXT_B(CHIPS)':
 'VCCSA'<23>: CDS_PINID='VCCSA(23)';
NODE_NAME     U5D1 CB67
 '@BASEBOARD_FAB2_LIB.BASEBOARD_FAB2(SCH_1):PAGE38_I34@CHPSET_LIB.SKX_EXT_B(CHIPS)':
 'VCCSA'<24>: CDS_PINID='VCCSA(24)';
NODE_NAME     U5D1 CB65
 '@BASEBOARD_FAB2_LIB.BASEBOARD_FAB2(SCH_1):PAGE38_I34@CHPSET_LIB.SKX_EXT_B(CHIPS)':
 'VCCSA'<25>: CDS_PINID='VCCSA(25)';
NODE_NAME     C5P7 1
 '@BASEBOARD_FAB2_LIB.BASEBOARD_FAB2(SCH_1):PAGE42_I25@MSTR_DISCRETE.CAP(CHIPS)':
 'A': CDS_PINID='A';
NODE_NAME     C5D13 1
 '@BASEBOARD_FAB2_LIB.BASEBOARD_FAB2(SCH_1):PAGE42_I91@MSTR_DISCRETE.CAP(CHIPS)':
 'A': CDS_PINID='A';
NODE_NAME     C5D11 1
 '@BASEBOARD_FAB2_LIB.BASEBOARD_FAB2(SCH_1):PAGE42_I93@MSTR_DISCRETE.CAP(CHIPS)':
 'A': CDS_PINID='A';
NODE_NAME     C5D12 1
 '@BASEBOARD_FAB2_LIB.BASEBOARD_FAB2(SCH_1):PAGE42_I94@MSTR_DISCRETE.CAP(CHIPS)':
 'A': CDS_PINID='A';
NODE_NAME     C5D10 1
 '@BASEBOARD_FAB2_LIB.BASEBOARD_FAB2(SCH_1):PAGE42_I108@MSTR_DISCRETE.CAP(CHIPS)':
 'A': CDS_PINID='A';
NODE_NAME     C6N7 1
 '@BASEBOARD_FAB2_LIB.BASEBOARD_FAB2(SCH_1):PAGE205_I5@DEV_DISCRETE.CAP_A(CHIPS)':
 'A': CDS_PINID='A';
NODE_NAME     C6N1 1
 '@BASEBOARD_FAB2_LIB.BASEBOARD_FAB2(SCH_1):PAGE205_I12@MSTR_DISCRETE.CAPP(CHIPS)':
 'A': CDS_PINID='A';
NODE_NAME     C6N4 1
 '@BASEBOARD_FAB2_LIB.BASEBOARD_FAB2(SCH_1):PAGE205_I14@MSTR_DISCRETE.CAPP(CHIPS)':
 'A': CDS_PINID='A';
NODE_NAME     R4C5 2
 '@BASEBOARD_FAB2_LIB.BASEBOARD_FAB2(SCH_1):PAGE205_I24@MSTR_DISCRETE.RES(CHIPS)':
 'B': CDS_PINID='B';
NODE_NAME     C4C11 1
 '@BASEBOARD_FAB2_LIB.BASEBOARD_FAB2(SCH_1):PAGE205_I43@DEV_DISCRETE.CAP_A(CHIPS)':
 'A': CDS_PINID='A';
NODE_NAME     R6N4 1
 '@BASEBOARD_FAB2_LIB.BASEBOARD_FAB2(SCH_1):PAGE205_I45@MSTR_DISCRETE.RES(CHIPS)':
 'A': CDS_PINID='A';
NODE_NAME     EU4C1 1
 '@BASEBOARD_FAB2_LIB.BASEBOARD_FAB2(SCH_1):PAGE205_I46@MSTR_DISCRETE.IR354XX(CHIPS)':
 'VOS': CDS_PINID='VOS';
NODE_NAME     L4C2 2
 '@BASEBOARD_FAB2_LIB.BASEBOARD_FAB2(SCH_1):PAGE205_I82@W_HDL.IND-300NH-20-GP(CHIPS)':
 'F': CDS_PINID='F';
NODE_NAME     C5P8 1
 '@BASEBOARD_FAB2_LIB.BASEBOARD_FAB2(SCH_1):PAGE42_I214@MSTR_DISCRETE.CAP(CHIPS)':
 'A': CDS_PINID='A';
NODE_NAME     C5P9 1
 '@BASEBOARD_FAB2_LIB.BASEBOARD_FAB2(SCH_1):PAGE42_I215@MSTR_DISCRETE.CAP(CHIPS)':
 'A': CDS_PINID='A';
NET_NAME
'PVSA_CPU1'
 '@BASEBOARD_FAB2_LIB.BASEBOARD_FAB2(SCH_1):PVSA_CPU1':
 C_SIGNAL='@baseboard_fab2_lib.baseboard_fab2(sch_1):pvsa_cpu1';
NODE_NAME     U2D1 CJ66
 '@BASEBOARD_FAB2_LIB.BASEBOARD_FAB2(SCH_1):PAGE72_I33@CHPSET_LIB.SKX_EXT_B(CHIPS)':
 'VCCSA'<0>: CDS_PINID='VCCSA(0)';
NODE_NAME     U2D1 CJ64
 '@BASEBOARD_FAB2_LIB.BASEBOARD_FAB2(SCH_1):PAGE72_I33@CHPSET_LIB.SKX_EXT_B(CHIPS)':
 'VCCSA'<1>: CDS_PINID='VCCSA(1)';
NODE_NAME     U2D1 CH75
 '@BASEBOARD_FAB2_LIB.BASEBOARD_FAB2(SCH_1):PAGE72_I33@CHPSET_LIB.SKX_EXT_B(CHIPS)':
 'VCCSA'<2>: CDS_PINID='VCCSA(2)';
NODE_NAME     U2D1 CH65
 '@BASEBOARD_FAB2_LIB.BASEBOARD_FAB2(SCH_1):PAGE72_I33@CHPSET_LIB.SKX_EXT_B(CHIPS)':
 'VCCSA'<3>: CDS_PINID='VCCSA(3)';
NODE_NAME     U2D1 CG74
 '@BASEBOARD_FAB2_LIB.BASEBOARD_FAB2(SCH_1):PAGE72_I33@CHPSET_LIB.SKX_EXT_B(CHIPS)':
 'VCCSA'<4>: CDS_PINID='VCCSA(4)';
NODE_NAME     U2D1 CG66
 '@BASEBOARD_FAB2_LIB.BASEBOARD_FAB2(SCH_1):PAGE72_I33@CHPSET_LIB.SKX_EXT_B(CHIPS)':
 'VCCSA'<5>: CDS_PINID='VCCSA(5)';
NODE_NAME     U2D1 CG64
 '@BASEBOARD_FAB2_LIB.BASEBOARD_FAB2(SCH_1):PAGE72_I33@CHPSET_LIB.SKX_EXT_B(CHIPS)':
 'VCCSA'<6>: CDS_PINID='VCCSA(6)';
NODE_NAME     U2D1 CF75
 '@BASEBOARD_FAB2_LIB.BASEBOARD_FAB2(SCH_1):PAGE72_I33@CHPSET_LIB.SKX_EXT_B(CHIPS)':
 'VCCSA'<7>: CDS_PINID='VCCSA(7)';
NODE_NAME     U2D1 CF73
 '@BASEBOARD_FAB2_LIB.BASEBOARD_FAB2(SCH_1):PAGE72_I33@CHPSET_LIB.SKX_EXT_B(CHIPS)':
 'VCCSA'<8>: CDS_PINID='VCCSA(8)';
NODE_NAME     U2D1 CF67
 '@BASEBOARD_FAB2_LIB.BASEBOARD_FAB2(SCH_1):PAGE72_I33@CHPSET_LIB.SKX_EXT_B(CHIPS)':
 'VCCSA'<9>: CDS_PINID='VCCSA(9)';
NODE_NAME     U2D1 CF65
 '@BASEBOARD_FAB2_LIB.BASEBOARD_FAB2(SCH_1):PAGE72_I33@CHPSET_LIB.SKX_EXT_B(CHIPS)':
 'VCCSA'<10>: CDS_PINID='VCCSA(10)';
NODE_NAME     U2D1 CE74
 '@BASEBOARD_FAB2_LIB.BASEBOARD_FAB2(SCH_1):PAGE72_I33@CHPSET_LIB.SKX_EXT_B(CHIPS)':
 'VCCSA'<11>: CDS_PINID='VCCSA(11)';
NODE_NAME     U2D1 CE72
 '@BASEBOARD_FAB2_LIB.BASEBOARD_FAB2(SCH_1):PAGE72_I33@CHPSET_LIB.SKX_EXT_B(CHIPS)':
 'VCCSA'<12>: CDS_PINID='VCCSA(12)';
NODE_NAME     U2D1 CE68
 '@BASEBOARD_FAB2_LIB.BASEBOARD_FAB2(SCH_1):PAGE72_I33@CHPSET_LIB.SKX_EXT_B(CHIPS)':
 'VCCSA'<13>: CDS_PINID='VCCSA(13)';
NODE_NAME     U2D1 CE66
 '@BASEBOARD_FAB2_LIB.BASEBOARD_FAB2(SCH_1):PAGE72_I33@CHPSET_LIB.SKX_EXT_B(CHIPS)':
 'VCCSA'<14>: CDS_PINID='VCCSA(14)';
NODE_NAME     U2D1 CE64
 '@BASEBOARD_FAB2_LIB.BASEBOARD_FAB2(SCH_1):PAGE72_I33@CHPSET_LIB.SKX_EXT_B(CHIPS)':
 'VCCSA'<15>: CDS_PINID='VCCSA(15)';
NODE_NAME     U2D1 CD71
 '@BASEBOARD_FAB2_LIB.BASEBOARD_FAB2(SCH_1):PAGE72_I33@CHPSET_LIB.SKX_EXT_B(CHIPS)':
 'VCCSA'<16>: CDS_PINID='VCCSA(16)';
NODE_NAME     U2D1 CD69
 '@BASEBOARD_FAB2_LIB.BASEBOARD_FAB2(SCH_1):PAGE72_I33@CHPSET_LIB.SKX_EXT_B(CHIPS)':
 'VCCSA'<17>: CDS_PINID='VCCSA(17)';
NODE_NAME     U2D1 CD67
 '@BASEBOARD_FAB2_LIB.BASEBOARD_FAB2(SCH_1):PAGE72_I33@CHPSET_LIB.SKX_EXT_B(CHIPS)':
 'VCCSA'<18>: CDS_PINID='VCCSA(18)';
NODE_NAME     U2D1 CD65
 '@BASEBOARD_FAB2_LIB.BASEBOARD_FAB2(SCH_1):PAGE72_I33@CHPSET_LIB.SKX_EXT_B(CHIPS)':
 'VCCSA'<19>: CDS_PINID='VCCSA(19)';
NODE_NAME     U2D1 CC70
 '@BASEBOARD_FAB2_LIB.BASEBOARD_FAB2(SCH_1):PAGE72_I33@CHPSET_LIB.SKX_EXT_B(CHIPS)':
 'VCCSA'<20>: CDS_PINID='VCCSA(20)';
NODE_NAME     U2D1 CC68
 '@BASEBOARD_FAB2_LIB.BASEBOARD_FAB2(SCH_1):PAGE72_I33@CHPSET_LIB.SKX_EXT_B(CHIPS)':
 'VCCSA'<21>: CDS_PINID='VCCSA(21)';
NODE_NAME     U2D1 CC66
 '@BASEBOARD_FAB2_LIB.BASEBOARD_FAB2(SCH_1):PAGE72_I33@CHPSET_LIB.SKX_EXT_B(CHIPS)':
 'VCCSA'<22>: CDS_PINID='VCCSA(22)';
NODE_NAME     U2D1 CB69
 '@BASEBOARD_FAB2_LIB.BASEBOARD_FAB2(SCH_1):PAGE72_I33@CHPSET_LIB.SKX_EXT_B(CHIPS)':
 'VCCSA'<23>: CDS_PINID='VCCSA(23)';
NODE_NAME     U2D1 CB67
 '@BASEBOARD_FAB2_LIB.BASEBOARD_FAB2(SCH_1):PAGE72_I33@CHPSET_LIB.SKX_EXT_B(CHIPS)':
 'VCCSA'<24>: CDS_PINID='VCCSA(24)';
NODE_NAME     U2D1 CB65
 '@BASEBOARD_FAB2_LIB.BASEBOARD_FAB2(SCH_1):PAGE72_I33@CHPSET_LIB.SKX_EXT_B(CHIPS)':
 'VCCSA'<25>: CDS_PINID='VCCSA(25)';
NODE_NAME     C2D8 1
 '@BASEBOARD_FAB2_LIB.BASEBOARD_FAB2(SCH_1):PAGE76_I33@MSTR_DISCRETE.CAP(CHIPS)':
 'A': CDS_PINID='A';
NODE_NAME     C2D10 1
 '@BASEBOARD_FAB2_LIB.BASEBOARD_FAB2(SCH_1):PAGE76_I37@MSTR_DISCRETE.CAP(CHIPS)':
 'A': CDS_PINID='A';
NODE_NAME     C2D11 1
 '@BASEBOARD_FAB2_LIB.BASEBOARD_FAB2(SCH_1):PAGE76_I42@MSTR_DISCRETE.CAP(CHIPS)':
 'A': CDS_PINID='A';
NODE_NAME     C2D9 1
 '@BASEBOARD_FAB2_LIB.BASEBOARD_FAB2(SCH_1):PAGE76_I43@MSTR_DISCRETE.CAP(CHIPS)':
 'A': CDS_PINID='A';
NODE_NAME     C1C19 1
 '@BASEBOARD_FAB2_LIB.BASEBOARD_FAB2(SCH_1):PAGE210_I8@DEV_DISCRETE.CAP_A(CHIPS)':
 'A': CDS_PINID='A';
NODE_NAME     C9N11 1
 '@BASEBOARD_FAB2_LIB.BASEBOARD_FAB2(SCH_1):PAGE210_I12@MSTR_DISCRETE.CAPP(CHIPS)':
 'A': CDS_PINID='A';
NODE_NAME     C9N20 1
 '@BASEBOARD_FAB2_LIB.BASEBOARD_FAB2(SCH_1):PAGE210_I14@MSTR_DISCRETE.CAPP(CHIPS)':
 'A': CDS_PINID='A';
NODE_NAME     R1C12 2
 '@BASEBOARD_FAB2_LIB.BASEBOARD_FAB2(SCH_1):PAGE210_I29@MSTR_DISCRETE.RES(CHIPS)':
 'B': CDS_PINID='B';
NODE_NAME     C9N22 1
 '@BASEBOARD_FAB2_LIB.BASEBOARD_FAB2(SCH_1):PAGE210_I44@DEV_DISCRETE.CAP_A(CHIPS)':
 'A': CDS_PINID='A';
NODE_NAME     R9N4 1
 '@BASEBOARD_FAB2_LIB.BASEBOARD_FAB2(SCH_1):PAGE210_I45@MSTR_DISCRETE.RES(CHIPS)':
 'A': CDS_PINID='A';
NODE_NAME     EU1C1 1
 '@BASEBOARD_FAB2_LIB.BASEBOARD_FAB2(SCH_1):PAGE210_I51@MSTR_DISCRETE.IR354XX(CHIPS)':
 'VOS': CDS_PINID='VOS';
NODE_NAME     L1C1 2
 '@BASEBOARD_FAB2_LIB.BASEBOARD_FAB2(SCH_1):PAGE210_I72@W_HDL.IND-300NH-20-GP(CHIPS)':
 'F': CDS_PINID='F';
NODE_NAME     C8P5 1
 '@BASEBOARD_FAB2_LIB.BASEBOARD_FAB2(SCH_1):PAGE76_I246@MSTR_DISCRETE.CAP(CHIPS)':
 'A': CDS_PINID='A';
NODE_NAME     C8P6 1
 '@BASEBOARD_FAB2_LIB.BASEBOARD_FAB2(SCH_1):PAGE76_I247@MSTR_DISCRETE.CAP(CHIPS)':
 'A': CDS_PINID='A';
NODE_NAME     C8P7 1
 '@BASEBOARD_FAB2_LIB.BASEBOARD_FAB2(SCH_1):PAGE76_I248@MSTR_DISCRETE.CAP(CHIPS)':
 'A': CDS_PINID='A';
NET_NAME
'PVTT_ABC'
 '@BASEBOARD_FAB2_LIB.BASEBOARD_FAB2(SCH_1):PVTT_ABC':
 C_SIGNAL='@baseboard_fab2_lib.baseboard_fab2(sch_1):pvtt_abc';
NODE_NAME     J4G1 221
 '@BASEBOARD_FAB2_LIB.BASEBOARD_FAB2(SCH_1):PAGE43_I260@MSTR_SCONN.SCONN288_H44441004(CHIPS)':
 'VTT'<0>: CDS_PINID='VTT(0)';
NODE_NAME     J4G1 77
 '@BASEBOARD_FAB2_LIB.BASEBOARD_FAB2(SCH_1):PAGE43_I260@MSTR_SCONN.SCONN288_H44441004(CHIPS)':
 'VTT'<1>: CDS_PINID='VTT(1)';
NODE_NAME     J6T1 221
 '@BASEBOARD_FAB2_LIB.BASEBOARD_FAB2(SCH_1):PAGE44_I75@MSTR_SCONN.SCONN288_H44441003(CHIPS)':
 'VTT'<0>: CDS_PINID='VTT(0)';
NODE_NAME     J6T1 77
 '@BASEBOARD_FAB2_LIB.BASEBOARD_FAB2(SCH_1):PAGE44_I75@MSTR_SCONN.SCONN288_H44441003(CHIPS)':
 'VTT'<1>: CDS_PINID='VTT(1)';
NODE_NAME     J4G2 221
 '@BASEBOARD_FAB2_LIB.BASEBOARD_FAB2(SCH_1):PAGE45_I169@MSTR_SCONN.SCONN288_H44441004(CHIPS)':
 'VTT'<0>: CDS_PINID='VTT(0)';
NODE_NAME     J4G2 77
 '@BASEBOARD_FAB2_LIB.BASEBOARD_FAB2(SCH_1):PAGE45_I169@MSTR_SCONN.SCONN288_H44441004(CHIPS)':
 'VTT'<1>: CDS_PINID='VTT(1)';
NODE_NAME     J6U1 221
 '@BASEBOARD_FAB2_LIB.BASEBOARD_FAB2(SCH_1):PAGE46_I67@MSTR_SCONN.SCONN288_H44441003(CHIPS)':
 'VTT'<0>: CDS_PINID='VTT(0)';
NODE_NAME     J6U1 77
 '@BASEBOARD_FAB2_LIB.BASEBOARD_FAB2(SCH_1):PAGE46_I67@MSTR_SCONN.SCONN288_H44441003(CHIPS)':
 'VTT'<1>: CDS_PINID='VTT(1)';
NODE_NAME     J4G3 221
 '@BASEBOARD_FAB2_LIB.BASEBOARD_FAB2(SCH_1):PAGE47_I179@MSTR_SCONN.SCONN288_H44441004(CHIPS)':
 'VTT'<0>: CDS_PINID='VTT(0)';
NODE_NAME     J4G3 77
 '@BASEBOARD_FAB2_LIB.BASEBOARD_FAB2(SCH_1):PAGE47_I179@MSTR_SCONN.SCONN288_H44441004(CHIPS)':
 'VTT'<1>: CDS_PINID='VTT(1)';
NODE_NAME     J6U2 221
 '@BASEBOARD_FAB2_LIB.BASEBOARD_FAB2(SCH_1):PAGE48_I171@MSTR_SCONN.SCONN288_H44441003(CHIPS)':
 'VTT'<0>: CDS_PINID='VTT(0)';
NODE_NAME     J6U2 77
 '@BASEBOARD_FAB2_LIB.BASEBOARD_FAB2(SCH_1):PAGE48_I171@MSTR_SCONN.SCONN288_H44441003(CHIPS)':
 'VTT'<1>: CDS_PINID='VTT(1)';
NODE_NAME     C4G24 1
 '@BASEBOARD_FAB2_LIB.BASEBOARD_FAB2(SCH_1):PAGE221_I24@MSTR_DISCRETE.CAP(CHIPS)':
 'A': CDS_PINID='A';
NODE_NAME     SH5U1 2
 '@BASEBOARD_FAB2_LIB.BASEBOARD_FAB2(SCH_1):PAGE221_I9@MSTR_MISC.SHUNT(CHIPS)':
 'B':NET_SHORT='VR_PVTT_ABC_SNS:PVTT_ABC',
 CDS_PINID='B';
NODE_NAME     EU4G3 9
 '@BASEBOARD_FAB2_LIB.BASEBOARD_FAB2(SCH_1):PAGE221_I15@MSTR_VREG.MIC5166(CHIPS)':
 'VTT': CDS_PINID='VTT';
NODE_NAME     C5T3 1
 '@BASEBOARD_FAB2_LIB.BASEBOARD_FAB2(SCH_1):PAGE221_I40@DEV_DISCRETE.CAP_A(CHIPS)':
 'A': CDS_PINID='A';
NODE_NAME     C6W11 1
 '@BASEBOARD_FAB2_LIB.BASEBOARD_FAB2(SCH_1):PAGE221_I44@MSTR_DISCRETE.CAP(CHIPS)':
 'A': CDS_PINID='A';
NODE_NAME     C5U12 1
 '@BASEBOARD_FAB2_LIB.BASEBOARD_FAB2(SCH_1):PAGE221_I45@MSTR_DISCRETE.CAP(CHIPS)':
 'A': CDS_PINID='A';
NODE_NAME     C5U16 1
 '@BASEBOARD_FAB2_LIB.BASEBOARD_FAB2(SCH_1):PAGE221_I46@MSTR_DISCRETE.CAP(CHIPS)':
 'A': CDS_PINID='A';
NET_NAME
'PVTT_DEF'
 '@BASEBOARD_FAB2_LIB.BASEBOARD_FAB2(SCH_1):PVTT_DEF':
 C_SIGNAL='@baseboard_fab2_lib.baseboard_fab2(sch_1):pvtt_def';
NODE_NAME     J4B1 221
 '@BASEBOARD_FAB2_LIB.BASEBOARD_FAB2(SCH_1):PAGE49_I169@MSTR_SCONN.SCONN288_H44441004(CHIPS)':
 'VTT'<0>: CDS_PINID='VTT(0)';
NODE_NAME     J4B1 77
 '@BASEBOARD_FAB2_LIB.BASEBOARD_FAB2(SCH_1):PAGE49_I169@MSTR_SCONN.SCONN288_H44441004(CHIPS)':
 'VTT'<1>: CDS_PINID='VTT(1)';
NODE_NAME     J6M1 221
 '@BASEBOARD_FAB2_LIB.BASEBOARD_FAB2(SCH_1):PAGE50_I50@MSTR_SCONN.SCONN288_H44441003(CHIPS)':
 'VTT'<0>: CDS_PINID='VTT(0)';
NODE_NAME     J6M1 77
 '@BASEBOARD_FAB2_LIB.BASEBOARD_FAB2(SCH_1):PAGE50_I50@MSTR_SCONN.SCONN288_H44441003(CHIPS)':
 'VTT'<1>: CDS_PINID='VTT(1)';
NODE_NAME     J4A2 221
 '@BASEBOARD_FAB2_LIB.BASEBOARD_FAB2(SCH_1):PAGE51_I167@MSTR_SCONN.SCONN288_H44441004(CHIPS)':
 'VTT'<0>: CDS_PINID='VTT(0)';
NODE_NAME     J4A2 77
 '@BASEBOARD_FAB2_LIB.BASEBOARD_FAB2(SCH_1):PAGE51_I167@MSTR_SCONN.SCONN288_H44441004(CHIPS)':
 'VTT'<1>: CDS_PINID='VTT(1)';
NODE_NAME     J6L2 221
 '@BASEBOARD_FAB2_LIB.BASEBOARD_FAB2(SCH_1):PAGE52_I55@MSTR_SCONN.SCONN288_H44441003(CHIPS)':
 'VTT'<0>: CDS_PINID='VTT(0)';
NODE_NAME     J6L2 77
 '@BASEBOARD_FAB2_LIB.BASEBOARD_FAB2(SCH_1):PAGE52_I55@MSTR_SCONN.SCONN288_H44441003(CHIPS)':
 'VTT'<1>: CDS_PINID='VTT(1)';
NODE_NAME     J4A1 221
 '@BASEBOARD_FAB2_LIB.BASEBOARD_FAB2(SCH_1):PAGE53_I171@MSTR_SCONN.SCONN288_H44441004(CHIPS)':
 'VTT'<0>: CDS_PINID='VTT(0)';
NODE_NAME     J4A1 77
 '@BASEBOARD_FAB2_LIB.BASEBOARD_FAB2(SCH_1):PAGE53_I171@MSTR_SCONN.SCONN288_H44441004(CHIPS)':
 'VTT'<1>: CDS_PINID='VTT(1)';
NODE_NAME     J6L1 221
 '@BASEBOARD_FAB2_LIB.BASEBOARD_FAB2(SCH_1):PAGE54_I170@MSTR_SCONN.SCONN288_H44441003(CHIPS)':
 'VTT'<0>: CDS_PINID='VTT(0)';
NODE_NAME     J6L1 77
 '@BASEBOARD_FAB2_LIB.BASEBOARD_FAB2(SCH_1):PAGE54_I170@MSTR_SCONN.SCONN288_H44441003(CHIPS)':
 'VTT'<1>: CDS_PINID='VTT(1)';
NODE_NAME     C4A1 1
 '@BASEBOARD_FAB2_LIB.BASEBOARD_FAB2(SCH_1):PAGE222_I28@MSTR_DISCRETE.CAP(CHIPS)':
 'A': CDS_PINID='A';
NODE_NAME     EU4A1 9
 '@BASEBOARD_FAB2_LIB.BASEBOARD_FAB2(SCH_1):PAGE222_I13@MSTR_VREG.MIC5166(CHIPS)':
 'VTT': CDS_PINID='VTT';
NODE_NAME     SH5L1 2
 '@BASEBOARD_FAB2_LIB.BASEBOARD_FAB2(SCH_1):PAGE222_I30@MSTR_MISC.SHUNT(CHIPS)':
 'B':NET_SHORT='VR_PVTT_DEF_SNS:PVTT_DEF',
 CDS_PINID='B';
NODE_NAME     C5M13 1
 '@BASEBOARD_FAB2_LIB.BASEBOARD_FAB2(SCH_1):PAGE222_I41@DEV_DISCRETE.CAP_A(CHIPS)':
 'A': CDS_PINID='A';
NODE_NAME     C5L5 1
 '@BASEBOARD_FAB2_LIB.BASEBOARD_FAB2(SCH_1):PAGE222_I44@MSTR_DISCRETE.CAP(CHIPS)':
 'A': CDS_PINID='A';
NODE_NAME     C5L4 1
 '@BASEBOARD_FAB2_LIB.BASEBOARD_FAB2(SCH_1):PAGE222_I45@MSTR_DISCRETE.CAP(CHIPS)':
 'A': CDS_PINID='A';
NODE_NAME     C4W5 1
 '@BASEBOARD_FAB2_LIB.BASEBOARD_FAB2(SCH_1):PAGE222_I46@MSTR_DISCRETE.CAP(CHIPS)':
 'A': CDS_PINID='A';
NET_NAME
'PVTT_GHJ'
 '@BASEBOARD_FAB2_LIB.BASEBOARD_FAB2(SCH_1):PVTT_GHJ':
 C_SIGNAL='@baseboard_fab2_lib.baseboard_fab2(sch_1):pvtt_ghj';
NODE_NAME     J1G1 221
 '@BASEBOARD_FAB2_LIB.BASEBOARD_FAB2(SCH_1):PAGE77_I171@MSTR_SCONN.SCONN288_H44441004(CHIPS)':
 'VTT'<0>: CDS_PINID='VTT(0)';
NODE_NAME     J1G1 77
 '@BASEBOARD_FAB2_LIB.BASEBOARD_FAB2(SCH_1):PAGE77_I171@MSTR_SCONN.SCONN288_H44441004(CHIPS)':
 'VTT'<1>: CDS_PINID='VTT(1)';
NODE_NAME     J9T1 221
 '@BASEBOARD_FAB2_LIB.BASEBOARD_FAB2(SCH_1):PAGE78_I75@MSTR_SCONN.SCONN288_H44441003(CHIPS)':
 'VTT'<0>: CDS_PINID='VTT(0)';
NODE_NAME     J9T1 77
 '@BASEBOARD_FAB2_LIB.BASEBOARD_FAB2(SCH_1):PAGE78_I75@MSTR_SCONN.SCONN288_H44441003(CHIPS)':
 'VTT'<1>: CDS_PINID='VTT(1)';
NODE_NAME     J1G2 221
 '@BASEBOARD_FAB2_LIB.BASEBOARD_FAB2(SCH_1):PAGE79_I169@MSTR_SCONN.SCONN288_H44441004(CHIPS)':
 'VTT'<0>: CDS_PINID='VTT(0)';
NODE_NAME     J1G2 77
 '@BASEBOARD_FAB2_LIB.BASEBOARD_FAB2(SCH_1):PAGE79_I169@MSTR_SCONN.SCONN288_H44441004(CHIPS)':
 'VTT'<1>: CDS_PINID='VTT(1)';
NODE_NAME     J9U1 221
 '@BASEBOARD_FAB2_LIB.BASEBOARD_FAB2(SCH_1):PAGE80_I56@MSTR_SCONN.SCONN288_H44441003(CHIPS)':
 'VTT'<0>: CDS_PINID='VTT(0)';
NODE_NAME     J9U1 77
 '@BASEBOARD_FAB2_LIB.BASEBOARD_FAB2(SCH_1):PAGE80_I56@MSTR_SCONN.SCONN288_H44441003(CHIPS)':
 'VTT'<1>: CDS_PINID='VTT(1)';
NODE_NAME     J1G3 221
 '@BASEBOARD_FAB2_LIB.BASEBOARD_FAB2(SCH_1):PAGE81_I169@MSTR_SCONN.SCONN288_H44441004(CHIPS)':
 'VTT'<0>: CDS_PINID='VTT(0)';
NODE_NAME     J1G3 77
 '@BASEBOARD_FAB2_LIB.BASEBOARD_FAB2(SCH_1):PAGE81_I169@MSTR_SCONN.SCONN288_H44441004(CHIPS)':
 'VTT'<1>: CDS_PINID='VTT(1)';
NODE_NAME     J9U2 221
 '@BASEBOARD_FAB2_LIB.BASEBOARD_FAB2(SCH_1):PAGE82_I171@MSTR_SCONN.SCONN288_H44441003(CHIPS)':
 'VTT'<0>: CDS_PINID='VTT(0)';
NODE_NAME     J9U2 77
 '@BASEBOARD_FAB2_LIB.BASEBOARD_FAB2(SCH_1):PAGE82_I171@MSTR_SCONN.SCONN288_H44441003(CHIPS)':
 'VTT'<1>: CDS_PINID='VTT(1)';
NODE_NAME     SH8U1 2
 '@BASEBOARD_FAB2_LIB.BASEBOARD_FAB2(SCH_1):PAGE229_I12@MSTR_MISC.SHUNT(CHIPS)':
 'B':NET_SHORT='VR_PVTT_GHJ_SNS:PVTT_GHJ',
 CDS_PINID='B';
NODE_NAME     C4G20 1
 '@BASEBOARD_FAB2_LIB.BASEBOARD_FAB2(SCH_1):PAGE229_I23@MSTR_DISCRETE.CAP(CHIPS)':
 'A': CDS_PINID='A';
NODE_NAME     C2F2 1
 '@BASEBOARD_FAB2_LIB.BASEBOARD_FAB2(SCH_1):PAGE229_I28@DEV_DISCRETE.CAP_A(CHIPS)':
 'A': CDS_PINID='A';
NODE_NAME     EU4G2 9
 '@BASEBOARD_FAB2_LIB.BASEBOARD_FAB2(SCH_1):PAGE229_I37@MSTR_VREG.MIC5166(CHIPS)':
 'VTT': CDS_PINID='VTT';
NODE_NAME     C8T3 1
 '@BASEBOARD_FAB2_LIB.BASEBOARD_FAB2(SCH_1):PAGE229_I41@MSTR_DISCRETE.CAP(CHIPS)':
 'A': CDS_PINID='A';
NODE_NAME     C8U10 1
 '@BASEBOARD_FAB2_LIB.BASEBOARD_FAB2(SCH_1):PAGE229_I42@MSTR_DISCRETE.CAP(CHIPS)':
 'A': CDS_PINID='A';
NODE_NAME     C6W12 1
 '@BASEBOARD_FAB2_LIB.BASEBOARD_FAB2(SCH_1):PAGE229_I43@MSTR_DISCRETE.CAP(CHIPS)':
 'A': CDS_PINID='A';
NET_NAME
'PVTT_KLM'
 '@BASEBOARD_FAB2_LIB.BASEBOARD_FAB2(SCH_1):PVTT_KLM':
 C_SIGNAL='@baseboard_fab2_lib.baseboard_fab2(sch_1):pvtt_klm';
NODE_NAME     J1B1 221
 '@BASEBOARD_FAB2_LIB.BASEBOARD_FAB2(SCH_1):PAGE83_I167@MSTR_SCONN.SCONN288_H44441004(CHIPS)':
 'VTT'<0>: CDS_PINID='VTT(0)';
NODE_NAME     J1B1 77
 '@BASEBOARD_FAB2_LIB.BASEBOARD_FAB2(SCH_1):PAGE83_I167@MSTR_SCONN.SCONN288_H44441004(CHIPS)':
 'VTT'<1>: CDS_PINID='VTT(1)';
NODE_NAME     J9M1 221
 '@BASEBOARD_FAB2_LIB.BASEBOARD_FAB2(SCH_1):PAGE84_I57@MSTR_SCONN.SCONN288_H44441003(CHIPS)':
 'VTT'<0>: CDS_PINID='VTT(0)';
NODE_NAME     J9M1 77
 '@BASEBOARD_FAB2_LIB.BASEBOARD_FAB2(SCH_1):PAGE84_I57@MSTR_SCONN.SCONN288_H44441003(CHIPS)':
 'VTT'<1>: CDS_PINID='VTT(1)';
NODE_NAME     J1A2 221
 '@BASEBOARD_FAB2_LIB.BASEBOARD_FAB2(SCH_1):PAGE85_I172@MSTR_SCONN.SCONN288_H44441004(CHIPS)':
 'VTT'<0>: CDS_PINID='VTT(0)';
NODE_NAME     J1A2 77
 '@BASEBOARD_FAB2_LIB.BASEBOARD_FAB2(SCH_1):PAGE85_I172@MSTR_SCONN.SCONN288_H44441004(CHIPS)':
 'VTT'<1>: CDS_PINID='VTT(1)';
NODE_NAME     J9L2 221
 '@BASEBOARD_FAB2_LIB.BASEBOARD_FAB2(SCH_1):PAGE86_I55@MSTR_SCONN.SCONN288_H44441003(CHIPS)':
 'VTT'<0>: CDS_PINID='VTT(0)';
NODE_NAME     J9L2 77
 '@BASEBOARD_FAB2_LIB.BASEBOARD_FAB2(SCH_1):PAGE86_I55@MSTR_SCONN.SCONN288_H44441003(CHIPS)':
 'VTT'<1>: CDS_PINID='VTT(1)';
NODE_NAME     J1A1 221
 '@BASEBOARD_FAB2_LIB.BASEBOARD_FAB2(SCH_1):PAGE87_I169@MSTR_SCONN.SCONN288_H44441004(CHIPS)':
 'VTT'<0>: CDS_PINID='VTT(0)';
NODE_NAME     J1A1 77
 '@BASEBOARD_FAB2_LIB.BASEBOARD_FAB2(SCH_1):PAGE87_I169@MSTR_SCONN.SCONN288_H44441004(CHIPS)':
 'VTT'<1>: CDS_PINID='VTT(1)';
NODE_NAME     J9L1 221
 '@BASEBOARD_FAB2_LIB.BASEBOARD_FAB2(SCH_1):PAGE88_I168@MSTR_SCONN.SCONN288_H44441003(CHIPS)':
 'VTT'<0>: CDS_PINID='VTT(0)';
NODE_NAME     J9L1 77
 '@BASEBOARD_FAB2_LIB.BASEBOARD_FAB2(SCH_1):PAGE88_I168@MSTR_SCONN.SCONN288_H44441003(CHIPS)':
 'VTT'<1>: CDS_PINID='VTT(1)';
NODE_NAME     C4A13 1
 '@BASEBOARD_FAB2_LIB.BASEBOARD_FAB2(SCH_1):PAGE230_I20@MSTR_DISCRETE.CAP(CHIPS)':
 'A': CDS_PINID='A';
NODE_NAME     C8M12 1
 '@BASEBOARD_FAB2_LIB.BASEBOARD_FAB2(SCH_1):PAGE230_I24@DEV_DISCRETE.CAP_A(CHIPS)':
 'A': CDS_PINID='A';
NODE_NAME     SH8L1 2
 '@BASEBOARD_FAB2_LIB.BASEBOARD_FAB2(SCH_1):PAGE230_I30@MSTR_MISC.SHUNT(CHIPS)':
 'B':NET_SHORT='VR_PVTT_KLM_SNS:PVTT_KLM',
 CDS_PINID='B';
NODE_NAME     EU4A2 9
 '@BASEBOARD_FAB2_LIB.BASEBOARD_FAB2(SCH_1):PAGE230_I37@MSTR_VREG.MIC5166(CHIPS)':
 'VTT': CDS_PINID='VTT';
NODE_NAME     C8L3 1
 '@BASEBOARD_FAB2_LIB.BASEBOARD_FAB2(SCH_1):PAGE230_I41@MSTR_DISCRETE.CAP(CHIPS)':
 'A': CDS_PINID='A';
NODE_NAME     C8L4 1
 '@BASEBOARD_FAB2_LIB.BASEBOARD_FAB2(SCH_1):PAGE230_I42@MSTR_DISCRETE.CAP(CHIPS)':
 'A': CDS_PINID='A';
NODE_NAME     C6W13 1
 '@BASEBOARD_FAB2_LIB.BASEBOARD_FAB2(SCH_1):PAGE230_I43@MSTR_DISCRETE.CAP(CHIPS)':
 'A': CDS_PINID='A';
NET_NAME
'PWRGD_CPU0_DRAMPWROK_ABC_G'
 '@BASEBOARD_FAB2_LIB.BASEBOARD_FAB2(SCH_1):PWRGD_CPU0_DRAMPWROK_ABC_G':
 C_SIGNAL='@baseboard_fab2_lib.baseboard_fab2(sch_1):pwrgd_cpu0_drampwrok_abc_g';
NODE_NAME     U5D1 AN30
 '@BASEBOARD_FAB2_LIB.BASEBOARD_FAB2(SCH_1):PAGE21_I259@CHPSET_LIB.SKX_EXT_B(CHIPS)':
 'DDR012_DRAM_PWR_OK': CDS_PINID='DDR012_DRAM_PWR_OK';
NODE_NAME     R3P38 2
 '@BASEBOARD_FAB2_LIB.BASEBOARD_FAB2(SCH_1):PAGE96_I7@MSTR_DISCRETE.RES(CHIPS)':
 'B': CDS_PINID='B';
NODE_NAME     U3P1 3
 '@BASEBOARD_FAB2_LIB.BASEBOARD_FAB2(SCH_1):PAGE96_I42@MSTR_DIGITAL.GTL2014(CHIPS)':
 'B1': CDS_PINID='B1';
NET_NAME
'PWRGD_CPU0_DRAMPWROK_DEF_G'
 '@BASEBOARD_FAB2_LIB.BASEBOARD_FAB2(SCH_1):PWRGD_CPU0_DRAMPWROK_DEF_G':
 C_SIGNAL='@baseboard_fab2_lib.baseboard_fab2(sch_1):pwrgd_cpu0_drampwrok_def_g';
NODE_NAME     U5D1 CR28
 '@BASEBOARD_FAB2_LIB.BASEBOARD_FAB2(SCH_1):PAGE21_I259@CHPSET_LIB.SKX_EXT_B(CHIPS)':
 'DDR345_DRAM_PWR_OK': CDS_PINID='DDR345_DRAM_PWR_OK';
NODE_NAME     R3P29 2
 '@BASEBOARD_FAB2_LIB.BASEBOARD_FAB2(SCH_1):PAGE96_I5@MSTR_DISCRETE.RES(CHIPS)':
 'B': CDS_PINID='B';
NODE_NAME     U3P1 2
 '@BASEBOARD_FAB2_LIB.BASEBOARD_FAB2(SCH_1):PAGE96_I42@MSTR_DIGITAL.GTL2014(CHIPS)':
 'B0': CDS_PINID='B0';
NET_NAME
'PWRGD_CPU0_G'
 '@BASEBOARD_FAB2_LIB.BASEBOARD_FAB2(SCH_1):PWRGD_CPU0_G':
 C_SIGNAL='@baseboard_fab2_lib.baseboard_fab2(sch_1):pwrgd_cpu0_g';
NODE_NAME     U5D1 BC24
 '@BASEBOARD_FAB2_LIB.BASEBOARD_FAB2(SCH_1):PAGE21_I259@CHPSET_LIB.SKX_EXT_B(CHIPS)':
 'PWRGOOD': CDS_PINID='PWRGOOD';
NODE_NAME     R6D8 2
 '@BASEBOARD_FAB2_LIB.BASEBOARD_FAB2(SCH_1):PAGE96_I3@MSTR_DISCRETE.RES(CHIPS)':
 'B': CDS_PINID='B';
NODE_NAME     U3P1 6
 '@BASEBOARD_FAB2_LIB.BASEBOARD_FAB2(SCH_1):PAGE96_I42@MSTR_DIGITAL.GTL2014(CHIPS)':
 'B3': CDS_PINID='B3';
NODE_NAME     R9B14 1
 '@BASEBOARD_FAB2_LIB.BASEBOARD_FAB2(SCH_1):PAGE113_I168@MSTR_DISCRETE.RES(CHIPS)':
 'A': CDS_PINID='A';
NET_NAME
'PWRGD_CPU0_G_R'
 '@BASEBOARD_FAB2_LIB.BASEBOARD_FAB2(SCH_1):PWRGD_CPU0_G_R':
 C_SIGNAL='@baseboard_fab2_lib.baseboard_fab2(sch_1):pwrgd_cpu0_g_r';
NODE_NAME     R9B14 2
 '@BASEBOARD_FAB2_LIB.BASEBOARD_FAB2(SCH_1):PAGE113_I168@MSTR_DISCRETE.RES(CHIPS)':
 'B': CDS_PINID='B';
NODE_NAME     J9B4 7
 '@BASEBOARD_FAB2_LIB.BASEBOARD_FAB2(SCH_1):PAGE113_I175@MSTR_SCONN.SCONN10_C12536004(CHIPS)':
 'IO7': CDS_PINID='IO7';
NET_NAME
'PWRGD_CPU0_LVC3'
 '@BASEBOARD_FAB2_LIB.BASEBOARD_FAB2(SCH_1):PWRGD_CPU0_LVC3':
 C_SIGNAL='@baseboard_fab2_lib.baseboard_fab2(sch_1):pwrgd_cpu0_lvc3';
NODE_NAME     U3P1 9
 '@BASEBOARD_FAB2_LIB.BASEBOARD_FAB2(SCH_1):PAGE96_I42@MSTR_DIGITAL.GTL2014(CHIPS)':
 'A3': CDS_PINID='A3';
NODE_NAME     U8D7 L5
 '@BASEBOARD_FAB2_LIB.BASEBOARD_FAB2(SCH_1):PAGE190_I179@MSTR_MEMORY.LCMXO2_A(CHIPS)':
 'PL11D': CDS_PINID='PL11D';
NET_NAME
'PWRGD_CPU1_DRAMPWROK_GHJ_G'
 '@BASEBOARD_FAB2_LIB.BASEBOARD_FAB2(SCH_1):PWRGD_CPU1_DRAMPWROK_GHJ_G':
 C_SIGNAL='@baseboard_fab2_lib.baseboard_fab2(sch_1):pwrgd_cpu1_drampwrok_ghj_g';
NODE_NAME     U2D1 AN30
 '@BASEBOARD_FAB2_LIB.BASEBOARD_FAB2(SCH_1):PAGE55_I172@CHPSET_LIB.SKX_EXT_B(CHIPS)':
 'DDR012_DRAM_PWR_OK': CDS_PINID='DDR012_DRAM_PWR_OK';
NODE_NAME     R3D21 2
 '@BASEBOARD_FAB2_LIB.BASEBOARD_FAB2(SCH_1):PAGE96_I30@MSTR_DISCRETE.RES(CHIPS)':
 'B': CDS_PINID='B';
NODE_NAME     U4C2 3
 '@BASEBOARD_FAB2_LIB.BASEBOARD_FAB2(SCH_1):PAGE96_I46@MSTR_DIGITAL.GTL2014(CHIPS)':
 'B1': CDS_PINID='B1';
NET_NAME
'PWRGD_CPU1_DRAMPWROK_KLM_G'
 '@BASEBOARD_FAB2_LIB.BASEBOARD_FAB2(SCH_1):PWRGD_CPU1_DRAMPWROK_KLM_G':
 C_SIGNAL='@baseboard_fab2_lib.baseboard_fab2(sch_1):pwrgd_cpu1_drampwrok_klm_g';
NODE_NAME     U2D1 CR28
 '@BASEBOARD_FAB2_LIB.BASEBOARD_FAB2(SCH_1):PAGE55_I172@CHPSET_LIB.SKX_EXT_B(CHIPS)':
 'DDR345_DRAM_PWR_OK': CDS_PINID='DDR345_DRAM_PWR_OK';
NODE_NAME     R7M9 2
 '@BASEBOARD_FAB2_LIB.BASEBOARD_FAB2(SCH_1):PAGE96_I28@MSTR_DISCRETE.RES(CHIPS)':
 'B': CDS_PINID='B';
NODE_NAME     U4C2 2
 '@BASEBOARD_FAB2_LIB.BASEBOARD_FAB2(SCH_1):PAGE96_I46@MSTR_DIGITAL.GTL2014(CHIPS)':
 'B0': CDS_PINID='B0';
NET_NAME
'PWRGD_CPU1_G'
 '@BASEBOARD_FAB2_LIB.BASEBOARD_FAB2(SCH_1):PWRGD_CPU1_G':
 C_SIGNAL='@baseboard_fab2_lib.baseboard_fab2(sch_1):pwrgd_cpu1_g';
NODE_NAME     U2D1 BC24
 '@BASEBOARD_FAB2_LIB.BASEBOARD_FAB2(SCH_1):PAGE55_I172@CHPSET_LIB.SKX_EXT_B(CHIPS)':
 'PWRGOOD': CDS_PINID='PWRGOOD';
NODE_NAME     R3D15 2
 '@BASEBOARD_FAB2_LIB.BASEBOARD_FAB2(SCH_1):PAGE96_I26@MSTR_DISCRETE.RES(CHIPS)':
 'B': CDS_PINID='B';
NODE_NAME     U4C2 6
 '@BASEBOARD_FAB2_LIB.BASEBOARD_FAB2(SCH_1):PAGE96_I46@MSTR_DIGITAL.GTL2014(CHIPS)':
 'B3': CDS_PINID='B3';
NET_NAME
'PWRGD_CPU1_LVC3'
 '@BASEBOARD_FAB2_LIB.BASEBOARD_FAB2(SCH_1):PWRGD_CPU1_LVC3':
 C_SIGNAL='@baseboard_fab2_lib.baseboard_fab2(sch_1):pwrgd_cpu1_lvc3';
NODE_NAME     U4C2 9
 '@BASEBOARD_FAB2_LIB.BASEBOARD_FAB2(SCH_1):PAGE96_I46@MSTR_DIGITAL.GTL2014(CHIPS)':
 'A3': CDS_PINID='A3';
NODE_NAME     U8D7 M10
 '@BASEBOARD_FAB2_LIB.BASEBOARD_FAB2(SCH_1):PAGE190_I179@MSTR_MEMORY.LCMXO2_A(CHIPS)':
 'PB21C': CDS_PINID='PB21C';
NET_NAME
'PWRGD_CPUPWRGD'
 '@BASEBOARD_FAB2_LIB.BASEBOARD_FAB2(SCH_1):PWRGD_CPUPWRGD':
 C_SIGNAL='@baseboard_fab2_lib.baseboard_fab2(sch_1):pwrgd_cpupwrgd';
NODE_NAME     R3R3 2
 '@BASEBOARD_FAB2_LIB.BASEBOARD_FAB2(SCH_1):PAGE92_I61@MSTR_DISCRETE.RES(CHIPS)':
 'B': CDS_PINID='B';
NODE_NAME     U8D7 F13
 '@BASEBOARD_FAB2_LIB.BASEBOARD_FAB2(SCH_1):PAGE191_I59@MSTR_MEMORY.LCMXO2_A(CHIPS)':
 'PR3C': CDS_PINID='PR3C';
NET_NAME
'PWRGD_CPUPWRGD_GTL'
 '@BASEBOARD_FAB2_LIB.BASEBOARD_FAB2(SCH_1):PWRGD_CPUPWRGD_GTL':
 C_SIGNAL='@baseboard_fab2_lib.baseboard_fab2(sch_1):pwrgd_cpupwrgd_gtl';
NODE_NAME     U3P2 2
 '@BASEBOARD_FAB2_LIB.BASEBOARD_FAB2(SCH_1):PAGE92_I1@MSTR_DIGITAL.GTL2014(CHIPS)':
 'B0': CDS_PINID='B0';
NODE_NAME     U7C1 R9
 '@BASEBOARD_FAB2_LIB.BASEBOARD_FAB2(SCH_1):PAGE118_I73@MSTR_U_PROC.LBG_CORE_QAT_EXT_D(CHIPS)':
 'PROC_PWRGD': CDS_PINID='PROC_PWRGD';
NET_NAME
'PWRGD_CPUPWRGD_R1'
 '@BASEBOARD_FAB2_LIB.BASEBOARD_FAB2(SCH_1):PWRGD_CPUPWRGD_R1':
 C_SIGNAL='@baseboard_fab2_lib.baseboard_fab2(sch_1):pwrgd_cpupwrgd_r1';
NODE_NAME     U3P2 13
 '@BASEBOARD_FAB2_LIB.BASEBOARD_FAB2(SCH_1):PAGE92_I1@MSTR_DIGITAL.GTL2014(CHIPS)':
 'A0': CDS_PINID='A0';
NODE_NAME     R3R3 1
 '@BASEBOARD_FAB2_LIB.BASEBOARD_FAB2(SCH_1):PAGE92_I61@MSTR_DISCRETE.RES(CHIPS)':
 'A': CDS_PINID='A';
NET_NAME
'PWRGD_DRAMPWRGD'
 '@BASEBOARD_FAB2_LIB.BASEBOARD_FAB2(SCH_1):PWRGD_DRAMPWRGD':
 C_SIGNAL='@baseboard_fab2_lib.baseboard_fab2(sch_1):pwrgd_drampwrgd';
NODE_NAME     U3P1 13
 '@BASEBOARD_FAB2_LIB.BASEBOARD_FAB2(SCH_1):PAGE96_I42@MSTR_DIGITAL.GTL2014(CHIPS)':
 'A0': CDS_PINID='A0';
NODE_NAME     U3P1 12
 '@BASEBOARD_FAB2_LIB.BASEBOARD_FAB2(SCH_1):PAGE96_I42@MSTR_DIGITAL.GTL2014(CHIPS)':
 'A1': CDS_PINID='A1';
NODE_NAME     U4C2 13
 '@BASEBOARD_FAB2_LIB.BASEBOARD_FAB2(SCH_1):PAGE96_I46@MSTR_DIGITAL.GTL2014(CHIPS)':
 'A0': CDS_PINID='A0';
NODE_NAME     U4C2 12
 '@BASEBOARD_FAB2_LIB.BASEBOARD_FAB2(SCH_1):PAGE96_I46@MSTR_DIGITAL.GTL2014(CHIPS)':
 'A1': CDS_PINID='A1';
NODE_NAME     U8D7 T15
 '@BASEBOARD_FAB2_LIB.BASEBOARD_FAB2(SCH_1):PAGE190_I179@MSTR_MEMORY.LCMXO2_A(CHIPS)':
 'PB25C': CDS_PINID='PB25C';
NET_NAME
'PWRGD_DSW_PWROK'
 '@BASEBOARD_FAB2_LIB.BASEBOARD_FAB2(SCH_1):PWRGD_DSW_PWROK':
 C_SIGNAL='@baseboard_fab2_lib.baseboard_fab2(sch_1):pwrgd_dsw_pwrok';
NODE_NAME     U7C1 K13
 '@BASEBOARD_FAB2_LIB.BASEBOARD_FAB2(SCH_1):PAGE118_I73@MSTR_U_PROC.LBG_CORE_QAT_EXT_D(CHIPS)':
 'DSW_PWROK': CDS_PINID='DSW_PWROK';
NODE_NAME     U8D2 2
 '@BASEBOARD_FAB2_LIB.BASEBOARD_FAB2(SCH_1):PAGE157_I374@MSTR_TTL.TTL1G07_A(CHIPS)':
 'A': CDS_PINID='A';
NODE_NAME     U8D7 B11
 '@BASEBOARD_FAB2_LIB.BASEBOARD_FAB2(SCH_1):PAGE191_I59@MSTR_MEMORY.LCMXO2_A(CHIPS)':
 'PT22A': CDS_PINID='PT22A';
NODE_NAME     R3P44 2
 '@BASEBOARD_FAB2_LIB.BASEBOARD_FAB2(SCH_1):PAGE196_I59@MSTR_DISCRETE.RES(CHIPS)':
 'B': CDS_PINID='B';
NODE_NAME     U7D3 4
 '@BASEBOARD_FAB2_LIB.BASEBOARD_FAB2(SCH_1):PAGE196_I70@MSTR_ANALOG.ADM1085(CHIPS)':
 'ENOUT': CDS_PINID='ENOUT';
NODE_NAME     CR7E1 2
 '@BASEBOARD_FAB2_LIB.BASEBOARD_FAB2(SCH_1):PAGE196_I103@MSTR_DISCRETE.DIODE(CHIPS)':
 'A': CDS_PINID='A';
NODE_NAME     U9P2 6
 '@BASEBOARD_FAB2_LIB.BASEBOARD_FAB2(SCH_1):PAGE200_I200@MSTR_VREG.TPS3700(CHIPS)':
 'OUTA': CDS_PINID='OUTA';
NODE_NAME     U6W1 17
 '@BASEBOARD_FAB2_LIB.BASEBOARD_FAB2(SCH_1):PAGE247_I120@W_HDL.TCA9555PWR-GP(CHIPS)':
 'P14': CDS_PINID='P14';
NODE_NAME     U25W9 2
 '@BASEBOARD_FAB2_LIB.BASEBOARD_FAB2(SCH_1):PAGE157_I394@MSTR_TTL.TTL1G07_A(CHIPS)':
 'A': CDS_PINID='A';
NET_NAME
'PWRGD_P12V_HSC'
 '@BASEBOARD_FAB2_LIB.BASEBOARD_FAB2(SCH_1):PWRGD_P12V_HSC':
 C_SIGNAL='@baseboard_fab2_lib.baseboard_fab2(sch_1):pwrgd_p12v_hsc';
NODE_NAME     U8E2 3
 '@BASEBOARD_FAB2_LIB.BASEBOARD_FAB2(SCH_1):PAGE196_I89@MSTR_ANALOG.ADM809(CHIPS)':
 'VCC': CDS_PINID='VCC';
NODE_NAME     C8E3 1
 '@BASEBOARD_FAB2_LIB.BASEBOARD_FAB2(SCH_1):PAGE196_I94@DEV_DISCRETE.CAP_A(CHIPS)':
 'A': CDS_PINID='A';
NODE_NAME     CR8E1 1
 '@BASEBOARD_FAB2_LIB.BASEBOARD_FAB2(SCH_1):PAGE196_I128@MSTR_DISCRETE.DIODE(CHIPS)':
 'C': CDS_PINID='C';
NODE_NAME     R1D33 2
 '@BASEBOARD_FAB2_LIB.BASEBOARD_FAB2(SCH_1):PAGE199_I108@MSTR_DISCRETE.RES(CHIPS)':
 'B': CDS_PINID='B';
NET_NAME
'PWRGD_P12V_HSC_DLY'
 '@BASEBOARD_FAB2_LIB.BASEBOARD_FAB2(SCH_1):PWRGD_P12V_HSC_DLY':
 C_SIGNAL='@baseboard_fab2_lib.baseboard_fab2(sch_1):pwrgd_p12v_hsc_dly';
NODE_NAME     R8E7 2
 '@BASEBOARD_FAB2_LIB.BASEBOARD_FAB2(SCH_1):PAGE196_I90@MSTR_DISCRETE.RES(CHIPS)':
 'B': CDS_PINID='B';
NODE_NAME     CR8E1 2
 '@BASEBOARD_FAB2_LIB.BASEBOARD_FAB2(SCH_1):PAGE196_I128@MSTR_DISCRETE.DIODE(CHIPS)':
 'A': CDS_PINID='A';
NODE_NAME     C8E13 1
 '@BASEBOARD_FAB2_LIB.BASEBOARD_FAB2(SCH_1):PAGE241_I41@MSTR_DISCRETE.CAP(CHIPS)':
 'A': CDS_PINID='A';
NODE_NAME     R8E33 1
 '@BASEBOARD_FAB2_LIB.BASEBOARD_FAB2(SCH_1):PAGE241_I91@MSTR_DISCRETE.RES(CHIPS)':
 'A': CDS_PINID='A';
NODE_NAME     U14E3 1
 '@BASEBOARD_FAB2_LIB.BASEBOARD_FAB2(SCH_1):PAGE248_I19@MSTR_TTL.TTL1G08(CHIPS)':
 'A'<0>: CDS_PINID='A(0)';
NODE_NAME     U8E1 10
 '@BASEBOARD_FAB2_LIB.BASEBOARD_FAB2(SCH_1):PAGE181_I60@MSTR_TTL.TTL08(CHIPS)':
 'B'<0>: CDS_PINID='B(0)';
NET_NAME
'PWRGD_P12V_HSC_DLY_R'
 '@BASEBOARD_FAB2_LIB.BASEBOARD_FAB2(SCH_1):PWRGD_P12V_HSC_DLY_R':
 C_SIGNAL='@baseboard_fab2_lib.baseboard_fab2(sch_1):pwrgd_p12v_hsc_dly_r';
NODE_NAME     U8E2 2
 '@BASEBOARD_FAB2_LIB.BASEBOARD_FAB2(SCH_1):PAGE196_I89@MSTR_ANALOG.ADM809(CHIPS)':
 'RESET_N': CDS_PINID='RESET_N';
NODE_NAME     R8E7 1
 '@BASEBOARD_FAB2_LIB.BASEBOARD_FAB2(SCH_1):PAGE196_I90@MSTR_DISCRETE.RES(CHIPS)':
 'A': CDS_PINID='A';
NET_NAME
'PWRGD_P12V_MAIN'
 '@BASEBOARD_FAB2_LIB.BASEBOARD_FAB2(SCH_1):PWRGD_P12V_MAIN':
 C_SIGNAL='@baseboard_fab2_lib.baseboard_fab2(sch_1):pwrgd_p12v_main';
NODE_NAME     U8D7 B5
 '@BASEBOARD_FAB2_LIB.BASEBOARD_FAB2(SCH_1):PAGE191_I59@MSTR_MEMORY.LCMXO2_A(CHIPS)':
 'PT9B': CDS_PINID='PT9B';
NODE_NAME     R8D42 2
 '@BASEBOARD_FAB2_LIB.BASEBOARD_FAB2(SCH_1):PAGE196_I106@MSTR_DISCRETE.RES(CHIPS)':
 'B': CDS_PINID='B';
NET_NAME
'PWRGD_P12V_MAIN_R'
 '@BASEBOARD_FAB2_LIB.BASEBOARD_FAB2(SCH_1):PWRGD_P12V_MAIN_R':
 C_SIGNAL='@baseboard_fab2_lib.baseboard_fab2(sch_1):pwrgd_p12v_main_r';
NODE_NAME     U8D8 6
 '@BASEBOARD_FAB2_LIB.BASEBOARD_FAB2(SCH_1):PAGE196_I104@MSTR_VREG.TPS3700(CHIPS)':
 'OUTA': CDS_PINID='OUTA';
NODE_NAME     R8D42 1
 '@BASEBOARD_FAB2_LIB.BASEBOARD_FAB2(SCH_1):PAGE196_I106@MSTR_DISCRETE.RES(CHIPS)':
 'A': CDS_PINID='A';
NODE_NAME     R8D41 2
 '@BASEBOARD_FAB2_LIB.BASEBOARD_FAB2(SCH_1):PAGE196_I120@MSTR_DISCRETE.RES(CHIPS)':
 'B': CDS_PINID='B';
NET_NAME
'PWRGD_P12V_R'
 '@BASEBOARD_FAB2_LIB.BASEBOARD_FAB2(SCH_1):PWRGD_P12V_R':
 C_SIGNAL='@baseboard_fab2_lib.baseboard_fab2(sch_1):pwrgd_p12v_r';
NODE_NAME     EU1D2 18
 '@BASEBOARD_FAB2_LIB.BASEBOARD_FAB2(SCH_1):PAGE199_I10@MSTR_CONTROLLER.ADM1278(CHIPS)':
 'PWRGD': CDS_PINID='PWRGD';
NODE_NAME     R9P18 2
 '@BASEBOARD_FAB2_LIB.BASEBOARD_FAB2(SCH_1):PAGE199_I41@MSTR_DISCRETE.RES(CHIPS)':
 'B': CDS_PINID='B';
NODE_NAME     R1D31 1
 '@BASEBOARD_FAB2_LIB.BASEBOARD_FAB2(SCH_1):PAGE199_I43@MSTR_DISCRETE.RES(CHIPS)':
 'A': CDS_PINID='A';
NODE_NAME     R1D33 1
 '@BASEBOARD_FAB2_LIB.BASEBOARD_FAB2(SCH_1):PAGE199_I108@MSTR_DISCRETE.RES(CHIPS)':
 'A': CDS_PINID='A';
NET_NAME
'PWRGD_P1V15_BMC_STBY'
 '@BASEBOARD_FAB2_LIB.BASEBOARD_FAB2(SCH_1):PWRGD_P1V15_BMC_STBY':
 C_SIGNAL='@baseboard_fab2_lib.baseboard_fab2(sch_1):pwrgd_p1v15_bmc_stby';
NODE_NAME     U8D7 E7
 '@BASEBOARD_FAB2_LIB.BASEBOARD_FAB2(SCH_1):PAGE191_I59@MSTR_MEMORY.LCMXO2_A(CHIPS)':
 'PT12B': CDS_PINID='PT12B';
NODE_NAME     R9F11 2
 '@BASEBOARD_FAB2_LIB.BASEBOARD_FAB2(SCH_1):PAGE238_I41@MSTR_DISCRETE.RES(CHIPS)':
 'B': CDS_PINID='B';
NET_NAME
'PWRGD_P1V15_BMC_STBY_R'
 '@BASEBOARD_FAB2_LIB.BASEBOARD_FAB2(SCH_1):PWRGD_P1V15_BMC_STBY_R':
 C_SIGNAL='@baseboard_fab2_lib.baseboard_fab2(sch_1):pwrgd_p1v15_bmc_stby_r';
NODE_NAME     C9F8 1
 '@BASEBOARD_FAB2_LIB.BASEBOARD_FAB2(SCH_1):PAGE238_I19@MSTR_DISCRETE.CAP(CHIPS)':
 'A': CDS_PINID='A';
NODE_NAME     R9F13 2
 '@BASEBOARD_FAB2_LIB.BASEBOARD_FAB2(SCH_1):PAGE238_I21@MSTR_DISCRETE.RES(CHIPS)':
 'B': CDS_PINID='B';
NODE_NAME     EU9F1 5
 '@BASEBOARD_FAB2_LIB.BASEBOARD_FAB2(SCH_1):PAGE238_I40@MSTR_VREG.RT9059(CHIPS)':
 'PGOOD': CDS_PINID='PGOOD';
NODE_NAME     R9F11 1
 '@BASEBOARD_FAB2_LIB.BASEBOARD_FAB2(SCH_1):PAGE238_I41@MSTR_DISCRETE.RES(CHIPS)':
 'A': CDS_PINID='A';
NET_NAME
'PWRGD_P1V2_BMC_STBY'
 '@BASEBOARD_FAB2_LIB.BASEBOARD_FAB2(SCH_1):PWRGD_P1V2_BMC_STBY':
 C_SIGNAL='@baseboard_fab2_lib.baseboard_fab2(sch_1):pwrgd_p1v2_bmc_stby';
NODE_NAME     C9F9 1
 '@BASEBOARD_FAB2_LIB.BASEBOARD_FAB2(SCH_1):PAGE238_I5@MSTR_DISCRETE.CAP(CHIPS)':
 'A': CDS_PINID='A';
NODE_NAME     EU9F1 6
 '@BASEBOARD_FAB2_LIB.BASEBOARD_FAB2(SCH_1):PAGE238_I40@MSTR_VREG.RT9059(CHIPS)':
 'EN': CDS_PINID='EN';
NODE_NAME     R1T9 2
 '@BASEBOARD_FAB2_LIB.BASEBOARD_FAB2(SCH_1):PAGE239_I72@MSTR_DISCRETE.RES(CHIPS)':
 'B': CDS_PINID='B';
NET_NAME
'PWRGD_P1V2_BMC_STBY_R'
 '@BASEBOARD_FAB2_LIB.BASEBOARD_FAB2(SCH_1):PWRGD_P1V2_BMC_STBY_R':
 C_SIGNAL='@baseboard_fab2_lib.baseboard_fab2(sch_1):pwrgd_p1v2_bmc_stby_r';
NODE_NAME     C9F10 1
 '@BASEBOARD_FAB2_LIB.BASEBOARD_FAB2(SCH_1):PAGE239_I4@MSTR_DISCRETE.CAP(CHIPS)':
 'A': CDS_PINID='A';
NODE_NAME     R9F12 2
 '@BASEBOARD_FAB2_LIB.BASEBOARD_FAB2(SCH_1):PAGE239_I6@MSTR_DISCRETE.RES(CHIPS)':
 'B': CDS_PINID='B';
NODE_NAME     EU9F2 5
 '@BASEBOARD_FAB2_LIB.BASEBOARD_FAB2(SCH_1):PAGE239_I70@MSTR_VREG.RT9059(CHIPS)':
 'PGOOD': CDS_PINID='PGOOD';
NODE_NAME     R1T9 1
 '@BASEBOARD_FAB2_LIB.BASEBOARD_FAB2(SCH_1):PAGE239_I72@MSTR_DISCRETE.RES(CHIPS)':
 'A': CDS_PINID='A';
NET_NAME
'PWRGD_P1V8MCP_CPU0'
 '@BASEBOARD_FAB2_LIB.BASEBOARD_FAB2(SCH_1):PWRGD_P1V8MCP_CPU0':
 C_SIGNAL='@baseboard_fab2_lib.baseboard_fab2(sch_1):pwrgd_p1v8mcp_cpu0';
NODE_NAME     U8D7 D15
 '@BASEBOARD_FAB2_LIB.BASEBOARD_FAB2(SCH_1):PAGE191_I59@MSTR_MEMORY.LCMXO2_A(CHIPS)':
 'PR2D': CDS_PINID='PR2D';
NODE_NAME     J6B1 B15
 '@BASEBOARD_FAB2_LIB.BASEBOARD_FAB2(SCH_1):PAGE194_I56@MSTR_SCONN.SCONN120_H61426002(CHIPS)':
 'IOB15': CDS_PINID='IOB15';
NET_NAME
'PWRGD_P1V8MCP_CPU1'
 '@BASEBOARD_FAB2_LIB.BASEBOARD_FAB2(SCH_1):PWRGD_P1V8MCP_CPU1':
 C_SIGNAL='@baseboard_fab2_lib.baseboard_fab2(sch_1):pwrgd_p1v8mcp_cpu1';
NODE_NAME     U8D7 D16
 '@BASEBOARD_FAB2_LIB.BASEBOARD_FAB2(SCH_1):PAGE191_I59@MSTR_MEMORY.LCMXO2_A(CHIPS)':
 'PR2A': CDS_PINID='PR2A';
NODE_NAME     J4B2 B15
 '@BASEBOARD_FAB2_LIB.BASEBOARD_FAB2(SCH_1):PAGE193_I46@MSTR_SCONN.SCONN120_H61426002(CHIPS)':
 'IOB15': CDS_PINID='IOB15';
NET_NAME
'PWRGD_P1V8_PCH_STBY'
 '@BASEBOARD_FAB2_LIB.BASEBOARD_FAB2(SCH_1):PWRGD_P1V8_PCH_STBY':
 C_SIGNAL='@baseboard_fab2_lib.baseboard_fab2(sch_1):pwrgd_p1v8_pch_stby';
NODE_NAME     R2L17 1
 '@BASEBOARD_FAB2_LIB.BASEBOARD_FAB2(SCH_1):PAGE235_I221@MSTR_DISCRETE.RES(CHIPS)':
 'A': CDS_PINID='A';
NODE_NAME     R8A11 2
 '@BASEBOARD_FAB2_LIB.BASEBOARD_FAB2(SCH_1):PAGE237_I90@MSTR_DISCRETE.RES(CHIPS)':
 'B': CDS_PINID='B';
NET_NAME
'PWRGD_P1V8_PCH_STBY_R'
 '@BASEBOARD_FAB2_LIB.BASEBOARD_FAB2(SCH_1):PWRGD_P1V8_PCH_STBY_R':
 C_SIGNAL='@baseboard_fab2_lib.baseboard_fab2(sch_1):pwrgd_p1v8_pch_stby_r';
NODE_NAME     R8A10 2
 '@BASEBOARD_FAB2_LIB.BASEBOARD_FAB2(SCH_1):PAGE237_I3@MSTR_DISCRETE.RES(CHIPS)':
 'B': CDS_PINID='B';
NODE_NAME     C8A11 1
 '@BASEBOARD_FAB2_LIB.BASEBOARD_FAB2(SCH_1):PAGE237_I5@MSTR_DISCRETE.CAP(CHIPS)':
 'A': CDS_PINID='A';
NODE_NAME     EU8A2 5
 '@BASEBOARD_FAB2_LIB.BASEBOARD_FAB2(SCH_1):PAGE237_I86@MSTR_VREG.RT9059(CHIPS)':
 'PGOOD': CDS_PINID='PGOOD';
NODE_NAME     R8A11 1
 '@BASEBOARD_FAB2_LIB.BASEBOARD_FAB2(SCH_1):PAGE237_I90@MSTR_DISCRETE.RES(CHIPS)':
 'A': CDS_PINID='A';
NET_NAME
'PWRGD_P2V5_BMC_STBY'
 '@BASEBOARD_FAB2_LIB.BASEBOARD_FAB2(SCH_1):PWRGD_P2V5_BMC_STBY':
 C_SIGNAL='@baseboard_fab2_lib.baseboard_fab2(sch_1):pwrgd_p2v5_bmc_stby';
NODE_NAME     C9F6 1
 '@BASEBOARD_FAB2_LIB.BASEBOARD_FAB2(SCH_1):PAGE239_I30@MSTR_DISCRETE.CAP(CHIPS)':
 'A': CDS_PINID='A';
NODE_NAME     EU9F2 6
 '@BASEBOARD_FAB2_LIB.BASEBOARD_FAB2(SCH_1):PAGE239_I70@MSTR_VREG.RT9059(CHIPS)':
 'EN': CDS_PINID='EN';
NODE_NAME     R1W9 2
 '@BASEBOARD_FAB2_LIB.BASEBOARD_FAB2(SCH_1):PAGE239_I77@MSTR_DISCRETE.RES(CHIPS)':
 'B': CDS_PINID='B';
NET_NAME
'PWRGD_P2V5_BMC_STBY_R'
 '@BASEBOARD_FAB2_LIB.BASEBOARD_FAB2(SCH_1):PWRGD_P2V5_BMC_STBY_R':
 C_SIGNAL='@baseboard_fab2_lib.baseboard_fab2(sch_1):pwrgd_p2v5_bmc_stby_r';
NODE_NAME     EU25F2 5
 '@BASEBOARD_FAB2_LIB.BASEBOARD_FAB2(SCH_1):PAGE239_I73@MSTR_VREG.RT9059(CHIPS)':
 'PGOOD': CDS_PINID='PGOOD';
NODE_NAME     R1W9 1
 '@BASEBOARD_FAB2_LIB.BASEBOARD_FAB2(SCH_1):PAGE239_I77@MSTR_DISCRETE.RES(CHIPS)':
 'A': CDS_PINID='A';
NODE_NAME     R9W12 2
 '@BASEBOARD_FAB2_LIB.BASEBOARD_FAB2(SCH_1):PAGE239_I79@MSTR_DISCRETE.RES(CHIPS)':
 'B': CDS_PINID='B';
NODE_NAME     C9W10 1
 '@BASEBOARD_FAB2_LIB.BASEBOARD_FAB2(SCH_1):PAGE239_I84@MSTR_DISCRETE.CAP(CHIPS)':
 'A': CDS_PINID='A';
NET_NAME
'PWRGD_P3V3'
 '@BASEBOARD_FAB2_LIB.BASEBOARD_FAB2(SCH_1):PWRGD_P3V3':
 C_SIGNAL='@baseboard_fab2_lib.baseboard_fab2(sch_1):pwrgd_p3v3';
NODE_NAME     R1L12 1
 '@BASEBOARD_FAB2_LIB.BASEBOARD_FAB2(SCH_1):PAGE175_I63@MSTR_DISCRETE.RES(CHIPS)':
 'A': CDS_PINID='A';
NODE_NAME     U8D7 H6
 '@BASEBOARD_FAB2_LIB.BASEBOARD_FAB2(SCH_1):PAGE190_I179@MSTR_MEMORY.LCMXO2_A(CHIPS)':
 'PL5D': CDS_PINID='PL5D';
NODE_NAME     R1L16 2
 '@BASEBOARD_FAB2_LIB.BASEBOARD_FAB2(SCH_1):PAGE196_I68@MSTR_DISCRETE.RES(CHIPS)':
 'B': CDS_PINID='B';
NODE_NAME     U14E3 2
 '@BASEBOARD_FAB2_LIB.BASEBOARD_FAB2(SCH_1):PAGE248_I19@MSTR_TTL.TTL1G08(CHIPS)':
 'B'<0>: CDS_PINID='B(0)';
NET_NAME
'PWRGD_P3V3_R'
 '@BASEBOARD_FAB2_LIB.BASEBOARD_FAB2(SCH_1):PWRGD_P3V3_R':
 C_SIGNAL='@baseboard_fab2_lib.baseboard_fab2(sch_1):pwrgd_p3v3_r';
NODE_NAME     U1L2 1
 '@BASEBOARD_FAB2_LIB.BASEBOARD_FAB2(SCH_1):PAGE175_I57@MSTR_TTL.TTL1G86(CHIPS)':
 'A': CDS_PINID='A';
NODE_NAME     R1L12 2
 '@BASEBOARD_FAB2_LIB.BASEBOARD_FAB2(SCH_1):PAGE175_I63@MSTR_DISCRETE.RES(CHIPS)':
 'B': CDS_PINID='B';
NET_NAME
'PWRGD_P3V3_R1'
 '@BASEBOARD_FAB2_LIB.BASEBOARD_FAB2(SCH_1):PWRGD_P3V3_R1':
 C_SIGNAL='@baseboard_fab2_lib.baseboard_fab2(sch_1):pwrgd_p3v3_r1';
NODE_NAME     R1L16 1
 '@BASEBOARD_FAB2_LIB.BASEBOARD_FAB2(SCH_1):PAGE196_I68@MSTR_DISCRETE.RES(CHIPS)':
 'A': CDS_PINID='A';
NODE_NAME     U1L3 2
 '@BASEBOARD_FAB2_LIB.BASEBOARD_FAB2(SCH_1):PAGE196_I80@MSTR_ANALOG.ADM809(CHIPS)':
 'RESET_N': CDS_PINID='RESET_N';
NET_NAME
'PWRGD_P3V3_STBY'
 '@BASEBOARD_FAB2_LIB.BASEBOARD_FAB2(SCH_1):PWRGD_P3V3_STBY':
 C_SIGNAL='@baseboard_fab2_lib.baseboard_fab2(sch_1):pwrgd_p3v3_stby';
NODE_NAME     EU8F2 40
 '@BASEBOARD_FAB2_LIB.BASEBOARD_FAB2(SCH_1):PAGE101_I34@MSTR_CLOCK.ICS9FGP204(CHIPS)':
 'VTTPWR_GD_PD_N': CDS_PINID='VTTPWR_GD_PD_N';
NODE_NAME     J7G2 5
 '@BASEBOARD_FAB2_LIB.BASEBOARD_FAB2(SCH_1):PAGE189_I47@MSTR_CONN.CONN8_C77962004(CHIPS)':
 'IO5': CDS_PINID='IO5';
NODE_NAME     U8D7 L12
 '@BASEBOARD_FAB2_LIB.BASEBOARD_FAB2(SCH_1):PAGE191_I59@MSTR_MEMORY.LCMXO2_A(CHIPS)':
 'PR10D': CDS_PINID='PR10D';
NODE_NAME     U7D3 1
 '@BASEBOARD_FAB2_LIB.BASEBOARD_FAB2(SCH_1):PAGE196_I70@MSTR_ANALOG.ADM1085(CHIPS)':
 'ENIN': CDS_PINID='ENIN';
NODE_NAME     R3P50 2
 '@BASEBOARD_FAB2_LIB.BASEBOARD_FAB2(SCH_1):PAGE196_I71@MSTR_DISCRETE.RES(CHIPS)':
 'B': CDS_PINID='B';
NODE_NAME     CR7E1 1
 '@BASEBOARD_FAB2_LIB.BASEBOARD_FAB2(SCH_1):PAGE196_I103@MSTR_DISCRETE.DIODE(CHIPS)':
 'C': CDS_PINID='C';
NODE_NAME     C8A10 1
 '@BASEBOARD_FAB2_LIB.BASEBOARD_FAB2(SCH_1):PAGE237_I55@MSTR_DISCRETE.CAP(CHIPS)':
 'A': CDS_PINID='A';
NODE_NAME     EU8A2 6
 '@BASEBOARD_FAB2_LIB.BASEBOARD_FAB2(SCH_1):PAGE237_I86@MSTR_VREG.RT9059(CHIPS)':
 'EN': CDS_PINID='EN';
NODE_NAME     R8F10 2
 '@BASEBOARD_FAB2_LIB.BASEBOARD_FAB2(SCH_1):PAGE240_I171@MSTR_DISCRETE.RES(CHIPS)':
 'B': CDS_PINID='B';
NODE_NAME     EU25F2 6
 '@BASEBOARD_FAB2_LIB.BASEBOARD_FAB2(SCH_1):PAGE239_I73@MSTR_VREG.RT9059(CHIPS)':
 'EN': CDS_PINID='EN';
NODE_NAME     C9W6 1
 '@BASEBOARD_FAB2_LIB.BASEBOARD_FAB2(SCH_1):PAGE239_I91@MSTR_DISCRETE.CAP(CHIPS)':
 'A': CDS_PINID='A';
NET_NAME
'PWRGD_P3V3_STBY_R'
 '@BASEBOARD_FAB2_LIB.BASEBOARD_FAB2(SCH_1):PWRGD_P3V3_STBY_R':
 C_SIGNAL='@baseboard_fab2_lib.baseboard_fab2(sch_1):pwrgd_p3v3_stby_r';
NODE_NAME     C8F2 1
 '@BASEBOARD_FAB2_LIB.BASEBOARD_FAB2(SCH_1):PAGE240_I116@MSTR_DISCRETE.CAP(CHIPS)':
 'A': CDS_PINID='A';
NODE_NAME     R8F5 2
 '@BASEBOARD_FAB2_LIB.BASEBOARD_FAB2(SCH_1):PAGE240_I117@MSTR_DISCRETE.RES(CHIPS)':
 'B': CDS_PINID='B';
NODE_NAME     EU8F1 9
 '@BASEBOARD_FAB2_LIB.BASEBOARD_FAB2(SCH_1):PAGE240_I125@MSTR_VREG.RT8240(CHIPS)':
 'PGOOD': CDS_PINID='PGOOD';
NODE_NAME     R8F10 1
 '@BASEBOARD_FAB2_LIB.BASEBOARD_FAB2(SCH_1):PAGE240_I171@MSTR_DISCRETE.RES(CHIPS)':
 'A': CDS_PINID='A';
NET_NAME
'PWRGD_P5V'
 '@BASEBOARD_FAB2_LIB.BASEBOARD_FAB2(SCH_1):PWRGD_P5V':
 C_SIGNAL='@baseboard_fab2_lib.baseboard_fab2(sch_1):pwrgd_p5v';
NODE_NAME     U8D7 J6
 '@BASEBOARD_FAB2_LIB.BASEBOARD_FAB2(SCH_1):PAGE190_I179@MSTR_MEMORY.LCMXO2_A(CHIPS)':
 'PL6D': CDS_PINID='PL6D';
NODE_NAME     R2P20 2
 '@BASEBOARD_FAB2_LIB.BASEBOARD_FAB2(SCH_1):PAGE196_I65@MSTR_DISCRETE.RES(CHIPS)':
 'B': CDS_PINID='B';
NET_NAME
'PWRGD_P5V_N'
 '@BASEBOARD_FAB2_LIB.BASEBOARD_FAB2(SCH_1):PWRGD_P5V_N':
 C_SIGNAL='@baseboard_fab2_lib.baseboard_fab2(sch_1):pwrgd_p5v_n';
NODE_NAME     U8D8 1
 '@BASEBOARD_FAB2_LIB.BASEBOARD_FAB2(SCH_1):PAGE196_I104@MSTR_VREG.TPS3700(CHIPS)':
 'OUTB': CDS_PINID='OUTB';
NODE_NAME     R2P18 2
 '@BASEBOARD_FAB2_LIB.BASEBOARD_FAB2(SCH_1):PAGE196_I121@MSTR_DISCRETE.RES(CHIPS)':
 'B': CDS_PINID='B';
NODE_NAME     Q1P2 1
 '@BASEBOARD_FAB2_LIB.BASEBOARD_FAB2(SCH_1):PAGE196_I129@MSTR_DISCRETE.FET_N(CHIPS)':
 'GATE': CDS_PINID='GATE';
NET_NAME
'PWRGD_P5V_R'
 '@BASEBOARD_FAB2_LIB.BASEBOARD_FAB2(SCH_1):PWRGD_P5V_R':
 C_SIGNAL='@baseboard_fab2_lib.baseboard_fab2(sch_1):pwrgd_p5v_r';
NODE_NAME     R2P20 1
 '@BASEBOARD_FAB2_LIB.BASEBOARD_FAB2(SCH_1):PAGE196_I65@MSTR_DISCRETE.RES(CHIPS)':
 'A': CDS_PINID='A';
NODE_NAME     R2P21 2
 '@BASEBOARD_FAB2_LIB.BASEBOARD_FAB2(SCH_1):PAGE196_I122@MSTR_DISCRETE.RES(CHIPS)':
 'B': CDS_PINID='B';
NODE_NAME     Q1P2 3
 '@BASEBOARD_FAB2_LIB.BASEBOARD_FAB2(SCH_1):PAGE196_I129@MSTR_DISCRETE.FET_N(CHIPS)':
 'DRN': CDS_PINID='DRN';
NET_NAME
'PWRGD_P5V_STBY'
 '@BASEBOARD_FAB2_LIB.BASEBOARD_FAB2(SCH_1):PWRGD_P5V_STBY':
 C_SIGNAL='@baseboard_fab2_lib.baseboard_fab2(sch_1):pwrgd_p5v_stby';
NODE_NAME     R8F1 1
 '@BASEBOARD_FAB2_LIB.BASEBOARD_FAB2(SCH_1):PAGE240_I111@MSTR_DISCRETE.RES(CHIPS)':
 'A': CDS_PINID='A';
NODE_NAME     C8E17 1
 '@BASEBOARD_FAB2_LIB.BASEBOARD_FAB2(SCH_1):PAGE240_I113@MSTR_DISCRETE.CAP(CHIPS)':
 'A': CDS_PINID='A';
NODE_NAME     R8F2 1
 '@BASEBOARD_FAB2_LIB.BASEBOARD_FAB2(SCH_1):PAGE240_I176@MSTR_DISCRETE.RES(CHIPS)':
 'A': CDS_PINID='A';
NODE_NAME     R7E15 2
 '@BASEBOARD_FAB2_LIB.BASEBOARD_FAB2(SCH_1):PAGE241_I89@MSTR_DISCRETE.RES(CHIPS)':
 'B': CDS_PINID='B';
NET_NAME
'PWRGD_P5V_STBY_R'
 '@BASEBOARD_FAB2_LIB.BASEBOARD_FAB2(SCH_1):PWRGD_P5V_STBY_R':
 C_SIGNAL='@baseboard_fab2_lib.baseboard_fab2(sch_1):pwrgd_p5v_stby_r';
NODE_NAME     R7E12 2
 '@BASEBOARD_FAB2_LIB.BASEBOARD_FAB2(SCH_1):PAGE241_I11@MSTR_DISCRETE.RES(CHIPS)':
 'B': CDS_PINID='B';
NODE_NAME     C7E10 1
 '@BASEBOARD_FAB2_LIB.BASEBOARD_FAB2(SCH_1):PAGE241_I14@MSTR_DISCRETE.CAP(CHIPS)':
 'A': CDS_PINID='A';
NODE_NAME     EU7E2 14
 '@BASEBOARD_FAB2_LIB.BASEBOARD_FAB2(SCH_1):PAGE241_I83@MSTR_VREG.TPS54821(CHIPS)':
 'PWRGD': CDS_PINID='PWRGD';
NODE_NAME     R7E15 1
 '@BASEBOARD_FAB2_LIB.BASEBOARD_FAB2(SCH_1):PAGE241_I89@MSTR_DISCRETE.RES(CHIPS)':
 'A': CDS_PINID='A';
NET_NAME
'PWRGD_PCH_PWROK'
 '@BASEBOARD_FAB2_LIB.BASEBOARD_FAB2(SCH_1):PWRGD_PCH_PWROK':
 C_SIGNAL='@baseboard_fab2_lib.baseboard_fab2(sch_1):pwrgd_pch_pwrok',
 PHYS_NET_NAME='H_CPU0_FAST_WAKE_LVT3_N';
NODE_NAME     U7C1 R17
 '@BASEBOARD_FAB2_LIB.BASEBOARD_FAB2(SCH_1):PAGE118_I73@MSTR_U_PROC.LBG_CORE_QAT_EXT_D(CHIPS)':
 'PCH_PWROK': CDS_PINID='PCH_PWROK';
NODE_NAME     R3N3 2
 '@BASEBOARD_FAB2_LIB.BASEBOARD_FAB2(SCH_1):PAGE133_I120@MSTR_DISCRETE.RES(CHIPS)':
 'B': CDS_PINID='B';
NODE_NAME     U8D7 C16
 '@BASEBOARD_FAB2_LIB.BASEBOARD_FAB2(SCH_1):PAGE191_I59@MSTR_MEMORY.LCMXO2_A(CHIPS)':
 'PR2C': CDS_PINID='PR2C';
NODE_NAME     U25W4 K19
 '@BASEBOARD_FAB2_LIB.BASEBOARD_FAB2(SCH_1):PAGE144_I95@W_HDL.AST2520A1-GP-GP(CHIPS)':
 'GPIOB0': CDS_PINID='GPIOB0';
NET_NAME
'PWRGD_PVCCIN_CPU0'
 '@BASEBOARD_FAB2_LIB.BASEBOARD_FAB2(SCH_1):PWRGD_PVCCIN_CPU0':
 C_SIGNAL='@baseboard_fab2_lib.baseboard_fab2(sch_1):pwrgd_pvccin_cpu0';
NODE_NAME     U1L1 13
 '@BASEBOARD_FAB2_LIB.BASEBOARD_FAB2(SCH_1):PAGE112_I108@MSTR_TTL.TTL3126(CHIPS)'(0):
 'OE'<0>: CDS_PINID='OE(0)';
NODE_NAME     U1L1 10
 '@BASEBOARD_FAB2_LIB.BASEBOARD_FAB2(SCH_1):PAGE112_I108@MSTR_TTL.TTL3126(CHIPS)'(1):
 'OE'<1>: CDS_PINID='OE(1)';
NODE_NAME     U1L1 4
 '@BASEBOARD_FAB2_LIB.BASEBOARD_FAB2(SCH_1):PAGE112_I108@MSTR_TTL.TTL3126(CHIPS)'(2):
 'OE'<2>: CDS_PINID='OE(2)';
NODE_NAME     U1L1 1
 '@BASEBOARD_FAB2_LIB.BASEBOARD_FAB2(SCH_1):PAGE112_I108@MSTR_TTL.TTL3126(CHIPS)'(3):
 'OE'<3>: CDS_PINID='OE(3)';
NODE_NAME     U1L5 13
 '@BASEBOARD_FAB2_LIB.BASEBOARD_FAB2(SCH_1):PAGE112_I109@MSTR_TTL.TTL3126(CHIPS)'(0):
 'OE'<0>: CDS_PINID='OE(0)';
NODE_NAME     U1L5 10
 '@BASEBOARD_FAB2_LIB.BASEBOARD_FAB2(SCH_1):PAGE112_I109@MSTR_TTL.TTL3126(CHIPS)'(1):
 'OE'<1>: CDS_PINID='OE(1)';
NODE_NAME     U1L5 4
 '@BASEBOARD_FAB2_LIB.BASEBOARD_FAB2(SCH_1):PAGE112_I109@MSTR_TTL.TTL3126(CHIPS)'(2):
 'OE'<2>: CDS_PINID='OE(2)';
NODE_NAME     U1L5 1
 '@BASEBOARD_FAB2_LIB.BASEBOARD_FAB2(SCH_1):PAGE112_I109@MSTR_TTL.TTL3126(CHIPS)'(3):
 'OE'<3>: CDS_PINID='OE(3)';
NODE_NAME     U8D7 K5
 '@BASEBOARD_FAB2_LIB.BASEBOARD_FAB2(SCH_1):PAGE190_I179@MSTR_MEMORY.LCMXO2_A(CHIPS)':
 'PL12C': CDS_PINID='PL12C';
NODE_NAME     R4D63 2
 '@BASEBOARD_FAB2_LIB.BASEBOARD_FAB2(SCH_1):PAGE201_I124@MSTR_DISCRETE.RES(CHIPS)':
 'B': CDS_PINID='B';
NET_NAME
'PWRGD_PVCCIN_CPU1'
 '@BASEBOARD_FAB2_LIB.BASEBOARD_FAB2(SCH_1):PWRGD_PVCCIN_CPU1':
 C_SIGNAL='@baseboard_fab2_lib.baseboard_fab2(sch_1):pwrgd_pvccin_cpu1';
NODE_NAME     U8D7 N1
 '@BASEBOARD_FAB2_LIB.BASEBOARD_FAB2(SCH_1):PAGE190_I179@MSTR_MEMORY.LCMXO2_A(CHIPS)':
 'PL13B': CDS_PINID='PL13B';
NODE_NAME     R1C30 2
 '@BASEBOARD_FAB2_LIB.BASEBOARD_FAB2(SCH_1):PAGE206_I113@MSTR_DISCRETE.RES(CHIPS)':
 'B': CDS_PINID='B';
NET_NAME
'PWRGD_PVCCIOMCP_CPU0'
 '@BASEBOARD_FAB2_LIB.BASEBOARD_FAB2(SCH_1):PWRGD_PVCCIOMCP_CPU0':
 C_SIGNAL='@baseboard_fab2_lib.baseboard_fab2(sch_1):pwrgd_pvcciomcp_cpu0';
NODE_NAME     U8D7 N6
 '@BASEBOARD_FAB2_LIB.BASEBOARD_FAB2(SCH_1):PAGE190_I179@MSTR_MEMORY.LCMXO2_A(CHIPS)':
 'PB8C': CDS_PINID='PB8C';
NODE_NAME     J6B1 B16
 '@BASEBOARD_FAB2_LIB.BASEBOARD_FAB2(SCH_1):PAGE194_I56@MSTR_SCONN.SCONN120_H61426002(CHIPS)':
 'IOB16': CDS_PINID='IOB16';
NET_NAME
'PWRGD_PVCCIOMCP_CPU1'
 '@BASEBOARD_FAB2_LIB.BASEBOARD_FAB2(SCH_1):PWRGD_PVCCIOMCP_CPU1':
 C_SIGNAL='@baseboard_fab2_lib.baseboard_fab2(sch_1):pwrgd_pvcciomcp_cpu1';
NODE_NAME     U8D7 T5
 '@BASEBOARD_FAB2_LIB.BASEBOARD_FAB2(SCH_1):PAGE190_I179@MSTR_MEMORY.LCMXO2_A(CHIPS)':
 'PB6A': CDS_PINID='PB6A';
NODE_NAME     J4B2 B16
 '@BASEBOARD_FAB2_LIB.BASEBOARD_FAB2(SCH_1):PAGE193_I46@MSTR_SCONN.SCONN120_H61426002(CHIPS)':
 'IOB16': CDS_PINID='IOB16';
NET_NAME
'PWRGD_PVCCIO_CPU0'
 '@BASEBOARD_FAB2_LIB.BASEBOARD_FAB2(SCH_1):PWRGD_PVCCIO_CPU0':
 C_SIGNAL='@baseboard_fab2_lib.baseboard_fab2(sch_1):pwrgd_pvccio_cpu0';
NODE_NAME     U7D1 1
 '@BASEBOARD_FAB2_LIB.BASEBOARD_FAB2(SCH_1):PAGE118_I142@MSTR_TTL.74CBTLV1G125(CHIPS)':
 'OE_N': CDS_PINID='OE_N';
NODE_NAME     U8D7 L8
 '@BASEBOARD_FAB2_LIB.BASEBOARD_FAB2(SCH_1):PAGE190_I179@MSTR_MEMORY.LCMXO2_A(CHIPS)':
 'PB11D': CDS_PINID='PB11D';
NODE_NAME     R3P20 2
 '@BASEBOARD_FAB2_LIB.BASEBOARD_FAB2(SCH_1):PAGE211_I58@MSTR_DISCRETE.RES(CHIPS)':
 'B': CDS_PINID='B';
NET_NAME
'PWRGD_PVCCIO_CPU0_R'
 '@BASEBOARD_FAB2_LIB.BASEBOARD_FAB2(SCH_1):PWRGD_PVCCIO_CPU0_R':
 C_SIGNAL='@baseboard_fab2_lib.baseboard_fab2(sch_1):pwrgd_pvccio_cpu0_r';
NODE_NAME     R3P25 2
 '@BASEBOARD_FAB2_LIB.BASEBOARD_FAB2(SCH_1):PAGE211_I56@MSTR_DISCRETE.RES(CHIPS)':
 'B': CDS_PINID='B';
NODE_NAME     R3P20 1
 '@BASEBOARD_FAB2_LIB.BASEBOARD_FAB2(SCH_1):PAGE211_I58@MSTR_DISCRETE.RES(CHIPS)':
 'A': CDS_PINID='A';
NODE_NAME     C3P6 1
 '@BASEBOARD_FAB2_LIB.BASEBOARD_FAB2(SCH_1):PAGE211_I71@MSTR_DISCRETE.CAP(CHIPS)':
 'A': CDS_PINID='A';
NODE_NAME     EU3P1 9
 '@BASEBOARD_FAB2_LIB.BASEBOARD_FAB2(SCH_1):PAGE211_I93@MSTR_CONTROLLER.PXE1110B(CHIPS)':
 'AVRRDY': CDS_PINID='AVRRDY';
NET_NAME
'PWRGD_PVCCIO_CPU1'
 '@BASEBOARD_FAB2_LIB.BASEBOARD_FAB2(SCH_1):PWRGD_PVCCIO_CPU1':
 C_SIGNAL='@baseboard_fab2_lib.baseboard_fab2(sch_1):pwrgd_pvccio_cpu1';
NODE_NAME     U8D7 L16
 '@BASEBOARD_FAB2_LIB.BASEBOARD_FAB2(SCH_1):PAGE191_I59@MSTR_MEMORY.LCMXO2_A(CHIPS)':
 'PR11A': CDS_PINID='PR11A';
NODE_NAME     R4D46 2
 '@BASEBOARD_FAB2_LIB.BASEBOARD_FAB2(SCH_1):PAGE213_I13@MSTR_DISCRETE.RES(CHIPS)':
 'B': CDS_PINID='B';
NET_NAME
'PWRGD_PVCCIO_CPU1_R'
 '@BASEBOARD_FAB2_LIB.BASEBOARD_FAB2(SCH_1):PWRGD_PVCCIO_CPU1_R':
 C_SIGNAL='@baseboard_fab2_lib.baseboard_fab2(sch_1):pwrgd_pvccio_cpu1_r';
NODE_NAME     R4D46 1
 '@BASEBOARD_FAB2_LIB.BASEBOARD_FAB2(SCH_1):PAGE213_I13@MSTR_DISCRETE.RES(CHIPS)':
 'A': CDS_PINID='A';
NODE_NAME     R4D42 2
 '@BASEBOARD_FAB2_LIB.BASEBOARD_FAB2(SCH_1):PAGE213_I15@MSTR_DISCRETE.RES(CHIPS)':
 'B': CDS_PINID='B';
NODE_NAME     C4D33 1
 '@BASEBOARD_FAB2_LIB.BASEBOARD_FAB2(SCH_1):PAGE213_I73@MSTR_DISCRETE.CAP(CHIPS)':
 'A': CDS_PINID='A';
NODE_NAME     EU4D5 9
 '@BASEBOARD_FAB2_LIB.BASEBOARD_FAB2(SCH_1):PAGE213_I96@MSTR_CONTROLLER.PXE1110B(CHIPS)':
 'AVRRDY': CDS_PINID='AVRRDY';
NET_NAME
'PWRGD_PVCCMCP_CPU0'
 '@BASEBOARD_FAB2_LIB.BASEBOARD_FAB2(SCH_1):PWRGD_PVCCMCP_CPU0':
 C_SIGNAL='@baseboard_fab2_lib.baseboard_fab2(sch_1):pwrgd_pvccmcp_cpu0';
NODE_NAME     U8D7 P5
 '@BASEBOARD_FAB2_LIB.BASEBOARD_FAB2(SCH_1):PAGE190_I179@MSTR_MEMORY.LCMXO2_A(CHIPS)':
 'PB5B': CDS_PINID='PB5B';
NODE_NAME     J6B1 D20
 '@BASEBOARD_FAB2_LIB.BASEBOARD_FAB2(SCH_1):PAGE194_I56@MSTR_SCONN.SCONN120_H61426002(CHIPS)':
 'IOD20': CDS_PINID='IOD20';
NET_NAME
'PWRGD_PVCCMCP_CPU1'
 '@BASEBOARD_FAB2_LIB.BASEBOARD_FAB2(SCH_1):PWRGD_PVCCMCP_CPU1':
 C_SIGNAL='@baseboard_fab2_lib.baseboard_fab2(sch_1):pwrgd_pvccmcp_cpu1';
NODE_NAME     U8D7 L4
 '@BASEBOARD_FAB2_LIB.BASEBOARD_FAB2(SCH_1):PAGE190_I179@MSTR_MEMORY.LCMXO2_A(CHIPS)':
 'PL12D': CDS_PINID='PL12D';
NODE_NAME     J4B2 D20
 '@BASEBOARD_FAB2_LIB.BASEBOARD_FAB2(SCH_1):PAGE193_I46@MSTR_SCONN.SCONN120_H61426002(CHIPS)':
 'IOD20': CDS_PINID='IOD20';
NET_NAME
'PWRGD_PVDDQ_ABC'
 '@BASEBOARD_FAB2_LIB.BASEBOARD_FAB2(SCH_1):PWRGD_PVDDQ_ABC':
 C_SIGNAL='@baseboard_fab2_lib.baseboard_fab2(sch_1):pwrgd_pvddq_abc';
NODE_NAME     R12W26 2
 '@BASEBOARD_FAB2_LIB.BASEBOARD_FAB2(SCH_1):PAGE215_I45@MSTR_DISCRETE.RES(CHIPS)':
 'B': CDS_PINID='B';
NODE_NAME     R12W27 2
 '@BASEBOARD_FAB2_LIB.BASEBOARD_FAB2(SCH_1):PAGE215_I54@MSTR_DISCRETE.RES(CHIPS)':
 'B': CDS_PINID='B';
NODE_NAME     R7F24 2
 '@BASEBOARD_FAB2_LIB.BASEBOARD_FAB2(SCH_1):PAGE215_I56@MSTR_DISCRETE.RES(CHIPS)':
 'B': CDS_PINID='B';
NODE_NAME     Q12W1 1
 '@BASEBOARD_FAB2_LIB.BASEBOARD_FAB2(SCH_1):PAGE197_I43@W_HDL.BSL308C-H6327-GP(CHIPS)':
 'GATE#1': CDS_PINID='\gate#1\';
NODE_NAME     R12W25 2
 '@BASEBOARD_FAB2_LIB.BASEBOARD_FAB2(SCH_1):PAGE215_I74@MSTR_DISCRETE.RES(CHIPS)':
 'B': CDS_PINID='B';
NODE_NAME     R7F36 2
 '@BASEBOARD_FAB2_LIB.BASEBOARD_FAB2(SCH_1):PAGE215_I75@MSTR_DISCRETE.RES(CHIPS)':
 'B': CDS_PINID='B';
NET_NAME
'PWRGD_PVDDQ_ABC_N'
 '@BASEBOARD_FAB2_LIB.BASEBOARD_FAB2(SCH_1):PWRGD_PVDDQ_ABC_N':
 C_SIGNAL='@baseboard_fab2_lib.baseboard_fab2(sch_1):pwrgd_pvddq_abc_n';
NODE_NAME     Q12W1 6
 '@BASEBOARD_FAB2_LIB.BASEBOARD_FAB2(SCH_1):PAGE197_I43@W_HDL.BSL308C-H6327-GP(CHIPS)':
 'DRAIN#6': CDS_PINID='\drain#6\';
NODE_NAME     Q12W1 3
 '@BASEBOARD_FAB2_LIB.BASEBOARD_FAB2(SCH_1):PAGE197_I43@W_HDL.BSL308C-H6327-GP(CHIPS)':
 'GATE#3': CDS_PINID='\gate#3\';
NODE_NAME     R12W4 2
 '@BASEBOARD_FAB2_LIB.BASEBOARD_FAB2(SCH_1):PAGE197_I45@MSTR_DISCRETE.RES(CHIPS)':
 'B': CDS_PINID='B';
NET_NAME
'PWRGD_PVDDQ_ABC_R'
 '@BASEBOARD_FAB2_LIB.BASEBOARD_FAB2(SCH_1):PWRGD_PVDDQ_ABC_R':
 C_SIGNAL='@baseboard_fab2_lib.baseboard_fab2(sch_1):pwrgd_pvddq_abc_r';
NODE_NAME     C7F14 1
 '@BASEBOARD_FAB2_LIB.BASEBOARD_FAB2(SCH_1):PAGE215_I44@MSTR_DISCRETE.CAP(CHIPS)':
 'A': CDS_PINID='A';
NODE_NAME     R7F22 2
 '@BASEBOARD_FAB2_LIB.BASEBOARD_FAB2(SCH_1):PAGE215_I51@MSTR_DISCRETE.RES(CHIPS)':
 'B': CDS_PINID='B';
NODE_NAME     R7F24 1
 '@BASEBOARD_FAB2_LIB.BASEBOARD_FAB2(SCH_1):PAGE215_I56@MSTR_DISCRETE.RES(CHIPS)':
 'A': CDS_PINID='A';
NODE_NAME     EU7G1 9
 '@BASEBOARD_FAB2_LIB.BASEBOARD_FAB2(SCH_1):PAGE215_I69@MSTR_CONTROLLER.PXM1310B(CHIPS)':
 'AVRRDY': CDS_PINID='AVRRDY';
NODE_NAME     R4G23 1
 '@BASEBOARD_FAB2_LIB.BASEBOARD_FAB2(SCH_1):PAGE221_I4@MSTR_DISCRETE.RES(CHIPS)':
 'A': CDS_PINID='A';
NET_NAME
'PWRGD_PVDDQ_DEF'
 '@BASEBOARD_FAB2_LIB.BASEBOARD_FAB2(SCH_1):PWRGD_PVDDQ_DEF':
 C_SIGNAL='@baseboard_fab2_lib.baseboard_fab2(sch_1):pwrgd_pvddq_def';
NODE_NAME     R3M3 2
 '@BASEBOARD_FAB2_LIB.BASEBOARD_FAB2(SCH_1):PAGE218_I60@MSTR_DISCRETE.RES(CHIPS)':
 'B': CDS_PINID='B';
NODE_NAME     R12W29 2
 '@BASEBOARD_FAB2_LIB.BASEBOARD_FAB2(SCH_1):PAGE218_I46@MSTR_DISCRETE.RES(CHIPS)':
 'B': CDS_PINID='B';
NODE_NAME     R12W30 2
 '@BASEBOARD_FAB2_LIB.BASEBOARD_FAB2(SCH_1):PAGE218_I55@MSTR_DISCRETE.RES(CHIPS)':
 'B': CDS_PINID='B';
NODE_NAME     Q12W2 1
 '@BASEBOARD_FAB2_LIB.BASEBOARD_FAB2(SCH_1):PAGE197_I19@W_HDL.BSL308C-H6327-GP(CHIPS)':
 'GATE#1': CDS_PINID='\gate#1\';
NODE_NAME     R12W28 2
 '@BASEBOARD_FAB2_LIB.BASEBOARD_FAB2(SCH_1):PAGE218_I75@MSTR_DISCRETE.RES(CHIPS)':
 'B': CDS_PINID='B';
NODE_NAME     R7A9 2
 '@BASEBOARD_FAB2_LIB.BASEBOARD_FAB2(SCH_1):PAGE218_I76@MSTR_DISCRETE.RES(CHIPS)':
 'B': CDS_PINID='B';
NET_NAME
'PWRGD_PVDDQ_DEF_N'
 '@BASEBOARD_FAB2_LIB.BASEBOARD_FAB2(SCH_1):PWRGD_PVDDQ_DEF_N':
 C_SIGNAL='@baseboard_fab2_lib.baseboard_fab2(sch_1):pwrgd_pvddq_def_n';
NODE_NAME     Q12W2 6
 '@BASEBOARD_FAB2_LIB.BASEBOARD_FAB2(SCH_1):PAGE197_I19@W_HDL.BSL308C-H6327-GP(CHIPS)':
 'DRAIN#6': CDS_PINID='\drain#6\';
NODE_NAME     Q12W2 3
 '@BASEBOARD_FAB2_LIB.BASEBOARD_FAB2(SCH_1):PAGE197_I19@W_HDL.BSL308C-H6327-GP(CHIPS)':
 'GATE#3': CDS_PINID='\gate#3\';
NODE_NAME     R12W9 2
 '@BASEBOARD_FAB2_LIB.BASEBOARD_FAB2(SCH_1):PAGE197_I21@MSTR_DISCRETE.RES(CHIPS)':
 'B': CDS_PINID='B';
NET_NAME
'PWRGD_PVDDQ_DEF_R'
 '@BASEBOARD_FAB2_LIB.BASEBOARD_FAB2(SCH_1):PWRGD_PVDDQ_DEF_R':
 C_SIGNAL='@baseboard_fab2_lib.baseboard_fab2(sch_1):pwrgd_pvddq_def_r';
NODE_NAME     R3M3 1
 '@BASEBOARD_FAB2_LIB.BASEBOARD_FAB2(SCH_1):PAGE218_I60@MSTR_DISCRETE.RES(CHIPS)':
 'A': CDS_PINID='A';
NODE_NAME     C7B3 1
 '@BASEBOARD_FAB2_LIB.BASEBOARD_FAB2(SCH_1):PAGE218_I41@MSTR_DISCRETE.CAP(CHIPS)':
 'A': CDS_PINID='A';
NODE_NAME     R7B5 2
 '@BASEBOARD_FAB2_LIB.BASEBOARD_FAB2(SCH_1):PAGE218_I58@MSTR_DISCRETE.RES(CHIPS)':
 'B': CDS_PINID='B';
NODE_NAME     EU7A5 9
 '@BASEBOARD_FAB2_LIB.BASEBOARD_FAB2(SCH_1):PAGE218_I69@MSTR_CONTROLLER.PXM1310B(CHIPS)':
 'AVRRDY': CDS_PINID='AVRRDY';
NODE_NAME     R4A2 1
 '@BASEBOARD_FAB2_LIB.BASEBOARD_FAB2(SCH_1):PAGE222_I4@MSTR_DISCRETE.RES(CHIPS)':
 'A': CDS_PINID='A';
NET_NAME
'PWRGD_PVDDQ_GHJ'
 '@BASEBOARD_FAB2_LIB.BASEBOARD_FAB2(SCH_1):PWRGD_PVDDQ_GHJ':
 C_SIGNAL='@baseboard_fab2_lib.baseboard_fab2(sch_1):pwrgd_pvddq_ghj';
NODE_NAME     R12W33 2
 '@BASEBOARD_FAB2_LIB.BASEBOARD_FAB2(SCH_1):PAGE223_I53@MSTR_DISCRETE.RES(CHIPS)':
 'B': CDS_PINID='B';
NODE_NAME     R12W32 2
 '@BASEBOARD_FAB2_LIB.BASEBOARD_FAB2(SCH_1):PAGE223_I45@MSTR_DISCRETE.RES(CHIPS)':
 'B': CDS_PINID='B';
NODE_NAME     R1G12 2
 '@BASEBOARD_FAB2_LIB.BASEBOARD_FAB2(SCH_1):PAGE223_I54@MSTR_DISCRETE.RES(CHIPS)':
 'B': CDS_PINID='B';
NODE_NAME     Q12W3 1
 '@BASEBOARD_FAB2_LIB.BASEBOARD_FAB2(SCH_1):PAGE197_I91@W_HDL.BSL308C-H6327-GP(CHIPS)':
 'GATE#1': CDS_PINID='\gate#1\';
NODE_NAME     R12W31 2
 '@BASEBOARD_FAB2_LIB.BASEBOARD_FAB2(SCH_1):PAGE223_I75@MSTR_DISCRETE.RES(CHIPS)':
 'B': CDS_PINID='B';
NODE_NAME     R1G6 2
 '@BASEBOARD_FAB2_LIB.BASEBOARD_FAB2(SCH_1):PAGE223_I76@MSTR_DISCRETE.RES(CHIPS)':
 'B': CDS_PINID='B';
NET_NAME
'PWRGD_PVDDQ_GHJ_N'
 '@BASEBOARD_FAB2_LIB.BASEBOARD_FAB2(SCH_1):PWRGD_PVDDQ_GHJ_N':
 C_SIGNAL='@baseboard_fab2_lib.baseboard_fab2(sch_1):pwrgd_pvddq_ghj_n';
NODE_NAME     R12W14 2
 '@BASEBOARD_FAB2_LIB.BASEBOARD_FAB2(SCH_1):PAGE197_I53@MSTR_DISCRETE.RES(CHIPS)':
 'B': CDS_PINID='B';
NODE_NAME     Q12W3 6
 '@BASEBOARD_FAB2_LIB.BASEBOARD_FAB2(SCH_1):PAGE197_I91@W_HDL.BSL308C-H6327-GP(CHIPS)':
 'DRAIN#6': CDS_PINID='\drain#6\';
NODE_NAME     Q12W3 3
 '@BASEBOARD_FAB2_LIB.BASEBOARD_FAB2(SCH_1):PAGE197_I91@W_HDL.BSL308C-H6327-GP(CHIPS)':
 'GATE#3': CDS_PINID='\gate#3\';
NET_NAME
'PWRGD_PVDDQ_GHJ_R'
 '@BASEBOARD_FAB2_LIB.BASEBOARD_FAB2(SCH_1):PWRGD_PVDDQ_GHJ_R':
 C_SIGNAL='@baseboard_fab2_lib.baseboard_fab2(sch_1):pwrgd_pvddq_ghj_r';
NODE_NAME     C1G21 1
 '@BASEBOARD_FAB2_LIB.BASEBOARD_FAB2(SCH_1):PAGE223_I40@MSTR_DISCRETE.CAP(CHIPS)':
 'A': CDS_PINID='A';
NODE_NAME     R1G16 2
 '@BASEBOARD_FAB2_LIB.BASEBOARD_FAB2(SCH_1):PAGE223_I48@MSTR_DISCRETE.RES(CHIPS)':
 'B': CDS_PINID='B';
NODE_NAME     R1G12 1
 '@BASEBOARD_FAB2_LIB.BASEBOARD_FAB2(SCH_1):PAGE223_I54@MSTR_DISCRETE.RES(CHIPS)':
 'A': CDS_PINID='A';
NODE_NAME     EU1G2 9
 '@BASEBOARD_FAB2_LIB.BASEBOARD_FAB2(SCH_1):PAGE223_I69@MSTR_CONTROLLER.PXM1310B(CHIPS)':
 'AVRRDY': CDS_PINID='AVRRDY';
NODE_NAME     R4G16 1
 '@BASEBOARD_FAB2_LIB.BASEBOARD_FAB2(SCH_1):PAGE229_I4@MSTR_DISCRETE.RES(CHIPS)':
 'A': CDS_PINID='A';
NET_NAME
'PWRGD_PVDDQ_KLM'
 '@BASEBOARD_FAB2_LIB.BASEBOARD_FAB2(SCH_1):PWRGD_PVDDQ_KLM':
 C_SIGNAL='@baseboard_fab2_lib.baseboard_fab2(sch_1):pwrgd_pvddq_klm';
NODE_NAME     R12W36 2
 '@BASEBOARD_FAB2_LIB.BASEBOARD_FAB2(SCH_1):PAGE226_I53@MSTR_DISCRETE.RES(CHIPS)':
 'B': CDS_PINID='B';
NODE_NAME     R12W35 2
 '@BASEBOARD_FAB2_LIB.BASEBOARD_FAB2(SCH_1):PAGE226_I46@MSTR_DISCRETE.RES(CHIPS)':
 'B': CDS_PINID='B';
NODE_NAME     R1B5 2
 '@BASEBOARD_FAB2_LIB.BASEBOARD_FAB2(SCH_1):PAGE226_I55@MSTR_DISCRETE.RES(CHIPS)':
 'B': CDS_PINID='B';
NODE_NAME     Q12W4 1
 '@BASEBOARD_FAB2_LIB.BASEBOARD_FAB2(SCH_1):PAGE197_I35@W_HDL.BSL308C-H6327-GP(CHIPS)':
 'GATE#1': CDS_PINID='\gate#1\';
NODE_NAME     R12W34 2
 '@BASEBOARD_FAB2_LIB.BASEBOARD_FAB2(SCH_1):PAGE226_I74@MSTR_DISCRETE.RES(CHIPS)':
 'B': CDS_PINID='B';
NODE_NAME     R1B13 2
 '@BASEBOARD_FAB2_LIB.BASEBOARD_FAB2(SCH_1):PAGE226_I75@MSTR_DISCRETE.RES(CHIPS)':
 'B': CDS_PINID='B';
NET_NAME
'PWRGD_PVDDQ_KLM_N'
 '@BASEBOARD_FAB2_LIB.BASEBOARD_FAB2(SCH_1):PWRGD_PVDDQ_KLM_N':
 C_SIGNAL='@baseboard_fab2_lib.baseboard_fab2(sch_1):pwrgd_pvddq_klm_n';
NODE_NAME     Q12W4 6
 '@BASEBOARD_FAB2_LIB.BASEBOARD_FAB2(SCH_1):PAGE197_I35@W_HDL.BSL308C-H6327-GP(CHIPS)':
 'DRAIN#6': CDS_PINID='\drain#6\';
NODE_NAME     Q12W4 3
 '@BASEBOARD_FAB2_LIB.BASEBOARD_FAB2(SCH_1):PAGE197_I35@W_HDL.BSL308C-H6327-GP(CHIPS)':
 'GATE#3': CDS_PINID='\gate#3\';
NODE_NAME     R12W19 2
 '@BASEBOARD_FAB2_LIB.BASEBOARD_FAB2(SCH_1):PAGE197_I37@MSTR_DISCRETE.RES(CHIPS)':
 'B': CDS_PINID='B';
NET_NAME
'PWRGD_PVDDQ_KLM_R'
 '@BASEBOARD_FAB2_LIB.BASEBOARD_FAB2(SCH_1):PWRGD_PVDDQ_KLM_R':
 C_SIGNAL='@baseboard_fab2_lib.baseboard_fab2(sch_1):pwrgd_pvddq_klm_r';
NODE_NAME     R1B2 2
 '@BASEBOARD_FAB2_LIB.BASEBOARD_FAB2(SCH_1):PAGE226_I50@MSTR_DISCRETE.RES(CHIPS)':
 'B': CDS_PINID='B';
NODE_NAME     C1B4 1
 '@BASEBOARD_FAB2_LIB.BASEBOARD_FAB2(SCH_1):PAGE226_I40@MSTR_DISCRETE.CAP(CHIPS)':
 'A': CDS_PINID='A';
NODE_NAME     R1B5 1
 '@BASEBOARD_FAB2_LIB.BASEBOARD_FAB2(SCH_1):PAGE226_I55@MSTR_DISCRETE.RES(CHIPS)':
 'A': CDS_PINID='A';
NODE_NAME     EU1B1 9
 '@BASEBOARD_FAB2_LIB.BASEBOARD_FAB2(SCH_1):PAGE226_I69@MSTR_CONTROLLER.PXM1310B(CHIPS)':
 'AVRRDY': CDS_PINID='AVRRDY';
NODE_NAME     R4A3 1
 '@BASEBOARD_FAB2_LIB.BASEBOARD_FAB2(SCH_1):PAGE230_I4@MSTR_DISCRETE.RES(CHIPS)':
 'A': CDS_PINID='A';
NET_NAME
'PWRGD_PVNN_P1V05_PCH'
 '@BASEBOARD_FAB2_LIB.BASEBOARD_FAB2(SCH_1):PWRGD_PVNN_P1V05_PCH':
 C_SIGNAL='@baseboard_fab2_lib.baseboard_fab2(sch_1):pwrgd_pvnn_p1v05_pch';
NODE_NAME     U8D7 P8
 '@BASEBOARD_FAB2_LIB.BASEBOARD_FAB2(SCH_1):PAGE190_I179@MSTR_MEMORY.LCMXO2_A(CHIPS)':
 'PB12A': CDS_PINID='PB12A';
NODE_NAME     R2L16 2
 '@BASEBOARD_FAB2_LIB.BASEBOARD_FAB2(SCH_1):PAGE235_I147@MSTR_DISCRETE.RES(CHIPS)':
 'B': CDS_PINID='B';
NET_NAME
'PWRGD_PVNN_PCH_R'
 '@BASEBOARD_FAB2_LIB.BASEBOARD_FAB2(SCH_1):PWRGD_PVNN_PCH_R':
 C_SIGNAL='@baseboard_fab2_lib.baseboard_fab2(sch_1):pwrgd_pvnn_pch_r';
NODE_NAME     R2L16 1
 '@BASEBOARD_FAB2_LIB.BASEBOARD_FAB2(SCH_1):PAGE235_I147@MSTR_DISCRETE.RES(CHIPS)':
 'A': CDS_PINID='A';
NODE_NAME     R8A6 2
 '@BASEBOARD_FAB2_LIB.BASEBOARD_FAB2(SCH_1):PAGE235_I149@MSTR_DISCRETE.RES(CHIPS)':
 'B': CDS_PINID='B';
NODE_NAME     C8A9 1
 '@BASEBOARD_FAB2_LIB.BASEBOARD_FAB2(SCH_1):PAGE235_I218@MSTR_DISCRETE.CAP(CHIPS)':
 'A': CDS_PINID='A';
NODE_NAME     EU8A1 9
 '@BASEBOARD_FAB2_LIB.BASEBOARD_FAB2(SCH_1):PAGE235_I229@MSTR_CONTROLLER.PXE1110B(CHIPS)':
 'AVRRDY': CDS_PINID='AVRRDY';
NET_NAME
'PWRGD_PVPP_ABC'
 '@BASEBOARD_FAB2_LIB.BASEBOARD_FAB2(SCH_1):PWRGD_PVPP_ABC':
 C_SIGNAL='@baseboard_fab2_lib.baseboard_fab2(sch_1):pwrgd_pvpp_abc';
NODE_NAME     J8B1 19
 '@BASEBOARD_FAB2_LIB.BASEBOARD_FAB2(SCH_1):PAGE91_I1@MSTR_SCONN.SCONN24_H46321001(CHIPS)':
 'IO19': CDS_PINID='IO19';
NODE_NAME     U8D7 N7
 '@BASEBOARD_FAB2_LIB.BASEBOARD_FAB2(SCH_1):PAGE190_I179@MSTR_MEMORY.LCMXO2_A(CHIPS)':
 'PB9D': CDS_PINID='PB9D';
NODE_NAME     R7F16 2
 '@BASEBOARD_FAB2_LIB.BASEBOARD_FAB2(SCH_1):PAGE231_I208@MSTR_DISCRETE.RES(CHIPS)':
 'B': CDS_PINID='B';
NET_NAME
'PWRGD_PVPP_ABC_R'
 '@BASEBOARD_FAB2_LIB.BASEBOARD_FAB2(SCH_1):PWRGD_PVPP_ABC_R':
 C_SIGNAL='@baseboard_fab2_lib.baseboard_fab2(sch_1):pwrgd_pvpp_abc_r';
NODE_NAME     C7F11 1
 '@BASEBOARD_FAB2_LIB.BASEBOARD_FAB2(SCH_1):PAGE231_I142@MSTR_DISCRETE.CAP(CHIPS)':
 'A': CDS_PINID='A';
NODE_NAME     R7F19 2
 '@BASEBOARD_FAB2_LIB.BASEBOARD_FAB2(SCH_1):PAGE231_I143@MSTR_DISCRETE.RES(CHIPS)':
 'B': CDS_PINID='B';
NODE_NAME     EU7F1 7
 '@BASEBOARD_FAB2_LIB.BASEBOARD_FAB2(SCH_1):PAGE231_I193@MSTR_VREG.NCP3232L(CHIPS)':
 'PG': CDS_PINID='PG';
NODE_NAME     R7F16 1
 '@BASEBOARD_FAB2_LIB.BASEBOARD_FAB2(SCH_1):PAGE231_I208@MSTR_DISCRETE.RES(CHIPS)':
 'A': CDS_PINID='A';
NET_NAME
'PWRGD_PVPP_DEF'
 '@BASEBOARD_FAB2_LIB.BASEBOARD_FAB2(SCH_1):PWRGD_PVPP_DEF':
 C_SIGNAL='@baseboard_fab2_lib.baseboard_fab2(sch_1):pwrgd_pvpp_def';
NODE_NAME     U8D7 M6
 '@BASEBOARD_FAB2_LIB.BASEBOARD_FAB2(SCH_1):PAGE190_I179@MSTR_MEMORY.LCMXO2_A(CHIPS)':
 'PB11C': CDS_PINID='PB11C';
NODE_NAME     R7B12 2
 '@BASEBOARD_FAB2_LIB.BASEBOARD_FAB2(SCH_1):PAGE232_I257@MSTR_DISCRETE.RES(CHIPS)':
 'B': CDS_PINID='B';
NET_NAME
'PWRGD_PVPP_DEF_R'
 '@BASEBOARD_FAB2_LIB.BASEBOARD_FAB2(SCH_1):PWRGD_PVPP_DEF_R':
 C_SIGNAL='@baseboard_fab2_lib.baseboard_fab2(sch_1):pwrgd_pvpp_def_r';
NODE_NAME     C7B12 1
 '@BASEBOARD_FAB2_LIB.BASEBOARD_FAB2(SCH_1):PAGE232_I209@MSTR_DISCRETE.CAP(CHIPS)':
 'A': CDS_PINID='A';
NODE_NAME     R7B17 2
 '@BASEBOARD_FAB2_LIB.BASEBOARD_FAB2(SCH_1):PAGE232_I210@MSTR_DISCRETE.RES(CHIPS)':
 'B': CDS_PINID='B';
NODE_NAME     EU7B1 7
 '@BASEBOARD_FAB2_LIB.BASEBOARD_FAB2(SCH_1):PAGE232_I214@MSTR_VREG.NCP3232L(CHIPS)':
 'PG': CDS_PINID='PG';
NODE_NAME     R7B12 1
 '@BASEBOARD_FAB2_LIB.BASEBOARD_FAB2(SCH_1):PAGE232_I257@MSTR_DISCRETE.RES(CHIPS)':
 'A': CDS_PINID='A';
NET_NAME
'PWRGD_PVPP_GHJ'
 '@BASEBOARD_FAB2_LIB.BASEBOARD_FAB2(SCH_1):PWRGD_PVPP_GHJ':
 C_SIGNAL='@baseboard_fab2_lib.baseboard_fab2(sch_1):pwrgd_pvpp_ghj';
NODE_NAME     U8D7 M2
 '@BASEBOARD_FAB2_LIB.BASEBOARD_FAB2(SCH_1):PAGE190_I179@MSTR_MEMORY.LCMXO2_A(CHIPS)':
 'PL14A': CDS_PINID='PL14A';
NODE_NAME     R4G12 2
 '@BASEBOARD_FAB2_LIB.BASEBOARD_FAB2(SCH_1):PAGE233_I247@MSTR_DISCRETE.RES(CHIPS)':
 'B': CDS_PINID='B';
NET_NAME
'PWRGD_PVPP_GHJ_R'
 '@BASEBOARD_FAB2_LIB.BASEBOARD_FAB2(SCH_1):PWRGD_PVPP_GHJ_R':
 C_SIGNAL='@baseboard_fab2_lib.baseboard_fab2(sch_1):pwrgd_pvpp_ghj_r';
NODE_NAME     R4G14 2
 '@BASEBOARD_FAB2_LIB.BASEBOARD_FAB2(SCH_1):PAGE233_I185@MSTR_DISCRETE.RES(CHIPS)':
 'B': CDS_PINID='B';
NODE_NAME     C4G9 1
 '@BASEBOARD_FAB2_LIB.BASEBOARD_FAB2(SCH_1):PAGE233_I201@MSTR_DISCRETE.CAP(CHIPS)':
 'A': CDS_PINID='A';
NODE_NAME     EU4G1 7
 '@BASEBOARD_FAB2_LIB.BASEBOARD_FAB2(SCH_1):PAGE233_I225@MSTR_VREG.NCP3232L(CHIPS)':
 'PG': CDS_PINID='PG';
NODE_NAME     R4G12 1
 '@BASEBOARD_FAB2_LIB.BASEBOARD_FAB2(SCH_1):PAGE233_I247@MSTR_DISCRETE.RES(CHIPS)':
 'A': CDS_PINID='A';
NET_NAME
'PWRGD_PVPP_KLM'
 '@BASEBOARD_FAB2_LIB.BASEBOARD_FAB2(SCH_1):PWRGD_PVPP_KLM':
 C_SIGNAL='@baseboard_fab2_lib.baseboard_fab2(sch_1):pwrgd_pvpp_klm';
NODE_NAME     U8D7 N2
 '@BASEBOARD_FAB2_LIB.BASEBOARD_FAB2(SCH_1):PAGE190_I179@MSTR_MEMORY.LCMXO2_A(CHIPS)':
 'PL13C': CDS_PINID='PL13C';
NODE_NAME     R4B7 2
 '@BASEBOARD_FAB2_LIB.BASEBOARD_FAB2(SCH_1):PAGE234_I201@MSTR_DISCRETE.RES(CHIPS)':
 'B': CDS_PINID='B';
NET_NAME
'PWRGD_PVPP_KLM_R'
 '@BASEBOARD_FAB2_LIB.BASEBOARD_FAB2(SCH_1):PWRGD_PVPP_KLM_R':
 C_SIGNAL='@baseboard_fab2_lib.baseboard_fab2(sch_1):pwrgd_pvpp_klm_r';
NODE_NAME     C4B8 1
 '@BASEBOARD_FAB2_LIB.BASEBOARD_FAB2(SCH_1):PAGE234_I139@MSTR_DISCRETE.CAP(CHIPS)':
 'A': CDS_PINID='A';
NODE_NAME     R4B10 2
 '@BASEBOARD_FAB2_LIB.BASEBOARD_FAB2(SCH_1):PAGE234_I143@MSTR_DISCRETE.RES(CHIPS)':
 'B': CDS_PINID='B';
NODE_NAME     EU4A3 7
 '@BASEBOARD_FAB2_LIB.BASEBOARD_FAB2(SCH_1):PAGE234_I184@MSTR_VREG.NCP3232L(CHIPS)':
 'PG': CDS_PINID='PG';
NODE_NAME     R4B7 1
 '@BASEBOARD_FAB2_LIB.BASEBOARD_FAB2(SCH_1):PAGE234_I201@MSTR_DISCRETE.RES(CHIPS)':
 'A': CDS_PINID='A';
NET_NAME
'PWRGD_PVSA_CPU0'
 '@BASEBOARD_FAB2_LIB.BASEBOARD_FAB2(SCH_1):PWRGD_PVSA_CPU0':
 C_SIGNAL='@baseboard_fab2_lib.baseboard_fab2(sch_1):pwrgd_pvsa_cpu0';
NODE_NAME     U8D7 L1
 '@BASEBOARD_FAB2_LIB.BASEBOARD_FAB2(SCH_1):PAGE190_I179@MSTR_MEMORY.LCMXO2_A(CHIPS)':
 'PL11A': CDS_PINID='PL11A';
NODE_NAME     R4D65 2
 '@BASEBOARD_FAB2_LIB.BASEBOARD_FAB2(SCH_1):PAGE201_I127@MSTR_DISCRETE.RES(CHIPS)':
 'B': CDS_PINID='B';
NET_NAME
'PWRGD_PVSA_CPU0_R'
 '@BASEBOARD_FAB2_LIB.BASEBOARD_FAB2(SCH_1):PWRGD_PVSA_CPU0_R':
 C_SIGNAL='@baseboard_fab2_lib.baseboard_fab2(sch_1):pwrgd_pvsa_cpu0_r';
NODE_NAME     R4E5 2
 '@BASEBOARD_FAB2_LIB.BASEBOARD_FAB2(SCH_1):PAGE201_I27@MSTR_DISCRETE.RES(CHIPS)':
 'B': CDS_PINID='B';
NODE_NAME     R4D65 1
 '@BASEBOARD_FAB2_LIB.BASEBOARD_FAB2(SCH_1):PAGE201_I127@MSTR_DISCRETE.RES(CHIPS)':
 'A': CDS_PINID='A';
NODE_NAME     EU4D4 15
 '@BASEBOARD_FAB2_LIB.BASEBOARD_FAB2(SCH_1):PAGE201_I155@MSTR_CONTROLLER.PXE1610B(CHIPS)':
 'MP0': CDS_PINID='MP0';
NET_NAME
'PWRGD_PVSA_CPU1'
 '@BASEBOARD_FAB2_LIB.BASEBOARD_FAB2(SCH_1):PWRGD_PVSA_CPU1':
 C_SIGNAL='@baseboard_fab2_lib.baseboard_fab2(sch_1):pwrgd_pvsa_cpu1';
NODE_NAME     U8D7 T4
 '@BASEBOARD_FAB2_LIB.BASEBOARD_FAB2(SCH_1):PAGE190_I179@MSTR_MEMORY.LCMXO2_A(CHIPS)':
 'PB3B': CDS_PINID='PB3B';
NODE_NAME     R1D1 2
 '@BASEBOARD_FAB2_LIB.BASEBOARD_FAB2(SCH_1):PAGE206_I116@MSTR_DISCRETE.RES(CHIPS)':
 'B': CDS_PINID='B';
NET_NAME
'PWRGD_PVSA_CPU1_R'
 '@BASEBOARD_FAB2_LIB.BASEBOARD_FAB2(SCH_1):PWRGD_PVSA_CPU1_R':
 C_SIGNAL='@baseboard_fab2_lib.baseboard_fab2(sch_1):pwrgd_pvsa_cpu1_r';
NODE_NAME     R1D8 2
 '@BASEBOARD_FAB2_LIB.BASEBOARD_FAB2(SCH_1):PAGE206_I36@MSTR_DISCRETE.RES(CHIPS)':
 'B': CDS_PINID='B';
NODE_NAME     R1D1 1
 '@BASEBOARD_FAB2_LIB.BASEBOARD_FAB2(SCH_1):PAGE206_I116@MSTR_DISCRETE.RES(CHIPS)':
 'A': CDS_PINID='A';
NODE_NAME     EU1C2 15
 '@BASEBOARD_FAB2_LIB.BASEBOARD_FAB2(SCH_1):PAGE206_I130@MSTR_CONTROLLER.PXE1610B(CHIPS)':
 'MP0': CDS_PINID='MP0';
NET_NAME
'PWRGD_PVTT_ABC_CPU0_R'
 '@BASEBOARD_FAB2_LIB.BASEBOARD_FAB2(SCH_1):PWRGD_PVTT_ABC_CPU0_R':
 C_SIGNAL='@baseboard_fab2_lib.baseboard_fab2(sch_1):pwrgd_pvtt_abc_cpu0_r';
NODE_NAME     R4G18 2
 '@BASEBOARD_FAB2_LIB.BASEBOARD_FAB2(SCH_1):PAGE221_I25@MSTR_DISCRETE.RES(CHIPS)':
 'B': CDS_PINID='B';
NODE_NAME     C4G14 1
 '@BASEBOARD_FAB2_LIB.BASEBOARD_FAB2(SCH_1):PAGE221_I30@MSTR_DISCRETE.CAP(CHIPS)':
 'A': CDS_PINID='A';
NODE_NAME     R4G19 1
 '@BASEBOARD_FAB2_LIB.BASEBOARD_FAB2(SCH_1):PAGE221_I33@MSTR_DISCRETE.RES(CHIPS)':
 'A': CDS_PINID='A';
NODE_NAME     EU4G3 5
 '@BASEBOARD_FAB2_LIB.BASEBOARD_FAB2(SCH_1):PAGE221_I15@MSTR_VREG.MIC5166(CHIPS)':
 'PG': CDS_PINID='PG';
NET_NAME
'PWRGD_PVTT_CPU0'
 '@BASEBOARD_FAB2_LIB.BASEBOARD_FAB2(SCH_1):PWRGD_PVTT_CPU0':
 C_SIGNAL='@baseboard_fab2_lib.baseboard_fab2(sch_1):pwrgd_pvtt_cpu0';
NODE_NAME     U8D7 B4
 '@BASEBOARD_FAB2_LIB.BASEBOARD_FAB2(SCH_1):PAGE191_I59@MSTR_MEMORY.LCMXO2_A(CHIPS)':
 'PT11D': CDS_PINID='PT11D';
NODE_NAME     R4G19 2
 '@BASEBOARD_FAB2_LIB.BASEBOARD_FAB2(SCH_1):PAGE221_I33@MSTR_DISCRETE.RES(CHIPS)':
 'B': CDS_PINID='B';
NODE_NAME     R4A6 2
 '@BASEBOARD_FAB2_LIB.BASEBOARD_FAB2(SCH_1):PAGE222_I31@MSTR_DISCRETE.RES(CHIPS)':
 'B': CDS_PINID='B';
NET_NAME
'PWRGD_PVTT_CPU1'
 '@BASEBOARD_FAB2_LIB.BASEBOARD_FAB2(SCH_1):PWRGD_PVTT_CPU1':
 C_SIGNAL='@baseboard_fab2_lib.baseboard_fab2(sch_1):pwrgd_pvtt_cpu1';
NODE_NAME     U8D7 R7
 '@BASEBOARD_FAB2_LIB.BASEBOARD_FAB2(SCH_1):PAGE190_I179@MSTR_MEMORY.LCMXO2_A(CHIPS)':
 'PB9A': CDS_PINID='PB9A';
NODE_NAME     R4G15 2
 '@BASEBOARD_FAB2_LIB.BASEBOARD_FAB2(SCH_1):PAGE229_I32@MSTR_DISCRETE.RES(CHIPS)':
 'B': CDS_PINID='B';
NODE_NAME     R4A4 2
 '@BASEBOARD_FAB2_LIB.BASEBOARD_FAB2(SCH_1):PAGE230_I32@MSTR_DISCRETE.RES(CHIPS)':
 'B': CDS_PINID='B';
NET_NAME
'PWRGD_PVTT_DEF_CPU0_R'
 '@BASEBOARD_FAB2_LIB.BASEBOARD_FAB2(SCH_1):PWRGD_PVTT_DEF_CPU0_R':
 C_SIGNAL='@baseboard_fab2_lib.baseboard_fab2(sch_1):pwrgd_pvtt_def_cpu0_r';
NODE_NAME     EU4A1 5
 '@BASEBOARD_FAB2_LIB.BASEBOARD_FAB2(SCH_1):PAGE222_I13@MSTR_VREG.MIC5166(CHIPS)':
 'PG': CDS_PINID='PG';
NODE_NAME     C4A12 1
 '@BASEBOARD_FAB2_LIB.BASEBOARD_FAB2(SCH_1):PAGE222_I22@MSTR_DISCRETE.CAP(CHIPS)':
 'A': CDS_PINID='A';
NODE_NAME     R6L9 2
 '@BASEBOARD_FAB2_LIB.BASEBOARD_FAB2(SCH_1):PAGE222_I23@MSTR_DISCRETE.RES(CHIPS)':
 'B': CDS_PINID='B';
NODE_NAME     R4A6 1
 '@BASEBOARD_FAB2_LIB.BASEBOARD_FAB2(SCH_1):PAGE222_I31@MSTR_DISCRETE.RES(CHIPS)':
 'A': CDS_PINID='A';
NET_NAME
'PWRGD_PVTT_GHJ_CPU1_R'
 '@BASEBOARD_FAB2_LIB.BASEBOARD_FAB2(SCH_1):PWRGD_PVTT_GHJ_CPU1_R':
 C_SIGNAL='@baseboard_fab2_lib.baseboard_fab2(sch_1):pwrgd_pvtt_ghj_cpu1_r';
NODE_NAME     R4G15 1
 '@BASEBOARD_FAB2_LIB.BASEBOARD_FAB2(SCH_1):PAGE229_I32@MSTR_DISCRETE.RES(CHIPS)':
 'A': CDS_PINID='A';
NODE_NAME     C4G13 1
 '@BASEBOARD_FAB2_LIB.BASEBOARD_FAB2(SCH_1):PAGE229_I26@MSTR_DISCRETE.CAP(CHIPS)':
 'A': CDS_PINID='A';
NODE_NAME     EU4G2 5
 '@BASEBOARD_FAB2_LIB.BASEBOARD_FAB2(SCH_1):PAGE229_I37@MSTR_VREG.MIC5166(CHIPS)':
 'PG': CDS_PINID='PG';
NODE_NAME     R4G17 2
 '@BASEBOARD_FAB2_LIB.BASEBOARD_FAB2(SCH_1):PAGE229_I24@MSTR_DISCRETE.RES(CHIPS)':
 'B': CDS_PINID='B';
NET_NAME
'PWRGD_PVTT_KLM_CPU1_R'
 '@BASEBOARD_FAB2_LIB.BASEBOARD_FAB2(SCH_1):PWRGD_PVTT_KLM_CPU1_R':
 C_SIGNAL='@baseboard_fab2_lib.baseboard_fab2(sch_1):pwrgd_pvtt_klm_cpu1_r';
NODE_NAME     C4A3 1
 '@BASEBOARD_FAB2_LIB.BASEBOARD_FAB2(SCH_1):PAGE230_I23@MSTR_DISCRETE.CAP(CHIPS)':
 'A': CDS_PINID='A';
NODE_NAME     R4A4 1
 '@BASEBOARD_FAB2_LIB.BASEBOARD_FAB2(SCH_1):PAGE230_I32@MSTR_DISCRETE.RES(CHIPS)':
 'A': CDS_PINID='A';
NODE_NAME     R4A5 2
 '@BASEBOARD_FAB2_LIB.BASEBOARD_FAB2(SCH_1):PAGE230_I21@MSTR_DISCRETE.RES(CHIPS)':
 'B': CDS_PINID='B';
NODE_NAME     EU4A2 5
 '@BASEBOARD_FAB2_LIB.BASEBOARD_FAB2(SCH_1):PAGE230_I37@MSTR_VREG.MIC5166(CHIPS)':
 'PG': CDS_PINID='PG';
NET_NAME
'PWRGD_SYS_PWROK'
 '@BASEBOARD_FAB2_LIB.BASEBOARD_FAB2(SCH_1):PWRGD_SYS_PWROK':
 C_SIGNAL='@baseboard_fab2_lib.baseboard_fab2(sch_1):pwrgd_sys_pwrok';
NODE_NAME     U7C1 BY19
 '@BASEBOARD_FAB2_LIB.BASEBOARD_FAB2(SCH_1):PAGE118_I73@MSTR_U_PROC.LBG_CORE_QAT_EXT_D(CHIPS)':
 'SYS_PWROK': CDS_PINID='SYS_PWROK';
NODE_NAME     R2N12 2
 '@BASEBOARD_FAB2_LIB.BASEBOARD_FAB2(SCH_1):PAGE133_I122@MSTR_DISCRETE.RES(CHIPS)':
 'B': CDS_PINID='B';
NODE_NAME     U8D7 D14
 '@BASEBOARD_FAB2_LIB.BASEBOARD_FAB2(SCH_1):PAGE191_I59@MSTR_MEMORY.LCMXO2_A(CHIPS)':
 'PR1A': CDS_PINID='PR1A';
NODE_NAME     U25W4 H22
 '@BASEBOARD_FAB2_LIB.BASEBOARD_FAB2(SCH_1):PAGE144_I95@W_HDL.AST2520A1-GP-GP(CHIPS)':
 'GPIOB6_LPCPME#': CDS_PINID='\gpiob6_lpcpme#\';
NODE_NAME     U6W1 15
 '@BASEBOARD_FAB2_LIB.BASEBOARD_FAB2(SCH_1):PAGE247_I120@W_HDL.TCA9555PWR-GP(CHIPS)':
 'P12': CDS_PINID='P12';
NODE_NAME     R25W182 2
 '@BASEBOARD_FAB2_LIB.BASEBOARD_FAB2(SCH_1):PAGE144_I151@MSTR_DISCRETE.RES(CHIPS)':
 'B': CDS_PINID='B';
NET_NAME
'Q25W1_GATE'
 '@BASEBOARD_FAB2_LIB.BASEBOARD_FAB2(SCH_1):Q25W1_GATE':
 C_SIGNAL='@baseboard_fab2_lib.baseboard_fab2(sch_1):q25w1_gate';
NODE_NAME     R25W131 2
 '@BASEBOARD_FAB2_LIB.BASEBOARD_FAB2(SCH_1):PAGE255_I30@MSTR_DISCRETE.RES(CHIPS)':
 'B': CDS_PINID='B';
NODE_NAME     Q25W4 2
 '@BASEBOARD_FAB2_LIB.BASEBOARD_FAB2(SCH_1):PAGE255_I95@MSTR_DISCRETE.FET_N_DUAL(CHIPS)':
 'GATE'<0>: CDS_PINID='GATE(0)';
NET_NAME
'Q25W2_GATE'
 '@BASEBOARD_FAB2_LIB.BASEBOARD_FAB2(SCH_1):Q25W2_GATE':
 C_SIGNAL='@baseboard_fab2_lib.baseboard_fab2(sch_1):q25w2_gate';
NODE_NAME     R25W134 2
 '@BASEBOARD_FAB2_LIB.BASEBOARD_FAB2(SCH_1):PAGE255_I43@MSTR_DISCRETE.RES(CHIPS)':
 'B': CDS_PINID='B';
NODE_NAME     Q25W4 5
 '@BASEBOARD_FAB2_LIB.BASEBOARD_FAB2(SCH_1):PAGE255_I96@MSTR_DISCRETE.FET_N_DUAL(CHIPS)':
 'GATE'<0>: CDS_PINID='GATE(0)';
NET_NAME
'RMII_BMC_OCP_CRSDV'
 '@BASEBOARD_FAB2_LIB.BASEBOARD_FAB2(SCH_1):RMII_BMC_OCP_CRSDV':
 C_SIGNAL='@baseboard_fab2_lib.baseboard_fab2(sch_1):rmii_bmc_ocp_crsdv';
NODE_NAME     R1M15 1
 '@BASEBOARD_FAB2_LIB.BASEBOARD_FAB2(SCH_1):PAGE186_I339@MSTR_DISCRETE.RES(CHIPS)':
 'A': CDS_PINID='A';
NODE_NAME     U25W4 C5
 '@BASEBOARD_FAB2_LIB.BASEBOARD_FAB2(SCH_1):PAGE147_I106@W_HDL.AST2520A1-GP-GP(CHIPS)':
 'RGMII1RXD2_RMII1CRSDV_GPIOV0': CDS_PINID='RGMII1RXD2_RMII1CRSDV_GPIOV0';
NET_NAME
'RMII_BMC_OCP_CRSDV_R'
 '@BASEBOARD_FAB2_LIB.BASEBOARD_FAB2(SCH_1):RMII_BMC_OCP_CRSDV_R':
 C_SIGNAL='@baseboard_fab2_lib.baseboard_fab2(sch_1):rmii_bmc_ocp_crsdv_r';
NODE_NAME     J9B3 27
 '@BASEBOARD_FAB2_LIB.BASEBOARD_FAB2(SCH_1):PAGE186_I336@MSTR_SCONN.SCONN120_A28699018(CHIPS)':
 'IO27': CDS_PINID='IO27';
NODE_NAME     R1M15 2
 '@BASEBOARD_FAB2_LIB.BASEBOARD_FAB2(SCH_1):PAGE186_I339@MSTR_DISCRETE.RES(CHIPS)':
 'B': CDS_PINID='B';
NET_NAME
'RMII_BMC_OCP_RXD0'
 '@BASEBOARD_FAB2_LIB.BASEBOARD_FAB2(SCH_1):RMII_BMC_OCP_RXD0':
 C_SIGNAL='@baseboard_fab2_lib.baseboard_fab2(sch_1):rmii_bmc_ocp_rxd0';
NODE_NAME     R1M17 1
 '@BASEBOARD_FAB2_LIB.BASEBOARD_FAB2(SCH_1):PAGE186_I338@MSTR_DISCRETE.RES(CHIPS)':
 'A': CDS_PINID='A';
NODE_NAME     U25W4 A3
 '@BASEBOARD_FAB2_LIB.BASEBOARD_FAB2(SCH_1):PAGE147_I106@W_HDL.AST2520A1-GP-GP(CHIPS)':
 'RGMII1RXD0_RMII1RXD0_GPIOU6': CDS_PINID='RGMII1RXD0_RMII1RXD0_GPIOU6';
NET_NAME
'RMII_BMC_OCP_RXD0_R'
 '@BASEBOARD_FAB2_LIB.BASEBOARD_FAB2(SCH_1):RMII_BMC_OCP_RXD0_R':
 C_SIGNAL='@baseboard_fab2_lib.baseboard_fab2(sch_1):rmii_bmc_ocp_rxd0_r';
NODE_NAME     J9B3 43
 '@BASEBOARD_FAB2_LIB.BASEBOARD_FAB2(SCH_1):PAGE186_I336@MSTR_SCONN.SCONN120_A28699018(CHIPS)':
 'IO43': CDS_PINID='IO43';
NODE_NAME     R1M17 2
 '@BASEBOARD_FAB2_LIB.BASEBOARD_FAB2(SCH_1):PAGE186_I338@MSTR_DISCRETE.RES(CHIPS)':
 'B': CDS_PINID='B';
NET_NAME
'RMII_BMC_OCP_RXD1'
 '@BASEBOARD_FAB2_LIB.BASEBOARD_FAB2(SCH_1):RMII_BMC_OCP_RXD1':
 C_SIGNAL='@baseboard_fab2_lib.baseboard_fab2(sch_1):rmii_bmc_ocp_rxd1';
NODE_NAME     R1M16 1
 '@BASEBOARD_FAB2_LIB.BASEBOARD_FAB2(SCH_1):PAGE186_I337@MSTR_DISCRETE.RES(CHIPS)':
 'A': CDS_PINID='A';
NODE_NAME     U25W4 D6
 '@BASEBOARD_FAB2_LIB.BASEBOARD_FAB2(SCH_1):PAGE147_I106@W_HDL.AST2520A1-GP-GP(CHIPS)':
 'RGMII1RXD1_RMII1RXD1_GPIOU7': CDS_PINID='RGMII1RXD1_RMII1RXD1_GPIOU7';
NET_NAME
'RMII_BMC_OCP_RXD1_R'
 '@BASEBOARD_FAB2_LIB.BASEBOARD_FAB2(SCH_1):RMII_BMC_OCP_RXD1_R':
 C_SIGNAL='@baseboard_fab2_lib.baseboard_fab2(sch_1):rmii_bmc_ocp_rxd1_r';
NODE_NAME     J9B3 45
 '@BASEBOARD_FAB2_LIB.BASEBOARD_FAB2(SCH_1):PAGE186_I336@MSTR_SCONN.SCONN120_A28699018(CHIPS)':
 'IO45': CDS_PINID='IO45';
NODE_NAME     R1M16 2
 '@BASEBOARD_FAB2_LIB.BASEBOARD_FAB2(SCH_1):PAGE186_I337@MSTR_DISCRETE.RES(CHIPS)':
 'B': CDS_PINID='B';
NET_NAME
'RMII_BMC_OCP_RXER'
 '@BASEBOARD_FAB2_LIB.BASEBOARD_FAB2(SCH_1):RMII_BMC_OCP_RXER':
 C_SIGNAL='@baseboard_fab2_lib.baseboard_fab2(sch_1):rmii_bmc_ocp_rxer';
NODE_NAME     R1M18 2
 '@BASEBOARD_FAB2_LIB.BASEBOARD_FAB2(SCH_1):PAGE186_I340@MSTR_DISCRETE.RES(CHIPS)':
 'B': CDS_PINID='B';
NODE_NAME     U25W4 C4
 '@BASEBOARD_FAB2_LIB.BASEBOARD_FAB2(SCH_1):PAGE147_I106@W_HDL.AST2520A1-GP-GP(CHIPS)':
 'RGMII1RXD3_RMII1RXER_GPIOV1': CDS_PINID='RGMII1RXD3_RMII1RXER_GPIOV1';
NET_NAME
'RMII_BMC_OCP_RXER_R'
 '@BASEBOARD_FAB2_LIB.BASEBOARD_FAB2(SCH_1):RMII_BMC_OCP_RXER_R':
 C_SIGNAL='@baseboard_fab2_lib.baseboard_fab2(sch_1):rmii_bmc_ocp_rxer_r';
NODE_NAME     J9B3 36
 '@BASEBOARD_FAB2_LIB.BASEBOARD_FAB2(SCH_1):PAGE186_I336@MSTR_SCONN.SCONN120_A28699018(CHIPS)':
 'IO36': CDS_PINID='IO36';
NODE_NAME     R1M18 1
 '@BASEBOARD_FAB2_LIB.BASEBOARD_FAB2(SCH_1):PAGE186_I340@MSTR_DISCRETE.RES(CHIPS)':
 'A': CDS_PINID='A';
NET_NAME
'RMII_BMC_OCP_TXD0'
 '@BASEBOARD_FAB2_LIB.BASEBOARD_FAB2(SCH_1):RMII_BMC_OCP_TXD0':
 C_SIGNAL='@baseboard_fab2_lib.baseboard_fab2(sch_1):rmii_bmc_ocp_txd0';
NODE_NAME     J9B3 40
 '@BASEBOARD_FAB2_LIB.BASEBOARD_FAB2(SCH_1):PAGE186_I336@MSTR_SCONN.SCONN120_A28699018(CHIPS)':
 'IO40': CDS_PINID='IO40';
NODE_NAME     R25W86 2
 '@BASEBOARD_FAB2_LIB.BASEBOARD_FAB2(SCH_1):PAGE147_I24@MSTR_DISCRETE.RES(CHIPS)':
 'B': CDS_PINID='B';
NET_NAME
'RMII_BMC_OCP_TXD0_R'
 '@BASEBOARD_FAB2_LIB.BASEBOARD_FAB2(SCH_1):RMII_BMC_OCP_TXD0_R':
 C_SIGNAL='@baseboard_fab2_lib.baseboard_fab2(sch_1):rmii_bmc_ocp_txd0_r';
NODE_NAME     R25W86 1
 '@BASEBOARD_FAB2_LIB.BASEBOARD_FAB2(SCH_1):PAGE147_I24@MSTR_DISCRETE.RES(CHIPS)':
 'A': CDS_PINID='A';
NODE_NAME     U25W4 F9
 '@BASEBOARD_FAB2_LIB.BASEBOARD_FAB2(SCH_1):PAGE147_I106@W_HDL.AST2520A1-GP-GP(CHIPS)':
 'RGMII1TXD0_RMII1TXD0_GPIOT2': CDS_PINID='RGMII1TXD0_RMII1TXD0_GPIOT2';
NODE_NAME     R25W107 2
 '@BASEBOARD_FAB2_LIB.BASEBOARD_FAB2(SCH_1):PAGE150_I190@MSTR_DISCRETE.RES(CHIPS)':
 'B': CDS_PINID='B';
NET_NAME
'RMII_BMC_OCP_TXD1'
 '@BASEBOARD_FAB2_LIB.BASEBOARD_FAB2(SCH_1):RMII_BMC_OCP_TXD1':
 C_SIGNAL='@baseboard_fab2_lib.baseboard_fab2(sch_1):rmii_bmc_ocp_txd1';
NODE_NAME     J9B3 42
 '@BASEBOARD_FAB2_LIB.BASEBOARD_FAB2(SCH_1):PAGE186_I336@MSTR_SCONN.SCONN120_A28699018(CHIPS)':
 'IO42': CDS_PINID='IO42';
NODE_NAME     R25W87 2
 '@BASEBOARD_FAB2_LIB.BASEBOARD_FAB2(SCH_1):PAGE147_I25@MSTR_DISCRETE.RES(CHIPS)':
 'B': CDS_PINID='B';
NET_NAME
'RMII_BMC_OCP_TXD1_R'
 '@BASEBOARD_FAB2_LIB.BASEBOARD_FAB2(SCH_1):RMII_BMC_OCP_TXD1_R':
 C_SIGNAL='@baseboard_fab2_lib.baseboard_fab2(sch_1):rmii_bmc_ocp_txd1_r';
NODE_NAME     R25W87 1
 '@BASEBOARD_FAB2_LIB.BASEBOARD_FAB2(SCH_1):PAGE147_I25@MSTR_DISCRETE.RES(CHIPS)':
 'A': CDS_PINID='A';
NODE_NAME     U25W4 A5
 '@BASEBOARD_FAB2_LIB.BASEBOARD_FAB2(SCH_1):PAGE147_I106@W_HDL.AST2520A1-GP-GP(CHIPS)':
 'RGMII1TXD1_RMII1TXD1_GPIOT3': CDS_PINID='RGMII1TXD1_RMII1TXD1_GPIOT3';
NODE_NAME     R25W108 2
 '@BASEBOARD_FAB2_LIB.BASEBOARD_FAB2(SCH_1):PAGE150_I191@MSTR_DISCRETE.RES(CHIPS)':
 'B': CDS_PINID='B';
NODE_NAME     R25W148 2
 '@BASEBOARD_FAB2_LIB.BASEBOARD_FAB2(SCH_1):PAGE150_I216@MSTR_DISCRETE.RES(CHIPS)':
 'B': CDS_PINID='B';
NET_NAME
'RMII_BMC_OCP_TXEN'
 '@BASEBOARD_FAB2_LIB.BASEBOARD_FAB2(SCH_1):RMII_BMC_OCP_TXEN':
 C_SIGNAL='@baseboard_fab2_lib.baseboard_fab2(sch_1):rmii_bmc_ocp_txen';
NODE_NAME     J9B3 31
 '@BASEBOARD_FAB2_LIB.BASEBOARD_FAB2(SCH_1):PAGE186_I336@MSTR_SCONN.SCONN120_A28699018(CHIPS)':
 'IO31': CDS_PINID='IO31';
NODE_NAME     R25W85 2
 '@BASEBOARD_FAB2_LIB.BASEBOARD_FAB2(SCH_1):PAGE147_I23@MSTR_DISCRETE.RES(CHIPS)':
 'B': CDS_PINID='B';
NODE_NAME     R25W106 2
 '@BASEBOARD_FAB2_LIB.BASEBOARD_FAB2(SCH_1):PAGE150_I175@MSTR_DISCRETE.RES(CHIPS)':
 'B': CDS_PINID='B';
NODE_NAME     R25W146 2
 '@BASEBOARD_FAB2_LIB.BASEBOARD_FAB2(SCH_1):PAGE150_I199@MSTR_DISCRETE.RES(CHIPS)':
 'B': CDS_PINID='B';
NET_NAME
'RMII_BMC_OCP_TXEN_R'
 '@BASEBOARD_FAB2_LIB.BASEBOARD_FAB2(SCH_1):RMII_BMC_OCP_TXEN_R':
 C_SIGNAL='@baseboard_fab2_lib.baseboard_fab2(sch_1):rmii_bmc_ocp_txen_r';
NODE_NAME     R25W85 1
 '@BASEBOARD_FAB2_LIB.BASEBOARD_FAB2(SCH_1):PAGE147_I23@MSTR_DISCRETE.RES(CHIPS)':
 'A': CDS_PINID='A';
NODE_NAME     U25W4 E9
 '@BASEBOARD_FAB2_LIB.BASEBOARD_FAB2(SCH_1):PAGE147_I106@W_HDL.AST2520A1-GP-GP(CHIPS)':
 'RGMII1TXCTL_RMII1TXEN_GPIOT1': CDS_PINID='RGMII1TXCTL_RMII1TXEN_GPIOT1';
NET_NAME
'RMII_BMC_PCH_SPRNGVLLE_CRSDV'
 '@BASEBOARD_FAB2_LIB.BASEBOARD_FAB2(SCH_1):RMII_BMC_PCH_SPRNGVLLE_CRSDV':
 C_SIGNAL='@baseboard_fab2_lib.baseboard_fab2(sch_1):rmii_bmc_pch_sprngvlle_crsd~
v';
NODE_NAME     R3P2 1
 '@BASEBOARD_FAB2_LIB.BASEBOARD_FAB2(SCH_1):PAGE121_I90@MSTR_DISCRETE.RES(CHIPS)':
 'A': CDS_PINID='A';
NODE_NAME     R1T1 1
 '@BASEBOARD_FAB2_LIB.BASEBOARD_FAB2(SCH_1):PAGE139_I214@MSTR_DISCRETE.RES(CHIPS)':
 'A': CDS_PINID='A';
NODE_NAME     R9F1 2
 '@BASEBOARD_FAB2_LIB.BASEBOARD_FAB2(SCH_1):PAGE139_I225@MSTR_DISCRETE.RES(CHIPS)':
 'B': CDS_PINID='B';
NODE_NAME     U25W4 D2
 '@BASEBOARD_FAB2_LIB.BASEBOARD_FAB2(SCH_1):PAGE147_I106@W_HDL.AST2520A1-GP-GP(CHIPS)':
 'RGMII2RXD2_RMII2CRSDV_GPIOV6': CDS_PINID='RGMII2RXD2_RMII2CRSDV_GPIOV6';
NET_NAME
'RMII_BMC_PCH_SPRNGVLLE_CRSDV_R'
 '@BASEBOARD_FAB2_LIB.BASEBOARD_FAB2(SCH_1):RMII_BMC_PCH_SPRNGVLLE_CRSDV_R':
 C_SIGNAL='@baseboard_fab2_lib.baseboard_fab2(sch_1):rmii_bmc_pch_sprngvlle_crsd~
v_r';
NODE_NAME     EU9E1 3
 '@BASEBOARD_FAB2_LIB.BASEBOARD_FAB2(SCH_1):PAGE139_I72@MSTR_INTEL.SPRINGVILLE(CHIPS)':
 'NC_SI_CRS_DV': CDS_PINID='NC_SI_CRS_DV';
NODE_NAME     R9F1 1
 '@BASEBOARD_FAB2_LIB.BASEBOARD_FAB2(SCH_1):PAGE139_I225@MSTR_DISCRETE.RES(CHIPS)':
 'A': CDS_PINID='A';
NET_NAME
'RMII_BMC_PCH_SPRNGVLLE_CRSDV_R1'
 '@BASEBOARD_FAB2_LIB.BASEBOARD_FAB2(SCH_1):RMII_BMC_PCH_SPRNGVLLE_CRSDV_R1':
 C_SIGNAL='@baseboard_fab2_lib.baseboard_fab2(sch_1):rmii_bmc_pch_sprngvlle_crsd~
v_r1';
NODE_NAME     U7C1 AN3
 '@BASEBOARD_FAB2_LIB.BASEBOARD_FAB2(SCH_1):PAGE121_I34@MSTR_U_PROC.LBG_CORE_QAT_EXT_D(CHIPS)':
 'GPP_K4_LAN_NCSI_CRS_DV': CDS_PINID='GPP_K4_LAN_NCSI_CRS_DV';
NODE_NAME     R3P2 2
 '@BASEBOARD_FAB2_LIB.BASEBOARD_FAB2(SCH_1):PAGE121_I90@MSTR_DISCRETE.RES(CHIPS)':
 'B': CDS_PINID='B';
NET_NAME
'RMII_BMC_PCH_SPRNGVLLE_RXER'
 '@BASEBOARD_FAB2_LIB.BASEBOARD_FAB2(SCH_1):RMII_BMC_PCH_SPRNGVLLE_RXER':
 C_SIGNAL='@baseboard_fab2_lib.baseboard_fab2(sch_1):rmii_bmc_pch_sprngvlle_rxer~
';
NODE_NAME     R7C14 1
 '@BASEBOARD_FAB2_LIB.BASEBOARD_FAB2(SCH_1):PAGE121_I98@MSTR_DISCRETE.RES(CHIPS)':
 'A': CDS_PINID='A';
NODE_NAME     R7D13 2
 '@BASEBOARD_FAB2_LIB.BASEBOARD_FAB2(SCH_1):PAGE125_I60@MSTR_DISCRETE.RES(CHIPS)':
 'B': CDS_PINID='B';
NODE_NAME     U25W4 E6
 '@BASEBOARD_FAB2_LIB.BASEBOARD_FAB2(SCH_1):PAGE147_I106@W_HDL.AST2520A1-GP-GP(CHIPS)':
 'RGMII2RXD3_RMII2RXER_GPIOV7': CDS_PINID='RGMII2RXD3_RMII2RXER_GPIOV7';
NET_NAME
'RMII_BMC_PCH_SPRNGVLLE_RXER_R'
 '@BASEBOARD_FAB2_LIB.BASEBOARD_FAB2(SCH_1):RMII_BMC_PCH_SPRNGVLLE_RXER_R':
 C_SIGNAL='@baseboard_fab2_lib.baseboard_fab2(sch_1):rmii_bmc_pch_sprngvlle_rxer~
_r';
NODE_NAME     U7C1 AH2
 '@BASEBOARD_FAB2_LIB.BASEBOARD_FAB2(SCH_1):PAGE121_I34@MSTR_U_PROC.LBG_CORE_QAT_EXT_D(CHIPS)':
 'GPP_K7': CDS_PINID='GPP_K7';
NODE_NAME     R7C14 2
 '@BASEBOARD_FAB2_LIB.BASEBOARD_FAB2(SCH_1):PAGE121_I98@MSTR_DISCRETE.RES(CHIPS)':
 'B': CDS_PINID='B';
NET_NAME
'RMII_BMC_PCH_SPRNGVLLE_TXD0'
 '@BASEBOARD_FAB2_LIB.BASEBOARD_FAB2(SCH_1):RMII_BMC_PCH_SPRNGVLLE_TXD0':
 C_SIGNAL='@baseboard_fab2_lib.baseboard_fab2(sch_1):rmii_bmc_pch_sprngvlle_txd0~
';
NODE_NAME     U7C1 AM2
 '@BASEBOARD_FAB2_LIB.BASEBOARD_FAB2(SCH_1):PAGE121_I34@MSTR_U_PROC.LBG_CORE_QAT_EXT_D(CHIPS)':
 'GPP_K1_LAN_NCSI_TXD0': CDS_PINID='GPP_K1_LAN_NCSI_TXD0';
NODE_NAME     EU9E1 9
 '@BASEBOARD_FAB2_LIB.BASEBOARD_FAB2(SCH_1):PAGE139_I72@MSTR_INTEL.SPRINGVILLE(CHIPS)':
 'NC_SI_TXD0': CDS_PINID='NC_SI_TXD0';
NODE_NAME     R25W89 2
 '@BASEBOARD_FAB2_LIB.BASEBOARD_FAB2(SCH_1):PAGE147_I22@MSTR_DISCRETE.RES(CHIPS)':
 'B': CDS_PINID='B';
NET_NAME
'RMII_BMC_PCH_SPRNGVLLE_TXD0_R'
 '@BASEBOARD_FAB2_LIB.BASEBOARD_FAB2(SCH_1):RMII_BMC_PCH_SPRNGVLLE_TXD0_R':
 C_SIGNAL='@baseboard_fab2_lib.baseboard_fab2(sch_1):rmii_bmc_pch_sprngvlle_txd0~
_r';
NODE_NAME     R25W89 1
 '@BASEBOARD_FAB2_LIB.BASEBOARD_FAB2(SCH_1):PAGE147_I22@MSTR_DISCRETE.RES(CHIPS)':
 'A': CDS_PINID='A';
NODE_NAME     U25W4 A2
 '@BASEBOARD_FAB2_LIB.BASEBOARD_FAB2(SCH_1):PAGE147_I106@W_HDL.AST2520A1-GP-GP(CHIPS)':
 'RGMII2TXD0_RMII2TXD0_GPIOU0': CDS_PINID='RGMII2TXD0_RMII2TXD0_GPIOU0';
NODE_NAME     R25W112 2
 '@BASEBOARD_FAB2_LIB.BASEBOARD_FAB2(SCH_1):PAGE150_I228@MSTR_DISCRETE.RES(CHIPS)':
 'B': CDS_PINID='B';
NODE_NAME     R25W150 2
 '@BASEBOARD_FAB2_LIB.BASEBOARD_FAB2(SCH_1):PAGE150_I229@MSTR_DISCRETE.RES(CHIPS)':
 'B': CDS_PINID='B';
NET_NAME
'RMII_BMC_PCH_SPRNGVLLE_TXD1'
 '@BASEBOARD_FAB2_LIB.BASEBOARD_FAB2(SCH_1):RMII_BMC_PCH_SPRNGVLLE_TXD1':
 C_SIGNAL='@baseboard_fab2_lib.baseboard_fab2(sch_1):rmii_bmc_pch_sprngvlle_txd1~
';
NODE_NAME     U7C1 AK2
 '@BASEBOARD_FAB2_LIB.BASEBOARD_FAB2(SCH_1):PAGE121_I34@MSTR_U_PROC.LBG_CORE_QAT_EXT_D(CHIPS)':
 'GPP_K2_LAN_NCSI_TXD1': CDS_PINID='GPP_K2_LAN_NCSI_TXD1';
NODE_NAME     EU9E1 8
 '@BASEBOARD_FAB2_LIB.BASEBOARD_FAB2(SCH_1):PAGE139_I72@MSTR_INTEL.SPRINGVILLE(CHIPS)':
 'NC_SI_TXD1': CDS_PINID='NC_SI_TXD1';
NODE_NAME     R25W90 2
 '@BASEBOARD_FAB2_LIB.BASEBOARD_FAB2(SCH_1):PAGE147_I21@MSTR_DISCRETE.RES(CHIPS)':
 'B': CDS_PINID='B';
NET_NAME
'RMII_BMC_PCH_SPRNGVLLE_TXD1_R'
 '@BASEBOARD_FAB2_LIB.BASEBOARD_FAB2(SCH_1):RMII_BMC_PCH_SPRNGVLLE_TXD1_R':
 C_SIGNAL='@baseboard_fab2_lib.baseboard_fab2(sch_1):rmii_bmc_pch_sprngvlle_txd1~
_r';
NODE_NAME     R25W90 1
 '@BASEBOARD_FAB2_LIB.BASEBOARD_FAB2(SCH_1):PAGE147_I21@MSTR_DISCRETE.RES(CHIPS)':
 'A': CDS_PINID='A';
NODE_NAME     U25W4 B3
 '@BASEBOARD_FAB2_LIB.BASEBOARD_FAB2(SCH_1):PAGE147_I106@W_HDL.AST2520A1-GP-GP(CHIPS)':
 'RGMII2TXD1_RMII2TXD1_GPIOU1': CDS_PINID='RGMII2TXD1_RMII2TXD1_GPIOU1';
NODE_NAME     R25W113 2
 '@BASEBOARD_FAB2_LIB.BASEBOARD_FAB2(SCH_1):PAGE150_I230@MSTR_DISCRETE.RES(CHIPS)':
 'B': CDS_PINID='B';
NODE_NAME     R25W151 2
 '@BASEBOARD_FAB2_LIB.BASEBOARD_FAB2(SCH_1):PAGE150_I232@MSTR_DISCRETE.RES(CHIPS)':
 'B': CDS_PINID='B';
NET_NAME
'RMII_BMC_PCH_SPRNGVLLE_TXEN'
 '@BASEBOARD_FAB2_LIB.BASEBOARD_FAB2(SCH_1):RMII_BMC_PCH_SPRNGVLLE_TXEN':
 C_SIGNAL='@baseboard_fab2_lib.baseboard_fab2(sch_1):rmii_bmc_pch_sprngvlle_txen~
';
NODE_NAME     U7C1 AL3
 '@BASEBOARD_FAB2_LIB.BASEBOARD_FAB2(SCH_1):PAGE121_I34@MSTR_U_PROC.LBG_CORE_QAT_EXT_D(CHIPS)':
 'GPP_K3_LAN_NCSI_TX_EN': CDS_PINID='GPP_K3_LAN_NCSI_TX_EN';
NODE_NAME     EU9E1 7
 '@BASEBOARD_FAB2_LIB.BASEBOARD_FAB2(SCH_1):PAGE139_I72@MSTR_INTEL.SPRINGVILLE(CHIPS)':
 'NC_SI_TX_EN': CDS_PINID='NC_SI_TX_EN';
NODE_NAME     R9E13 1
 '@BASEBOARD_FAB2_LIB.BASEBOARD_FAB2(SCH_1):PAGE139_I212@MSTR_DISCRETE.RES(CHIPS)':
 'A': CDS_PINID='A';
NODE_NAME     R25W88 2
 '@BASEBOARD_FAB2_LIB.BASEBOARD_FAB2(SCH_1):PAGE147_I8@MSTR_DISCRETE.RES(CHIPS)':
 'B': CDS_PINID='B';
NODE_NAME     R25W111 2
 '@BASEBOARD_FAB2_LIB.BASEBOARD_FAB2(SCH_1):PAGE150_I180@MSTR_DISCRETE.RES(CHIPS)':
 'B': CDS_PINID='B';
NET_NAME
'RMII_BMC_SPRNGVLLE_TXEN_R'
 '@BASEBOARD_FAB2_LIB.BASEBOARD_FAB2(SCH_1):RMII_BMC_SPRNGVLLE_TXEN_R':
 C_SIGNAL='@baseboard_fab2_lib.baseboard_fab2(sch_1):rmii_bmc_sprngvlle_txen_r';
NODE_NAME     R25W88 1
 '@BASEBOARD_FAB2_LIB.BASEBOARD_FAB2(SCH_1):PAGE147_I8@MSTR_DISCRETE.RES(CHIPS)':
 'A': CDS_PINID='A';
NODE_NAME     U25W4 B1
 '@BASEBOARD_FAB2_LIB.BASEBOARD_FAB2(SCH_1):PAGE147_I106@W_HDL.AST2520A1-GP-GP(CHIPS)':
 'RGMII2TXCTL_RMII2TXEN_GPIOT7': CDS_PINID='RGMII2TXCTL_RMII2TXEN_GPIOT7';
NET_NAME
'RMII_PCH_SPRNGVLLE_ARB_IN'
 '@BASEBOARD_FAB2_LIB.BASEBOARD_FAB2(SCH_1):RMII_PCH_SPRNGVLLE_ARB_IN':
 C_SIGNAL='@baseboard_fab2_lib.baseboard_fab2(sch_1):rmii_pch_sprngvlle_arb_in';
NODE_NAME     U7C1 AJ3
 '@BASEBOARD_FAB2_LIB.BASEBOARD_FAB2(SCH_1):PAGE121_I34@MSTR_U_PROC.LBG_CORE_QAT_EXT_D(CHIPS)':
 'GPP_K8_LAN_NCSI_ARB_IN': CDS_PINID='GPP_K8_LAN_NCSI_ARB_IN';
NODE_NAME     R9E16 2
 '@BASEBOARD_FAB2_LIB.BASEBOARD_FAB2(SCH_1):PAGE139_I235@MSTR_DISCRETE.RES(CHIPS)':
 'B': CDS_PINID='B';
NET_NAME
'RMII_PCH_SPRNGVLLE_ARB_IN_R'
 '@BASEBOARD_FAB2_LIB.BASEBOARD_FAB2(SCH_1):RMII_PCH_SPRNGVLLE_ARB_IN_R':
 C_SIGNAL='@baseboard_fab2_lib.baseboard_fab2(sch_1):rmii_pch_sprngvlle_arb_in_r~
';
NODE_NAME     EU9E1 44
 '@BASEBOARD_FAB2_LIB.BASEBOARD_FAB2(SCH_1):PAGE139_I72@MSTR_INTEL.SPRINGVILLE(CHIPS)':
 'NC_SI_ARB_OUT': CDS_PINID='NC_SI_ARB_OUT';
NODE_NAME     R9E16 1
 '@BASEBOARD_FAB2_LIB.BASEBOARD_FAB2(SCH_1):PAGE139_I235@MSTR_DISCRETE.RES(CHIPS)':
 'A': CDS_PINID='A';
NET_NAME
'RMII_PCH_SPRNGVLLE_ARB_OUT'
 '@BASEBOARD_FAB2_LIB.BASEBOARD_FAB2(SCH_1):RMII_PCH_SPRNGVLLE_ARB_OUT':
 C_SIGNAL='@baseboard_fab2_lib.baseboard_fab2(sch_1):rmii_pch_sprngvlle_arb_out';
NODE_NAME     R8D11 1
 '@BASEBOARD_FAB2_LIB.BASEBOARD_FAB2(SCH_1):PAGE121_I101@MSTR_DISCRETE.RES(CHIPS)':
 'A': CDS_PINID='A';
NODE_NAME     EU9E1 43
 '@BASEBOARD_FAB2_LIB.BASEBOARD_FAB2(SCH_1):PAGE139_I72@MSTR_INTEL.SPRINGVILLE(CHIPS)':
 'NC_SI_ARB_IN': CDS_PINID='NC_SI_ARB_IN';
NODE_NAME     R8D16 2
 '@BASEBOARD_FAB2_LIB.BASEBOARD_FAB2(SCH_1):PAGE125_I85@MSTR_DISCRETE.RES(CHIPS)':
 'B': CDS_PINID='B';
NODE_NAME     R7D1 1
 '@BASEBOARD_FAB2_LIB.BASEBOARD_FAB2(SCH_1):PAGE125_I86@MSTR_DISCRETE.RES(CHIPS)':
 'A': CDS_PINID='A';
NET_NAME
'RMII_PCH_SPRNGVLLE_ARB_OUT_R'
 '@BASEBOARD_FAB2_LIB.BASEBOARD_FAB2(SCH_1):RMII_PCH_SPRNGVLLE_ARB_OUT_R':
 C_SIGNAL='@baseboard_fab2_lib.baseboard_fab2(sch_1):rmii_pch_sprngvlle_arb_out_~
r';
NODE_NAME     U7C1 AK4
 '@BASEBOARD_FAB2_LIB.BASEBOARD_FAB2(SCH_1):PAGE121_I34@MSTR_U_PROC.LBG_CORE_QAT_EXT_D(CHIPS)':
 'GPP_K9_LAN_NCSI_ARB_OUT': CDS_PINID='GPP_K9_LAN_NCSI_ARB_OUT';
NODE_NAME     R8D11 2
 '@BASEBOARD_FAB2_LIB.BASEBOARD_FAB2(SCH_1):PAGE121_I101@MSTR_DISCRETE.RES(CHIPS)':
 'B': CDS_PINID='B';
NET_NAME
'RMII_SPRNGVLLE_BMC_PCH_RXD0'
 '@BASEBOARD_FAB2_LIB.BASEBOARD_FAB2(SCH_1):RMII_SPRNGVLLE_BMC_PCH_RXD0':
 C_SIGNAL='@baseboard_fab2_lib.baseboard_fab2(sch_1):rmii_sprngvlle_bmc_pch_rxd0~
';
NODE_NAME     R3P3 1
 '@BASEBOARD_FAB2_LIB.BASEBOARD_FAB2(SCH_1):PAGE121_I89@MSTR_DISCRETE.RES(CHIPS)':
 'A': CDS_PINID='A';
NODE_NAME     R9E17 2
 '@BASEBOARD_FAB2_LIB.BASEBOARD_FAB2(SCH_1):PAGE139_I229@MSTR_DISCRETE.RES(CHIPS)':
 'B': CDS_PINID='B';
NODE_NAME     R25W79 2
 '@BASEBOARD_FAB2_LIB.BASEBOARD_FAB2(SCH_1):PAGE147_I42@MSTR_DISCRETE.RES(CHIPS)':
 'B': CDS_PINID='B';
NODE_NAME     U25W4 C3
 '@BASEBOARD_FAB2_LIB.BASEBOARD_FAB2(SCH_1):PAGE147_I106@W_HDL.AST2520A1-GP-GP(CHIPS)':
 'RGMII2RXD0_RMII2RXD0_GPIOV4': CDS_PINID='RGMII2RXD0_RMII2RXD0_GPIOV4';
NET_NAME
'RMII_SPRNGVLLE_BMC_PCH_RXD0_R'
 '@BASEBOARD_FAB2_LIB.BASEBOARD_FAB2(SCH_1):RMII_SPRNGVLLE_BMC_PCH_RXD0_R':
 C_SIGNAL='@baseboard_fab2_lib.baseboard_fab2(sch_1):rmii_sprngvlle_bmc_pch_rxd0~
_r';
NODE_NAME     EU9E1 6
 '@BASEBOARD_FAB2_LIB.BASEBOARD_FAB2(SCH_1):PAGE139_I72@MSTR_INTEL.SPRINGVILLE(CHIPS)':
 'NC_SI_RXD0': CDS_PINID='NC_SI_RXD0';
NODE_NAME     R9E17 1
 '@BASEBOARD_FAB2_LIB.BASEBOARD_FAB2(SCH_1):PAGE139_I229@MSTR_DISCRETE.RES(CHIPS)':
 'A': CDS_PINID='A';
NET_NAME
'RMII_SPRNGVLLE_BMC_PCH_RXD0_R1'
 '@BASEBOARD_FAB2_LIB.BASEBOARD_FAB2(SCH_1):RMII_SPRNGVLLE_BMC_PCH_RXD0_R1':
 C_SIGNAL='@baseboard_fab2_lib.baseboard_fab2(sch_1):rmii_sprngvlle_bmc_pch_rxd0~
_r1';
NODE_NAME     U7C1 AL1
 '@BASEBOARD_FAB2_LIB.BASEBOARD_FAB2(SCH_1):PAGE121_I34@MSTR_U_PROC.LBG_CORE_QAT_EXT_D(CHIPS)':
 'GPP_K5_LAN_NCSI_RXD0': CDS_PINID='GPP_K5_LAN_NCSI_RXD0';
NODE_NAME     R3P3 2
 '@BASEBOARD_FAB2_LIB.BASEBOARD_FAB2(SCH_1):PAGE121_I89@MSTR_DISCRETE.RES(CHIPS)':
 'B': CDS_PINID='B';
NET_NAME
'RMII_SPRNGVLLE_BMC_PCH_RXD1'
 '@BASEBOARD_FAB2_LIB.BASEBOARD_FAB2(SCH_1):RMII_SPRNGVLLE_BMC_PCH_RXD1':
 C_SIGNAL='@baseboard_fab2_lib.baseboard_fab2(sch_1):rmii_sprngvlle_bmc_pch_rxd1~
';
NODE_NAME     R2P1 1
 '@BASEBOARD_FAB2_LIB.BASEBOARD_FAB2(SCH_1):PAGE121_I91@MSTR_DISCRETE.RES(CHIPS)':
 'A': CDS_PINID='A';
NODE_NAME     R9E19 2
 '@BASEBOARD_FAB2_LIB.BASEBOARD_FAB2(SCH_1):PAGE139_I228@MSTR_DISCRETE.RES(CHIPS)':
 'B': CDS_PINID='B';
NODE_NAME     R25W80 2
 '@BASEBOARD_FAB2_LIB.BASEBOARD_FAB2(SCH_1):PAGE147_I43@MSTR_DISCRETE.RES(CHIPS)':
 'B': CDS_PINID='B';
NODE_NAME     U25W4 D1
 '@BASEBOARD_FAB2_LIB.BASEBOARD_FAB2(SCH_1):PAGE147_I106@W_HDL.AST2520A1-GP-GP(CHIPS)':
 'RGMII2RXD1_RMII2RXD1_GPIOV5': CDS_PINID='RGMII2RXD1_RMII2RXD1_GPIOV5';
NET_NAME
'RMII_SPRNGVLLE_BMC_PCH_RXD1_R'
 '@BASEBOARD_FAB2_LIB.BASEBOARD_FAB2(SCH_1):RMII_SPRNGVLLE_BMC_PCH_RXD1_R':
 C_SIGNAL='@baseboard_fab2_lib.baseboard_fab2(sch_1):rmii_sprngvlle_bmc_pch_rxd1~
_r';
NODE_NAME     EU9E1 5
 '@BASEBOARD_FAB2_LIB.BASEBOARD_FAB2(SCH_1):PAGE139_I72@MSTR_INTEL.SPRINGVILLE(CHIPS)':
 'NC_SI_RXD1': CDS_PINID='NC_SI_RXD1';
NODE_NAME     R9E19 1
 '@BASEBOARD_FAB2_LIB.BASEBOARD_FAB2(SCH_1):PAGE139_I228@MSTR_DISCRETE.RES(CHIPS)':
 'A': CDS_PINID='A';
NET_NAME
'RMII_SPRNGVLLE_BMC_PCH_RXD1_R1'
 '@BASEBOARD_FAB2_LIB.BASEBOARD_FAB2(SCH_1):RMII_SPRNGVLLE_BMC_PCH_RXD1_R1':
 C_SIGNAL='@baseboard_fab2_lib.baseboard_fab2(sch_1):rmii_sprngvlle_bmc_pch_rxd1~
_r1';
NODE_NAME     U7C1 AN1
 '@BASEBOARD_FAB2_LIB.BASEBOARD_FAB2(SCH_1):PAGE121_I34@MSTR_U_PROC.LBG_CORE_QAT_EXT_D(CHIPS)':
 'GPP_K6_LAN_NCSI_RXD1': CDS_PINID='GPP_K6_LAN_NCSI_RXD1';
NODE_NAME     R2P1 2
 '@BASEBOARD_FAB2_LIB.BASEBOARD_FAB2(SCH_1):PAGE121_I91@MSTR_DISCRETE.RES(CHIPS)':
 'B': CDS_PINID='B';
NET_NAME
'RST_BMC_DDR3_BUF_IN_N'
 '@BASEBOARD_FAB2_LIB.BASEBOARD_FAB2(SCH_1):RST_BMC_DDR3_BUF_IN_N':
 C_SIGNAL='@baseboard_fab2_lib.baseboard_fab2(sch_1):rst_bmc_ddr3_buf_in_n';
NODE_NAME     R8D36 2
 '@BASEBOARD_FAB2_LIB.BASEBOARD_FAB2(SCH_1):PAGE157_I388@MSTR_DISCRETE.RES(CHIPS)':
 'B': CDS_PINID='B';
NODE_NAME     U9F3 2
 '@BASEBOARD_FAB2_LIB.BASEBOARD_FAB2(SCH_1):PAGE151_I56@MSTR_TTL.TTL1G07_A(CHIPS)':
 'A': CDS_PINID='A';
NET_NAME
'RST_BMC_DDR3_R_N'
 '@BASEBOARD_FAB2_LIB.BASEBOARD_FAB2(SCH_1):RST_BMC_DDR3_R_N':
 C_SIGNAL='@baseboard_fab2_lib.baseboard_fab2(sch_1):rst_bmc_ddr3_r_n';
NODE_NAME     R9F29 2
 '@BASEBOARD_FAB2_LIB.BASEBOARD_FAB2(SCH_1):PAGE151_I55@MSTR_DISCRETE.RES(CHIPS)':
 'B': CDS_PINID='B';
NODE_NAME     U9F3 4
 '@BASEBOARD_FAB2_LIB.BASEBOARD_FAB2(SCH_1):PAGE151_I56@MSTR_TTL.TTL1G07_A(CHIPS)':
 'Y': CDS_PINID='Y';
NODE_NAME     R9F34 1
 '@BASEBOARD_FAB2_LIB.BASEBOARD_FAB2(SCH_1):PAGE151_I209@MSTR_DISCRETE.RES(CHIPS)':
 'A': CDS_PINID='A';
NET_NAME
'RST_BMC_EXTRST_N'
 '@BASEBOARD_FAB2_LIB.BASEBOARD_FAB2(SCH_1):RST_BMC_EXTRST_N':
 C_SIGNAL='@baseboard_fab2_lib.baseboard_fab2(sch_1):rst_bmc_extrst_n';
NODE_NAME     U25W4 V18
 '@BASEBOARD_FAB2_LIB.BASEBOARD_FAB2(SCH_1):PAGE146_I105@W_HDL.AST2520A1-GP-GP(CHIPS)':
 'EXTRST#': CDS_PINID='\extrst#\';
NODE_NAME     R3W6 2
 '@BASEBOARD_FAB2_LIB.BASEBOARD_FAB2(SCH_1):PAGE249_I48@MSTR_DISCRETE.RES(CHIPS)':
 'B': CDS_PINID='B';
NODE_NAME     Q9W3 3
 '@BASEBOARD_FAB2_LIB.BASEBOARD_FAB2(SCH_1):PAGE249_I49@MSTR_DISCRETE.NPN(CHIPS)':
 'C': CDS_PINID='C';
NET_NAME
'RST_BMC_LVC3_N'
 '@BASEBOARD_FAB2_LIB.BASEBOARD_FAB2(SCH_1):RST_BMC_LVC3_N':
 C_SIGNAL='@baseboard_fab2_lib.baseboard_fab2(sch_1):rst_bmc_lvc3_n';
NODE_NAME     R25W74 2
 '@BASEBOARD_FAB2_LIB.BASEBOARD_FAB2(SCH_1):PAGE146_I70@MSTR_DISCRETE.RES(CHIPS)':
 'B': CDS_PINID='B';
NODE_NAME     U25W4 G22
 '@BASEBOARD_FAB2_LIB.BASEBOARD_FAB2(SCH_1):PAGE146_I105@W_HDL.AST2520A1-GP-GP(CHIPS)':
 'GPIOAC7_ESPIRST#_LPCRST#': CDS_PINID='\gpioac7_espirst#_lpcrst#\';
NET_NAME
'RST_BMC_PLTRST_BUF_N'
 '@BASEBOARD_FAB2_LIB.BASEBOARD_FAB2(SCH_1):RST_BMC_PLTRST_BUF_N':
 C_SIGNAL='@baseboard_fab2_lib.baseboard_fab2(sch_1):rst_bmc_pltrst_buf_n';
NODE_NAME     U25W4 V19
 '@BASEBOARD_FAB2_LIB.BASEBOARD_FAB2(SCH_1):PAGE146_I105@W_HDL.AST2520A1-GP-GP(CHIPS)':
 'GPIOR5_SPI2MISO': CDS_PINID='GPIOR5_SPI2MISO';
NODE_NAME     R25W184 1
 '@BASEBOARD_FAB2_LIB.BASEBOARD_FAB2(SCH_1):PAGE146_I166@MSTR_DISCRETE.RES(CHIPS)':
 'A': CDS_PINID='A';
NET_NAME
'RST_BMC_SRST_N'
 '@BASEBOARD_FAB2_LIB.BASEBOARD_FAB2(SCH_1):RST_BMC_SRST_N':
 C_SIGNAL='@baseboard_fab2_lib.baseboard_fab2(sch_1):rst_bmc_srst_n';
NODE_NAME     R7D23 1
 '@BASEBOARD_FAB2_LIB.BASEBOARD_FAB2(SCH_1):PAGE118_I131@MSTR_DISCRETE.RES(CHIPS)':
 'A': CDS_PINID='A';
NODE_NAME     J8G2 3
 '@BASEBOARD_FAB2_LIB.BASEBOARD_FAB2(SCH_1):PAGE135_I124@MSTR_CONN.CONN12_C73564003(CHIPS)':
 'IO3': CDS_PINID='IO3';
NODE_NAME     U25W4 U18
 '@BASEBOARD_FAB2_LIB.BASEBOARD_FAB2(SCH_1):PAGE145_I117@W_HDL.AST2520A1-GP-GP(CHIPS)':
 'SRST#': CDS_PINID='\srst#\';
NODE_NAME     U25W9 4
 '@BASEBOARD_FAB2_LIB.BASEBOARD_FAB2(SCH_1):PAGE157_I394@MSTR_TTL.TTL1G07_A(CHIPS)':
 'Y': CDS_PINID='Y';
NODE_NAME     R25W153 2
 '@BASEBOARD_FAB2_LIB.BASEBOARD_FAB2(SCH_1):PAGE157_I396@MSTR_DISCRETE.RES(CHIPS)':
 'B': CDS_PINID='B';
NET_NAME
'RST_BMC_SRST_R2_N'
 '@BASEBOARD_FAB2_LIB.BASEBOARD_FAB2(SCH_1):RST_BMC_SRST_R2_N':
 C_SIGNAL='@baseboard_fab2_lib.baseboard_fab2(sch_1):rst_bmc_srst_r2_n';
NODE_NAME     R8D25 2
 '@BASEBOARD_FAB2_LIB.BASEBOARD_FAB2(SCH_1):PAGE157_I335@MSTR_DISCRETE.RES(CHIPS)':
 'B': CDS_PINID='B';
NODE_NAME     U8D2 4
 '@BASEBOARD_FAB2_LIB.BASEBOARD_FAB2(SCH_1):PAGE157_I374@MSTR_TTL.TTL1G07_A(CHIPS)':
 'Y': CDS_PINID='Y';
NODE_NAME     R8D22 1
 '@BASEBOARD_FAB2_LIB.BASEBOARD_FAB2(SCH_1):PAGE157_I386@MSTR_DISCRETE.RES(CHIPS)':
 'A': CDS_PINID='A';
NODE_NAME     R8D36 1
 '@BASEBOARD_FAB2_LIB.BASEBOARD_FAB2(SCH_1):PAGE157_I388@MSTR_DISCRETE.RES(CHIPS)':
 'A': CDS_PINID='A';
NET_NAME
'RST_BMC_SRST_R_N'
 '@BASEBOARD_FAB2_LIB.BASEBOARD_FAB2(SCH_1):RST_BMC_SRST_R_N':
 C_SIGNAL='@baseboard_fab2_lib.baseboard_fab2(sch_1):rst_bmc_srst_r_n';
NODE_NAME     U7C1 M11
 '@BASEBOARD_FAB2_LIB.BASEBOARD_FAB2(SCH_1):PAGE118_I73@MSTR_U_PROC.LBG_CORE_QAT_EXT_D(CHIPS)':
 'GPD2_GBE_WAKE_N': CDS_PINID='GPD2_GBE_WAKE_N';
NODE_NAME     R7D23 2
 '@BASEBOARD_FAB2_LIB.BASEBOARD_FAB2(SCH_1):PAGE118_I131@MSTR_DISCRETE.RES(CHIPS)':
 'B': CDS_PINID='B';
NODE_NAME     R7W21 2
 '@BASEBOARD_FAB2_LIB.BASEBOARD_FAB2(SCH_1):PAGE118_I183@MSTR_DISCRETE.RES(CHIPS)':
 'B': CDS_PINID='B';
NET_NAME
'RST_BMC_SYSRST_BTN_OUT_B_N'
 '@BASEBOARD_FAB2_LIB.BASEBOARD_FAB2(SCH_1):RST_BMC_SYSRST_BTN_OUT_B_N':
 C_SIGNAL='@baseboard_fab2_lib.baseboard_fab2(sch_1):rst_bmc_sysrst_btn_out_b_n';
NODE_NAME     U7C1 BV19
 '@BASEBOARD_FAB2_LIB.BASEBOARD_FAB2(SCH_1):PAGE118_I73@MSTR_U_PROC.LBG_CORE_QAT_EXT_D(CHIPS)':
 'SYS_RESET_N': CDS_PINID='SYS_RESET_N';
NODE_NAME     R2T18 2
 '@BASEBOARD_FAB2_LIB.BASEBOARD_FAB2(SCH_1):PAGE156_I288@MSTR_DISCRETE.RES(CHIPS)':
 'B': CDS_PINID='B';
NODE_NAME     R1W29 1
 '@BASEBOARD_FAB2_LIB.BASEBOARD_FAB2(SCH_1):PAGE191_I198@MSTR_DISCRETE.RES(CHIPS)':
 'A': CDS_PINID='A';
NODE_NAME     R1W30 1
 '@BASEBOARD_FAB2_LIB.BASEBOARD_FAB2(SCH_1):PAGE118_I168@MSTR_DISCRETE.RES(CHIPS)':
 'A': CDS_PINID='A';
NET_NAME
'RST_BMC_SYSRST_BTN_OUT_B_R1_N'
 '@BASEBOARD_FAB2_LIB.BASEBOARD_FAB2(SCH_1):RST_BMC_SYSRST_BTN_OUT_B_R1_N':
 C_SIGNAL='@baseboard_fab2_lib.baseboard_fab2(sch_1):rst_bmc_sysrst_btn_out_b_r1~
_n';
NODE_NAME     U8D7 F14
 '@BASEBOARD_FAB2_LIB.BASEBOARD_FAB2(SCH_1):PAGE191_I59@MSTR_MEMORY.LCMXO2_A(CHIPS)':
 'PR4A': CDS_PINID='PR4A';
NODE_NAME     R1W29 2
 '@BASEBOARD_FAB2_LIB.BASEBOARD_FAB2(SCH_1):PAGE191_I198@MSTR_DISCRETE.RES(CHIPS)':
 'B': CDS_PINID='B';
NET_NAME
'RST_BMC_SYSRST_BTN_OUT_B_R_N'
 '@BASEBOARD_FAB2_LIB.BASEBOARD_FAB2(SCH_1):RST_BMC_SYSRST_BTN_OUT_B_R_N':
 C_SIGNAL='@baseboard_fab2_lib.baseboard_fab2(sch_1):rst_bmc_sysrst_btn_out_b_r_~
n';
NODE_NAME     R2T22 2
 '@BASEBOARD_FAB2_LIB.BASEBOARD_FAB2(SCH_1):PAGE156_I210@MSTR_DISCRETE.RES(CHIPS)':
 'B': CDS_PINID='B';
NODE_NAME     R2T18 1
 '@BASEBOARD_FAB2_LIB.BASEBOARD_FAB2(SCH_1):PAGE156_I288@MSTR_DISCRETE.RES(CHIPS)':
 'A': CDS_PINID='A';
NODE_NAME     U8F3 6
 '@BASEBOARD_FAB2_LIB.BASEBOARD_FAB2(SCH_1):PAGE156_I340@W_HDL.SN74LVC2G07DCKR-GP(CHIPS)':
 '1Y': CDS_PINID='\1y\';
NODE_NAME     U8G1 6
 '@BASEBOARD_FAB2_LIB.BASEBOARD_FAB2(SCH_1):PAGE156_I342@W_HDL.SN74LVC2G07DCKR-GP(CHIPS)':
 '1Y': CDS_PINID='\1y\';
NET_NAME
'RST_BMC_SYSRST_BTN_OUT_N'
 '@BASEBOARD_FAB2_LIB.BASEBOARD_FAB2(SCH_1):RST_BMC_SYSRST_BTN_OUT_N':
 C_SIGNAL='@baseboard_fab2_lib.baseboard_fab2(sch_1):rst_bmc_sysrst_btn_out_n';
NODE_NAME     R2T35 2
 '@BASEBOARD_FAB2_LIB.BASEBOARD_FAB2(SCH_1):PAGE156_I207@MSTR_DISCRETE.RES(CHIPS)':
 'B': CDS_PINID='B';
NODE_NAME     U25W4 C20
 '@BASEBOARD_FAB2_LIB.BASEBOARD_FAB2(SCH_1):PAGE145_I117@W_HDL.AST2520A1-GP-GP(CHIPS)':
 'GPIOE1_NDCD3': CDS_PINID='GPIOE1_NDCD3';
NODE_NAME     U8F3 1
 '@BASEBOARD_FAB2_LIB.BASEBOARD_FAB2(SCH_1):PAGE156_I340@W_HDL.SN74LVC2G07DCKR-GP(CHIPS)':
 '1A': CDS_PINID='\1a\';
NET_NAME
'RST_CD_CPU0_POR_N'
 '@BASEBOARD_FAB2_LIB.BASEBOARD_FAB2(SCH_1):RST_CD_CPU0_POR_N':
 C_SIGNAL='@baseboard_fab2_lib.baseboard_fab2(sch_1):rst_cd_cpu0_por_n';
NODE_NAME     U5D1 CF25
 '@BASEBOARD_FAB2_LIB.BASEBOARD_FAB2(SCH_1):PAGE29_I61@CHPSET_LIB.SKX_EXT_B(CHIPS)':
 'CD_POR_N': CDS_PINID='CD_POR_N';
NODE_NAME     U8D7 N3
 '@BASEBOARD_FAB2_LIB.BASEBOARD_FAB2(SCH_1):PAGE190_I179@MSTR_MEMORY.LCMXO2_A(CHIPS)':
 'PL14B': CDS_PINID='PL14B';
NODE_NAME     R3R16 2
 '@BASEBOARD_FAB2_LIB.BASEBOARD_FAB2(SCH_1):PAGE192_I48@MSTR_DISCRETE.RES(CHIPS)':
 'B': CDS_PINID='B';
NET_NAME
'RST_CD_CPU1_POR_N'
 '@BASEBOARD_FAB2_LIB.BASEBOARD_FAB2(SCH_1):RST_CD_CPU1_POR_N':
 C_SIGNAL='@baseboard_fab2_lib.baseboard_fab2(sch_1):rst_cd_cpu1_por_n';
NODE_NAME     U2D1 CF25
 '@BASEBOARD_FAB2_LIB.BASEBOARD_FAB2(SCH_1):PAGE63_I23@CHPSET_LIB.SKX_EXT_B(CHIPS)':
 'CD_POR_N': CDS_PINID='CD_POR_N';
NODE_NAME     U8D7 P10
 '@BASEBOARD_FAB2_LIB.BASEBOARD_FAB2(SCH_1):PAGE190_I179@MSTR_MEMORY.LCMXO2_A(CHIPS)':
 'PB19A': CDS_PINID='PB19A';
NODE_NAME     R6M9 2
 '@BASEBOARD_FAB2_LIB.BASEBOARD_FAB2(SCH_1):PAGE192_I49@MSTR_DISCRETE.RES(CHIPS)':
 'B': CDS_PINID='B';
NET_NAME
'RST_CPU0_G_N'
 '@BASEBOARD_FAB2_LIB.BASEBOARD_FAB2(SCH_1):RST_CPU0_G_N':
 C_SIGNAL='@baseboard_fab2_lib.baseboard_fab2(sch_1):rst_cpu0_g_n';
NODE_NAME     U5D1 AP21
 '@BASEBOARD_FAB2_LIB.BASEBOARD_FAB2(SCH_1):PAGE21_I259@CHPSET_LIB.SKX_EXT_B(CHIPS)':
 'RESET_N': CDS_PINID='RESET_N';
NODE_NAME     R6D12 2
 '@BASEBOARD_FAB2_LIB.BASEBOARD_FAB2(SCH_1):PAGE96_I2@MSTR_DISCRETE.RES(CHIPS)':
 'B': CDS_PINID='B';
NODE_NAME     U3P1 5
 '@BASEBOARD_FAB2_LIB.BASEBOARD_FAB2(SCH_1):PAGE96_I42@MSTR_DIGITAL.GTL2014(CHIPS)':
 'B2': CDS_PINID='B2';
NET_NAME
'RST_CPU0_LVC3_N'
 '@BASEBOARD_FAB2_LIB.BASEBOARD_FAB2(SCH_1):RST_CPU0_LVC3_N':
 C_SIGNAL='@baseboard_fab2_lib.baseboard_fab2(sch_1):rst_cpu0_lvc3_n';
NODE_NAME     U3P1 10
 '@BASEBOARD_FAB2_LIB.BASEBOARD_FAB2(SCH_1):PAGE96_I42@MSTR_DIGITAL.GTL2014(CHIPS)':
 'A2': CDS_PINID='A2';
NODE_NAME     R3P34 2
 '@BASEBOARD_FAB2_LIB.BASEBOARD_FAB2(SCH_1):PAGE190_I116@MSTR_DISCRETE.RES(CHIPS)':
 'B': CDS_PINID='B';
NET_NAME
'RST_CPU0_LVC3_R1_N'
 '@BASEBOARD_FAB2_LIB.BASEBOARD_FAB2(SCH_1):RST_CPU0_LVC3_R1_N':
 C_SIGNAL='@baseboard_fab2_lib.baseboard_fab2(sch_1):rst_cpu0_lvc3_r1_n';
NODE_NAME     R3P34 1
 '@BASEBOARD_FAB2_LIB.BASEBOARD_FAB2(SCH_1):PAGE190_I116@MSTR_DISCRETE.RES(CHIPS)':
 'A': CDS_PINID='A';
NODE_NAME     U8D7 R10
 '@BASEBOARD_FAB2_LIB.BASEBOARD_FAB2(SCH_1):PAGE190_I179@MSTR_MEMORY.LCMXO2_A(CHIPS)':
 'PB19B': CDS_PINID='PB19B';
NET_NAME
'RST_CPU1_G_N'
 '@BASEBOARD_FAB2_LIB.BASEBOARD_FAB2(SCH_1):RST_CPU1_G_N':
 C_SIGNAL='@baseboard_fab2_lib.baseboard_fab2(sch_1):rst_cpu1_g_n';
NODE_NAME     U2D1 AP21
 '@BASEBOARD_FAB2_LIB.BASEBOARD_FAB2(SCH_1):PAGE55_I172@CHPSET_LIB.SKX_EXT_B(CHIPS)':
 'RESET_N': CDS_PINID='RESET_N';
NODE_NAME     R3D20 2
 '@BASEBOARD_FAB2_LIB.BASEBOARD_FAB2(SCH_1):PAGE96_I25@MSTR_DISCRETE.RES(CHIPS)':
 'B': CDS_PINID='B';
NODE_NAME     U4C2 5
 '@BASEBOARD_FAB2_LIB.BASEBOARD_FAB2(SCH_1):PAGE96_I46@MSTR_DIGITAL.GTL2014(CHIPS)':
 'B2': CDS_PINID='B2';
NET_NAME
'RST_CPU1_LVC3_N'
 '@BASEBOARD_FAB2_LIB.BASEBOARD_FAB2(SCH_1):RST_CPU1_LVC3_N':
 C_SIGNAL='@baseboard_fab2_lib.baseboard_fab2(sch_1):rst_cpu1_lvc3_n';
NODE_NAME     U4C2 10
 '@BASEBOARD_FAB2_LIB.BASEBOARD_FAB2(SCH_1):PAGE96_I46@MSTR_DIGITAL.GTL2014(CHIPS)':
 'A2': CDS_PINID='A2';
NODE_NAME     R3P35 2
 '@BASEBOARD_FAB2_LIB.BASEBOARD_FAB2(SCH_1):PAGE190_I117@MSTR_DISCRETE.RES(CHIPS)':
 'B': CDS_PINID='B';
NET_NAME
'RST_CPU1_LVC3_R1_N'
 '@BASEBOARD_FAB2_LIB.BASEBOARD_FAB2(SCH_1):RST_CPU1_LVC3_R1_N':
 C_SIGNAL='@baseboard_fab2_lib.baseboard_fab2(sch_1):rst_cpu1_lvc3_r1_n';
NODE_NAME     R3P35 1
 '@BASEBOARD_FAB2_LIB.BASEBOARD_FAB2(SCH_1):PAGE190_I117@MSTR_DISCRETE.RES(CHIPS)':
 'A': CDS_PINID='A';
NODE_NAME     U8D7 N10
 '@BASEBOARD_FAB2_LIB.BASEBOARD_FAB2(SCH_1):PAGE190_I179@MSTR_MEMORY.LCMXO2_A(CHIPS)':
 'PB19C': CDS_PINID='PB19C';
NET_NAME
'RST_HFI0_CPU0_LVT2_N'
 '@BASEBOARD_FAB2_LIB.BASEBOARD_FAB2(SCH_1):RST_HFI0_CPU0_LVT2_N':
 C_SIGNAL='@baseboard_fab2_lib.baseboard_fab2(sch_1):rst_hfi0_cpu0_lvt2_n';
NODE_NAME     U5D1 BN24
 '@BASEBOARD_FAB2_LIB.BASEBOARD_FAB2(SCH_1):PAGE29_I61@CHPSET_LIB.SKX_EXT_B(CHIPS)':
 'CD_HFI0_RESET_N': CDS_PINID='CD_HFI0_RESET_N';
NODE_NAME     J8B1 6
 '@BASEBOARD_FAB2_LIB.BASEBOARD_FAB2(SCH_1):PAGE91_I1@MSTR_SCONN.SCONN24_H46321001(CHIPS)':
 'IO6': CDS_PINID='IO6';
NODE_NAME     R8B8 2
 '@BASEBOARD_FAB2_LIB.BASEBOARD_FAB2(SCH_1):PAGE91_I14@MSTR_DISCRETE.RES(CHIPS)':
 'B': CDS_PINID='B';
NET_NAME
'RST_HFI1_CPU0_LVT2_N'
 '@BASEBOARD_FAB2_LIB.BASEBOARD_FAB2(SCH_1):RST_HFI1_CPU0_LVT2_N':
 C_SIGNAL='@baseboard_fab2_lib.baseboard_fab2(sch_1):rst_hfi1_cpu0_lvt2_n';
NODE_NAME     U5D1 BK23
 '@BASEBOARD_FAB2_LIB.BASEBOARD_FAB2(SCH_1):PAGE29_I61@CHPSET_LIB.SKX_EXT_B(CHIPS)':
 'CD_HFI1_RESET_N': CDS_PINID='CD_HFI1_RESET_N';
NODE_NAME     J8B1 14
 '@BASEBOARD_FAB2_LIB.BASEBOARD_FAB2(SCH_1):PAGE91_I1@MSTR_SCONN.SCONN24_H46321001(CHIPS)':
 'IO14': CDS_PINID='IO14';
NODE_NAME     R8B16 2
 '@BASEBOARD_FAB2_LIB.BASEBOARD_FAB2(SCH_1):PAGE91_I17@MSTR_DISCRETE.RES(CHIPS)':
 'B': CDS_PINID='B';
NET_NAME
'RST_PCH_SYSRST_BTN_OUT_N'
 '@BASEBOARD_FAB2_LIB.BASEBOARD_FAB2(SCH_1):RST_PCH_SYSRST_BTN_OUT_N':
 C_SIGNAL='@baseboard_fab2_lib.baseboard_fab2(sch_1):rst_pch_sysrst_btn_out_n';
NODE_NAME     U7C1 AD3
 '@BASEBOARD_FAB2_LIB.BASEBOARD_FAB2(SCH_1):PAGE119_I115@MSTR_U_PROC.LBG_CORE_QAT_EXT_D(CHIPS)':
 'GPP_A18': CDS_PINID='GPP_A18';
NODE_NAME     R2U2 2
 '@BASEBOARD_FAB2_LIB.BASEBOARD_FAB2(SCH_1):PAGE156_I265@MSTR_DISCRETE.RES(CHIPS)':
 'B': CDS_PINID='B';
NODE_NAME     U8G1 1
 '@BASEBOARD_FAB2_LIB.BASEBOARD_FAB2(SCH_1):PAGE156_I342@W_HDL.SN74LVC2G07DCKR-GP(CHIPS)':
 '1A': CDS_PINID='\1a\';
NET_NAME
'RST_PCIE_CPU_DEV0_N'
 '@BASEBOARD_FAB2_LIB.BASEBOARD_FAB2(SCH_1):RST_PCIE_CPU_DEV0_N':
 C_SIGNAL='@baseboard_fab2_lib.baseboard_fab2(sch_1):rst_pcie_cpu_dev0_n';
NODE_NAME     R1M14 1
 '@BASEBOARD_FAB2_LIB.BASEBOARD_FAB2(SCH_1):PAGE186_I220@MSTR_DISCRETE.RES(CHIPS)':
 'A': CDS_PINID='A';
NODE_NAME     U8D7 D6
 '@BASEBOARD_FAB2_LIB.BASEBOARD_FAB2(SCH_1):PAGE191_I59@MSTR_MEMORY.LCMXO2_A(CHIPS)':
 'PT12A': CDS_PINID='PT12A';
NET_NAME
'RST_PCIE_CPU_DEV0_R_N'
 '@BASEBOARD_FAB2_LIB.BASEBOARD_FAB2(SCH_1):RST_PCIE_CPU_DEV0_R_N':
 C_SIGNAL='@baseboard_fab2_lib.baseboard_fab2(sch_1):rst_pcie_cpu_dev0_r_n';
NODE_NAME     R1M14 2
 '@BASEBOARD_FAB2_LIB.BASEBOARD_FAB2(SCH_1):PAGE186_I220@MSTR_DISCRETE.RES(CHIPS)':
 'B': CDS_PINID='B';
NODE_NAME     J9B3 33
 '@BASEBOARD_FAB2_LIB.BASEBOARD_FAB2(SCH_1):PAGE186_I336@MSTR_SCONN.SCONN120_A28699018(CHIPS)':
 'IO33': CDS_PINID='IO33';
NET_NAME
'RST_PCIE_CPU_DEV1_N'
 '@BASEBOARD_FAB2_LIB.BASEBOARD_FAB2(SCH_1):RST_PCIE_CPU_DEV1_N':
 C_SIGNAL='@baseboard_fab2_lib.baseboard_fab2(sch_1):rst_pcie_cpu_dev1_n';
NODE_NAME     R9E10 2
 '@BASEBOARD_FAB2_LIB.BASEBOARD_FAB2(SCH_1):PAGE187_I145@MSTR_DISCRETE.RES(CHIPS)':
 'B': CDS_PINID='B';
NODE_NAME     U8D7 C1
 '@BASEBOARD_FAB2_LIB.BASEBOARD_FAB2(SCH_1):PAGE190_I179@MSTR_MEMORY.LCMXO2_A(CHIPS)':
 'PL2C': CDS_PINID='PL2C';
NET_NAME
'RST_PCIE_CPU_DEV1_R_N'
 '@BASEBOARD_FAB2_LIB.BASEBOARD_FAB2(SCH_1):RST_PCIE_CPU_DEV1_R_N':
 C_SIGNAL='@baseboard_fab2_lib.baseboard_fab2(sch_1):rst_pcie_cpu_dev1_r_n';
NODE_NAME     J8E3 75
 '@BASEBOARD_FAB2_LIB.BASEBOARD_FAB2(SCH_1):PAGE187_I119@MSTR_SCONN.SCONN80_E67482007(CHIPS)':
 'IO75': CDS_PINID='IO75';
NODE_NAME     R9E10 1
 '@BASEBOARD_FAB2_LIB.BASEBOARD_FAB2(SCH_1):PAGE187_I145@MSTR_DISCRETE.RES(CHIPS)':
 'A': CDS_PINID='A';
NET_NAME
'RST_PCIE_CPU_DEV2_N'
 '@BASEBOARD_FAB2_LIB.BASEBOARD_FAB2(SCH_1):RST_PCIE_CPU_DEV2_N':
 C_SIGNAL='@baseboard_fab2_lib.baseboard_fab2(sch_1):rst_pcie_cpu_dev2_n';
NODE_NAME     R9E11 2
 '@BASEBOARD_FAB2_LIB.BASEBOARD_FAB2(SCH_1):PAGE187_I150@MSTR_DISCRETE.RES(CHIPS)':
 'B': CDS_PINID='B';
NODE_NAME     U8D7 H3
 '@BASEBOARD_FAB2_LIB.BASEBOARD_FAB2(SCH_1):PAGE190_I179@MSTR_MEMORY.LCMXO2_A(CHIPS)':
 'PL7A': CDS_PINID='PL7A';
NET_NAME
'RST_PCIE_CPU_DEV2_R_N'
 '@BASEBOARD_FAB2_LIB.BASEBOARD_FAB2(SCH_1):RST_PCIE_CPU_DEV2_R_N':
 C_SIGNAL='@baseboard_fab2_lib.baseboard_fab2(sch_1):rst_pcie_cpu_dev2_r_n';
NODE_NAME     J8E3 77
 '@BASEBOARD_FAB2_LIB.BASEBOARD_FAB2(SCH_1):PAGE187_I119@MSTR_SCONN.SCONN80_E67482007(CHIPS)':
 'IO77': CDS_PINID='IO77';
NODE_NAME     R9E11 1
 '@BASEBOARD_FAB2_LIB.BASEBOARD_FAB2(SCH_1):PAGE187_I150@MSTR_DISCRETE.RES(CHIPS)':
 'A': CDS_PINID='A';
NET_NAME
'RST_PCIE_CPU_DEV3_N'
 '@BASEBOARD_FAB2_LIB.BASEBOARD_FAB2(SCH_1):RST_PCIE_CPU_DEV3_N':
 C_SIGNAL='@baseboard_fab2_lib.baseboard_fab2(sch_1):rst_pcie_cpu_dev3_n';
NODE_NAME     R9E12 2
 '@BASEBOARD_FAB2_LIB.BASEBOARD_FAB2(SCH_1):PAGE187_I153@MSTR_DISCRETE.RES(CHIPS)':
 'B': CDS_PINID='B';
NODE_NAME     U8D7 H1
 '@BASEBOARD_FAB2_LIB.BASEBOARD_FAB2(SCH_1):PAGE190_I179@MSTR_MEMORY.LCMXO2_A(CHIPS)':
 'PL7B': CDS_PINID='PL7B';
NET_NAME
'RST_PCIE_CPU_DEV3_R_N'
 '@BASEBOARD_FAB2_LIB.BASEBOARD_FAB2(SCH_1):RST_PCIE_CPU_DEV3_R_N':
 C_SIGNAL='@baseboard_fab2_lib.baseboard_fab2(sch_1):rst_pcie_cpu_dev3_r_n';
NODE_NAME     J8E3 79
 '@BASEBOARD_FAB2_LIB.BASEBOARD_FAB2(SCH_1):PAGE187_I119@MSTR_SCONN.SCONN80_E67482007(CHIPS)':
 'IO79': CDS_PINID='IO79';
NODE_NAME     R9E12 1
 '@BASEBOARD_FAB2_LIB.BASEBOARD_FAB2(SCH_1):PAGE187_I153@MSTR_DISCRETE.RES(CHIPS)':
 'A': CDS_PINID='A';
NET_NAME
'RST_PCIE_M2_DEV_AND'
 '@BASEBOARD_FAB2_LIB.BASEBOARD_FAB2(SCH_1):RST_PCIE_M2_DEV_AND':
 C_SIGNAL='@baseboard_fab2_lib.baseboard_fab2(sch_1):rst_pcie_m2_dev_and';
NODE_NAME     U14E2 2
 '@BASEBOARD_FAB2_LIB.BASEBOARD_FAB2(SCH_1):PAGE248_I11@MSTR_TTL.TTL1G08(CHIPS)':
 'B'<0>: CDS_PINID='B(0)';
NODE_NAME     U14E3 4
 '@BASEBOARD_FAB2_LIB.BASEBOARD_FAB2(SCH_1):PAGE248_I19@MSTR_TTL.TTL1G08(CHIPS)':
 'Y'<0>: CDS_PINID='Y(0)';
NET_NAME
'RST_PCIE_M2_DEV_IC_N'
 '@BASEBOARD_FAB2_LIB.BASEBOARD_FAB2(SCH_1):RST_PCIE_M2_DEV_IC_N':
 C_SIGNAL='@baseboard_fab2_lib.baseboard_fab2(sch_1):rst_pcie_m2_dev_ic_n';
NODE_NAME     U14E2 4
 '@BASEBOARD_FAB2_LIB.BASEBOARD_FAB2(SCH_1):PAGE248_I11@MSTR_TTL.TTL1G08(CHIPS)':
 'Y'<0>: CDS_PINID='Y(0)';
NODE_NAME     J8F1 50
 '@BASEBOARD_FAB2_LIB.BASEBOARD_FAB2(SCH_1):PAGE185_I143@W_HDL.SKT-MINI67P-41-GP(CHIPS)':
 '50': CDS_PINID='\50\';
NET_NAME
'RST_PCIE_M2_DEV_N'
 '@BASEBOARD_FAB2_LIB.BASEBOARD_FAB2(SCH_1):RST_PCIE_M2_DEV_N':
 C_SIGNAL='@baseboard_fab2_lib.baseboard_fab2(sch_1):rst_pcie_m2_dev_n';
NODE_NAME     U8D7 R6
 '@BASEBOARD_FAB2_LIB.BASEBOARD_FAB2(SCH_1):PAGE190_I179@MSTR_MEMORY.LCMXO2_A(CHIPS)':
 'PB6B': CDS_PINID='PB6B';
NODE_NAME     U14E2 1
 '@BASEBOARD_FAB2_LIB.BASEBOARD_FAB2(SCH_1):PAGE248_I11@MSTR_TTL.TTL1G08(CHIPS)':
 'A'<0>: CDS_PINID='A(0)';
NET_NAME
'RST_PCIE_MIDPLANE_N'
 '@BASEBOARD_FAB2_LIB.BASEBOARD_FAB2(SCH_1):RST_PCIE_MIDPLANE_N':
 C_SIGNAL='@baseboard_fab2_lib.baseboard_fab2(sch_1):rst_pcie_midplane_n';
NODE_NAME     U8D7 D9
 '@BASEBOARD_FAB2_LIB.BASEBOARD_FAB2(SCH_1):PAGE191_I59@MSTR_MEMORY.LCMXO2_A(CHIPS)':
 'PT18B': CDS_PINID='PT18B';
NODE_NAME     J1F1 I5
 '@BASEBOARD_FAB2_LIB.BASEBOARD_FAB2(SCH_1):PAGE181_I134@W_HDL.DM-FCI-CONN76-8R-GP-U-01(CHIPS)':
 'PCIE_PERST#': CDS_PINID='\pcie_perst#\';
NET_NAME
'RST_PCIE_PCH_PERST_N'
 '@BASEBOARD_FAB2_LIB.BASEBOARD_FAB2(SCH_1):RST_PCIE_PCH_PERST_N':
 C_SIGNAL='@baseboard_fab2_lib.baseboard_fab2(sch_1):rst_pcie_pch_perst_n';
NODE_NAME     U7C1 AH4
 '@BASEBOARD_FAB2_LIB.BASEBOARD_FAB2(SCH_1):PAGE121_I34@MSTR_U_PROC.LBG_CORE_QAT_EXT_D(CHIPS)':
 'GPP_K10_PE_RST_N': CDS_PINID='GPP_K10_PE_RST_N';
NODE_NAME     U8D7 B1
 '@BASEBOARD_FAB2_LIB.BASEBOARD_FAB2(SCH_1):PAGE190_I179@MSTR_MEMORY.LCMXO2_A(CHIPS)':
 'PL1C': CDS_PINID='PL1C';
NET_NAME
'RST_PCIE_RISER1_PERST_N'
 '@BASEBOARD_FAB2_LIB.BASEBOARD_FAB2(SCH_1):RST_PCIE_RISER1_PERST_N':
 C_SIGNAL='@baseboard_fab2_lib.baseboard_fab2(sch_1):rst_pcie_riser1_perst_n';
NODE_NAME     R2U37 1
 '@BASEBOARD_FAB2_LIB.BASEBOARD_FAB2(SCH_1):PAGE108_I173@MSTR_DISCRETE.RES(CHIPS)':
 'A': CDS_PINID='A';
NODE_NAME     U8D7 M3
 '@BASEBOARD_FAB2_LIB.BASEBOARD_FAB2(SCH_1):PAGE190_I179@MSTR_MEMORY.LCMXO2_A(CHIPS)':
 'PL13A': CDS_PINID='PL13A';
NET_NAME
'RST_PCIE_RISER1_PERST_R_N'
 '@BASEBOARD_FAB2_LIB.BASEBOARD_FAB2(SCH_1):RST_PCIE_RISER1_PERST_R_N':
 C_SIGNAL='@baseboard_fab2_lib.baseboard_fab2(sch_1):rst_pcie_riser1_perst_r_n';
NODE_NAME     R2U37 2
 '@BASEBOARD_FAB2_LIB.BASEBOARD_FAB2(SCH_1):PAGE108_I173@MSTR_DISCRETE.RES(CHIPS)':
 'B': CDS_PINID='B';
NODE_NAME     J8G1 29
 '@BASEBOARD_FAB2_LIB.BASEBOARD_FAB2(SCH_1):PAGE108_I258@MSTR_SCONN.SCONN200_H68296001(CHIPS)':
 'IO29': CDS_PINID='IO29';
NET_NAME
'RST_PLTRST_BUF_N'
 '@BASEBOARD_FAB2_LIB.BASEBOARD_FAB2(SCH_1):RST_PLTRST_BUF_N':
 C_SIGNAL='@baseboard_fab2_lib.baseboard_fab2(sch_1):rst_pltrst_buf_n';
NODE_NAME     J8E1 2
 '@BASEBOARD_FAB2_LIB.BASEBOARD_FAB2(SCH_1):PAGE184_I87@MSTR_SCONN.SCONN11_H67026001(CHIPS)':
 'IO2': CDS_PINID='IO2';
NODE_NAME     U8D7 K11
 '@BASEBOARD_FAB2_LIB.BASEBOARD_FAB2(SCH_1):PAGE191_I59@MSTR_MEMORY.LCMXO2_A(CHIPS)':
 'PR12C': CDS_PINID='PR12C';
NODE_NAME     R25W74 1
 '@BASEBOARD_FAB2_LIB.BASEBOARD_FAB2(SCH_1):PAGE146_I70@MSTR_DISCRETE.RES(CHIPS)':
 'A': CDS_PINID='A';
NODE_NAME     Q8D2 1
 '@BASEBOARD_FAB2_LIB.BASEBOARD_FAB2(SCH_1):PAGE134_I15@MSTR_DISCRETE.FET_N(CHIPS)':
 'GATE': CDS_PINID='GATE';
NODE_NAME     R25W141 1
 '@BASEBOARD_FAB2_LIB.BASEBOARD_FAB2(SCH_1):PAGE145_I160@MSTR_DISCRETE.RES(CHIPS)':
 'A': CDS_PINID='A';
NODE_NAME     R25W184 2
 '@BASEBOARD_FAB2_LIB.BASEBOARD_FAB2(SCH_1):PAGE146_I166@MSTR_DISCRETE.RES(CHIPS)':
 'B': CDS_PINID='B';
NET_NAME
'RST_PLTRST_BUF_N_R'
 '@BASEBOARD_FAB2_LIB.BASEBOARD_FAB2(SCH_1):RST_PLTRST_BUF_N_R':
 C_SIGNAL='@baseboard_fab2_lib.baseboard_fab2(sch_1):rst_pltrst_buf_n_r';
NODE_NAME     R25W62 1
 '@BASEBOARD_FAB2_LIB.BASEBOARD_FAB2(SCH_1):PAGE145_I31@MSTR_DISCRETE.RES(CHIPS)':
 'A': CDS_PINID='A';
NODE_NAME     U25W4 L20
 '@BASEBOARD_FAB2_LIB.BASEBOARD_FAB2(SCH_1):PAGE145_I117@W_HDL.AST2520A1-GP-GP(CHIPS)':
 'PERST#': CDS_PINID='\perst#\';
NODE_NAME     R25W141 2
 '@BASEBOARD_FAB2_LIB.BASEBOARD_FAB2(SCH_1):PAGE145_I160@MSTR_DISCRETE.RES(CHIPS)':
 'B': CDS_PINID='B';
NET_NAME
'RST_PLTRST_N'
 '@BASEBOARD_FAB2_LIB.BASEBOARD_FAB2(SCH_1):RST_PLTRST_N':
 C_SIGNAL='@baseboard_fab2_lib.baseboard_fab2(sch_1):rst_pltrst_n';
NODE_NAME     U7C1 BN18
 '@BASEBOARD_FAB2_LIB.BASEBOARD_FAB2(SCH_1):PAGE119_I115@MSTR_U_PROC.LBG_CORE_QAT_EXT_D(CHIPS)':
 'GPP_B13_PLTRST_N': CDS_PINID='GPP_B13_PLTRST_N';
NODE_NAME     Q8E1 1
 '@BASEBOARD_FAB2_LIB.BASEBOARD_FAB2(SCH_1):PAGE136_I134@MSTR_DISCRETE.FET_N(CHIPS)':
 'GATE': CDS_PINID='GATE';
NODE_NAME     R1R1 1
 '@BASEBOARD_FAB2_LIB.BASEBOARD_FAB2(SCH_1):PAGE139_I195@MSTR_DISCRETE.RES(CHIPS)':
 'A': CDS_PINID='A';
NODE_NAME     U8D7 E15
 '@BASEBOARD_FAB2_LIB.BASEBOARD_FAB2(SCH_1):PAGE191_I59@MSTR_MEMORY.LCMXO2_A(CHIPS)':
 'PR1B': CDS_PINID='PR1B';
NODE_NAME     U6W1 16
 '@BASEBOARD_FAB2_LIB.BASEBOARD_FAB2(SCH_1):PAGE247_I120@W_HDL.TCA9555PWR-GP(CHIPS)':
 'P13': CDS_PINID='P13';
NET_NAME
'RST_PLTRST_SPRV_R_N'
 '@BASEBOARD_FAB2_LIB.BASEBOARD_FAB2(SCH_1):RST_PLTRST_SPRV_R_N':
 C_SIGNAL='@baseboard_fab2_lib.baseboard_fab2(sch_1):rst_pltrst_sprv_r_n';
NODE_NAME     EU9E1 17
 '@BASEBOARD_FAB2_LIB.BASEBOARD_FAB2(SCH_1):PAGE139_I72@MSTR_INTEL.SPRINGVILLE(CHIPS)':
 'PE_RST_N': CDS_PINID='PE_RST_N';
NODE_NAME     R1R1 2
 '@BASEBOARD_FAB2_LIB.BASEBOARD_FAB2(SCH_1):PAGE139_I195@MSTR_DISCRETE.RES(CHIPS)':
 'B': CDS_PINID='B';
NODE_NAME     R9E4 2
 '@BASEBOARD_FAB2_LIB.BASEBOARD_FAB2(SCH_1):PAGE139_I200@MSTR_DISCRETE.RES(CHIPS)':
 'B': CDS_PINID='B';
NET_NAME
'RST_PLTRST_TOP_SWAP'
 '@BASEBOARD_FAB2_LIB.BASEBOARD_FAB2(SCH_1):RST_PLTRST_TOP_SWAP':
 C_SIGNAL='@baseboard_fab2_lib.baseboard_fab2(sch_1):rst_pltrst_top_swap';
NODE_NAME     U8E3 1
 '@BASEBOARD_FAB2_LIB.BASEBOARD_FAB2(SCH_1):PAGE136_I130@MSTR_TTL.TTL1G126_A(CHIPS)':
 'OE': CDS_PINID='OE';
NODE_NAME     R8E14 2
 '@BASEBOARD_FAB2_LIB.BASEBOARD_FAB2(SCH_1):PAGE136_I133@MSTR_DISCRETE.RES(CHIPS)':
 'B': CDS_PINID='B';
NODE_NAME     Q8E1 3
 '@BASEBOARD_FAB2_LIB.BASEBOARD_FAB2(SCH_1):PAGE136_I134@MSTR_DISCRETE.FET_N(CHIPS)':
 'DRN': CDS_PINID='DRN';
NET_NAME
'RST_RSMRST_DLY'
 '@BASEBOARD_FAB2_LIB.BASEBOARD_FAB2(SCH_1):RST_RSMRST_DLY':
 C_SIGNAL='@baseboard_fab2_lib.baseboard_fab2(sch_1):rst_rsmrst_dly';
NODE_NAME     Q8E2 1
 '@BASEBOARD_FAB2_LIB.BASEBOARD_FAB2(SCH_1):PAGE126_I13@MSTR_DISCRETE.FET_N(CHIPS)':
 'GATE': CDS_PINID='GATE';
NODE_NAME     U8D7 M1
 '@BASEBOARD_FAB2_LIB.BASEBOARD_FAB2(SCH_1):PAGE190_I179@MSTR_MEMORY.LCMXO2_A(CHIPS)':
 'PL12B_PCLKC3_0': CDS_PINID='PL12B_PCLKC3_0';
NET_NAME
'RST_RSMRST_N'
 '@BASEBOARD_FAB2_LIB.BASEBOARD_FAB2(SCH_1):RST_RSMRST_N':
 C_SIGNAL='@baseboard_fab2_lib.baseboard_fab2(sch_1):rst_rsmrst_n';
NODE_NAME     R9A15 1
 '@BASEBOARD_FAB2_LIB.BASEBOARD_FAB2(SCH_1):PAGE111_I60@MSTR_DISCRETE.RES(CHIPS)':
 'A': CDS_PINID='A';
NODE_NAME     U7C1 P15
 '@BASEBOARD_FAB2_LIB.BASEBOARD_FAB2(SCH_1):PAGE118_I73@MSTR_U_PROC.LBG_CORE_QAT_EXT_D(CHIPS)':
 'RSMRST_N': CDS_PINID='RSMRST_N';
NODE_NAME     R2R2 2
 '@BASEBOARD_FAB2_LIB.BASEBOARD_FAB2(SCH_1):PAGE190_I338@MSTR_DISCRETE.RES(CHIPS)':
 'B': CDS_PINID='B';
NODE_NAME     R7E18 2
 '@BASEBOARD_FAB2_LIB.BASEBOARD_FAB2(SCH_1):PAGE192_I55@MSTR_DISCRETE.RES(CHIPS)':
 'B': CDS_PINID='B';
NODE_NAME     R25W181 1
 '@BASEBOARD_FAB2_LIB.BASEBOARD_FAB2(SCH_1):PAGE147_I173@MSTR_DISCRETE.RES(CHIPS)':
 'A': CDS_PINID='A';
NET_NAME
'RST_RSMRST_R_N'
 '@BASEBOARD_FAB2_LIB.BASEBOARD_FAB2(SCH_1):RST_RSMRST_R_N':
 C_SIGNAL='@baseboard_fab2_lib.baseboard_fab2(sch_1):rst_rsmrst_r_n';
NODE_NAME     U8D7 G4
 '@BASEBOARD_FAB2_LIB.BASEBOARD_FAB2(SCH_1):PAGE190_I179@MSTR_MEMORY.LCMXO2_A(CHIPS)':
 'PL4D': CDS_PINID='PL4D';
NODE_NAME     R2R2 1
 '@BASEBOARD_FAB2_LIB.BASEBOARD_FAB2(SCH_1):PAGE190_I338@MSTR_DISCRETE.RES(CHIPS)':
 'A': CDS_PINID='A';
NODE_NAME     R1W26 1
 '@BASEBOARD_FAB2_LIB.BASEBOARD_FAB2(SCH_1):PAGE190_I349@MSTR_DISCRETE.RES(CHIPS)':
 'A': CDS_PINID='A';
NET_NAME
'RST_RTCRST_N'
 '@BASEBOARD_FAB2_LIB.BASEBOARD_FAB2(SCH_1):RST_RTCRST_N':
 C_SIGNAL='@baseboard_fab2_lib.baseboard_fab2(sch_1):rst_rtcrst_n';
NODE_NAME     U7C1 P11
 '@BASEBOARD_FAB2_LIB.BASEBOARD_FAB2(SCH_1):PAGE121_I34@MSTR_U_PROC.LBG_CORE_QAT_EXT_D(CHIPS)':
 'RTCRST_N': CDS_PINID='RTCRST_N';
NODE_NAME     R7C11 2
 '@BASEBOARD_FAB2_LIB.BASEBOARD_FAB2(SCH_1):PAGE137_I11@MSTR_DISCRETE.RES(CHIPS)':
 'B': CDS_PINID='B';
NODE_NAME     R7C10 2
 '@BASEBOARD_FAB2_LIB.BASEBOARD_FAB2(SCH_1):PAGE137_I13@MSTR_DISCRETE.RES(CHIPS)':
 'B': CDS_PINID='B';
NODE_NAME     C7C19 1
 '@BASEBOARD_FAB2_LIB.BASEBOARD_FAB2(SCH_1):PAGE137_I14@DEV_DISCRETE.CAP_A(CHIPS)':
 'A': CDS_PINID='A';
NODE_NAME     J9G1 4
 '@BASEBOARD_FAB2_LIB.BASEBOARD_FAB2(SCH_1):PAGE137_I128@MSTR_CONN.CONN12_C73564003(CHIPS)':
 'IO4': CDS_PINID='IO4';
NET_NAME
'RST_SRTCRST_N'
 '@BASEBOARD_FAB2_LIB.BASEBOARD_FAB2(SCH_1):RST_SRTCRST_N':
 C_SIGNAL='@baseboard_fab2_lib.baseboard_fab2(sch_1):rst_srtcrst_n';
NODE_NAME     U7C1 G18
 '@BASEBOARD_FAB2_LIB.BASEBOARD_FAB2(SCH_1):PAGE121_I34@MSTR_U_PROC.LBG_CORE_QAT_EXT_D(CHIPS)':
 'SRTCRST_N': CDS_PINID='SRTCRST_N';
NODE_NAME     R3N4 2
 '@BASEBOARD_FAB2_LIB.BASEBOARD_FAB2(SCH_1):PAGE137_I19@MSTR_DISCRETE.RES(CHIPS)':
 'B': CDS_PINID='B';
NODE_NAME     C3N32 1
 '@BASEBOARD_FAB2_LIB.BASEBOARD_FAB2(SCH_1):PAGE137_I20@DEV_DISCRETE.CAP_A(CHIPS)':
 'A': CDS_PINID='A';
NET_NAME
'RST_SYSTEM_BTN_BUF_N'
 '@BASEBOARD_FAB2_LIB.BASEBOARD_FAB2(SCH_1):RST_SYSTEM_BTN_BUF_N':
 C_SIGNAL='@baseboard_fab2_lib.baseboard_fab2(sch_1):rst_system_btn_buf_n';
NODE_NAME     U9A3 4
 '@BASEBOARD_FAB2_LIB.BASEBOARD_FAB2(SCH_1):PAGE175_I93@W_HDL.TC7PZ14FU-GP(CHIPS)':
 '2Y': CDS_PINID='\2y\';
NODE_NAME     R9A9 1
 '@BASEBOARD_FAB2_LIB.BASEBOARD_FAB2(SCH_1):PAGE175_I95@MSTR_DISCRETE.RES(CHIPS)':
 'A': CDS_PINID='A';
NODE_NAME     R1W30 2
 '@BASEBOARD_FAB2_LIB.BASEBOARD_FAB2(SCH_1):PAGE118_I168@MSTR_DISCRETE.RES(CHIPS)':
 'B': CDS_PINID='B';
NET_NAME
'RST_SYSTEM_BTN_N'
 '@BASEBOARD_FAB2_LIB.BASEBOARD_FAB2(SCH_1):RST_SYSTEM_BTN_N':
 C_SIGNAL='@baseboard_fab2_lib.baseboard_fab2(sch_1):rst_system_btn_n';
NODE_NAME     U7C1 BL11
 '@BASEBOARD_FAB2_LIB.BASEBOARD_FAB2(SCH_1):PAGE119_I115@MSTR_U_PROC.LBG_CORE_QAT_EXT_D(CHIPS)':
 'GPP_B10_SRCCLKREQ5_N': CDS_PINID='GPP_B10_SRCCLKREQ5_N';
NODE_NAME     R9A9 2
 '@BASEBOARD_FAB2_LIB.BASEBOARD_FAB2(SCH_1):PAGE175_I95@MSTR_DISCRETE.RES(CHIPS)':
 'B': CDS_PINID='B';
NODE_NAME     R25W145 2
 '@BASEBOARD_FAB2_LIB.BASEBOARD_FAB2(SCH_1):PAGE145_I175@MSTR_DISCRETE.RES(CHIPS)':
 'B': CDS_PINID='B';
NET_NAME
'RST_SYSTEM_BTN_R_N'
 '@BASEBOARD_FAB2_LIB.BASEBOARD_FAB2(SCH_1):RST_SYSTEM_BTN_R_N':
 C_SIGNAL='@baseboard_fab2_lib.baseboard_fab2(sch_1):rst_system_btn_r_n';
NODE_NAME     U25W4 B20
 '@BASEBOARD_FAB2_LIB.BASEBOARD_FAB2(SCH_1):PAGE145_I117@W_HDL.AST2520A1-GP-GP(CHIPS)':
 'GPIOE0_NCTS3': CDS_PINID='GPIOE0_NCTS3';
NODE_NAME     R25W145 1
 '@BASEBOARD_FAB2_LIB.BASEBOARD_FAB2(SCH_1):PAGE145_I175@MSTR_DISCRETE.RES(CHIPS)':
 'A': CDS_PINID='A';
NET_NAME
'SATA6G_P0_RX_C_DN'
 '@BASEBOARD_FAB2_LIB.BASEBOARD_FAB2(SCH_1):SATA6G_P0_RX_C_DN':
 C_SIGNAL='@baseboard_fab2_lib.baseboard_fab2(sch_1):sata6g_p0_rx_c_dn';
NODE_NAME     J8A1 1B5
 '@BASEBOARD_FAB2_LIB.BASEBOARD_FAB2(SCH_1):PAGE173_I163@MSTR_CONN.CONN72_G97614002_A(CHIPS)':
 'RXA0_DN': CDS_PINID='RXA0_DN';
NODE_NAME     C2L17 2
 '@BASEBOARD_FAB2_LIB.BASEBOARD_FAB2(SCH_1):PAGE173_I174@DEV_DISCRETE.CAP_A(CHIPS)':
 'B': CDS_PINID='B';
NET_NAME
'SATA6G_P0_RX_C_DP'
 '@BASEBOARD_FAB2_LIB.BASEBOARD_FAB2(SCH_1):SATA6G_P0_RX_C_DP':
 C_SIGNAL='@baseboard_fab2_lib.baseboard_fab2(sch_1):sata6g_p0_rx_c_dp';
NODE_NAME     J8A1 1B4
 '@BASEBOARD_FAB2_LIB.BASEBOARD_FAB2(SCH_1):PAGE173_I163@MSTR_CONN.CONN72_G97614002_A(CHIPS)':
 'RXA0_DP': CDS_PINID='RXA0_DP';
NODE_NAME     C2L19 2
 '@BASEBOARD_FAB2_LIB.BASEBOARD_FAB2(SCH_1):PAGE173_I172@DEV_DISCRETE.CAP_A(CHIPS)':
 'B': CDS_PINID='B';
NET_NAME
'SATA6G_P0_TX_C_DN'
 '@BASEBOARD_FAB2_LIB.BASEBOARD_FAB2(SCH_1):SATA6G_P0_TX_C_DN':
 C_SIGNAL='@baseboard_fab2_lib.baseboard_fab2(sch_1):sata6g_p0_tx_c_dn';
NODE_NAME     J8A1 1D5
 '@BASEBOARD_FAB2_LIB.BASEBOARD_FAB2(SCH_1):PAGE173_I163@MSTR_CONN.CONN72_G97614002_A(CHIPS)':
 'TXA0_DN': CDS_PINID='TXA0_DN';
NODE_NAME     C2L40 1
 '@BASEBOARD_FAB2_LIB.BASEBOARD_FAB2(SCH_1):PAGE173_I220@DEV_DISCRETE.CAP_A(CHIPS)':
 'A': CDS_PINID='A';
NET_NAME
'SATA6G_P0_TX_C_DP'
 '@BASEBOARD_FAB2_LIB.BASEBOARD_FAB2(SCH_1):SATA6G_P0_TX_C_DP':
 C_SIGNAL='@baseboard_fab2_lib.baseboard_fab2(sch_1):sata6g_p0_tx_c_dp';
NODE_NAME     J8A1 1D4
 '@BASEBOARD_FAB2_LIB.BASEBOARD_FAB2(SCH_1):PAGE173_I163@MSTR_CONN.CONN72_G97614002_A(CHIPS)':
 'TXA0_DP': CDS_PINID='TXA0_DP';
NODE_NAME     C2L39 1
 '@BASEBOARD_FAB2_LIB.BASEBOARD_FAB2(SCH_1):PAGE173_I221@DEV_DISCRETE.CAP_A(CHIPS)':
 'A': CDS_PINID='A';
NET_NAME
'SATA6G_P1_RX_C_DN'
 '@BASEBOARD_FAB2_LIB.BASEBOARD_FAB2(SCH_1):SATA6G_P1_RX_C_DN':
 C_SIGNAL='@baseboard_fab2_lib.baseboard_fab2(sch_1):sata6g_p1_rx_c_dn';
NODE_NAME     J8A1 1A5
 '@BASEBOARD_FAB2_LIB.BASEBOARD_FAB2(SCH_1):PAGE173_I163@MSTR_CONN.CONN72_G97614002_A(CHIPS)':
 'RXA1_DN': CDS_PINID='RXA1_DN';
NODE_NAME     C2L6 2
 '@BASEBOARD_FAB2_LIB.BASEBOARD_FAB2(SCH_1):PAGE173_I166@DEV_DISCRETE.CAP_A(CHIPS)':
 'B': CDS_PINID='B';
NET_NAME
'SATA6G_P1_RX_C_DP'
 '@BASEBOARD_FAB2_LIB.BASEBOARD_FAB2(SCH_1):SATA6G_P1_RX_C_DP':
 C_SIGNAL='@baseboard_fab2_lib.baseboard_fab2(sch_1):sata6g_p1_rx_c_dp';
NODE_NAME     J8A1 1A4
 '@BASEBOARD_FAB2_LIB.BASEBOARD_FAB2(SCH_1):PAGE173_I163@MSTR_CONN.CONN72_G97614002_A(CHIPS)':
 'RXA1_DP': CDS_PINID='RXA1_DP';
NODE_NAME     C2L10 2
 '@BASEBOARD_FAB2_LIB.BASEBOARD_FAB2(SCH_1):PAGE173_I173@DEV_DISCRETE.CAP_A(CHIPS)':
 'B': CDS_PINID='B';
NET_NAME
'SATA6G_P1_TX_C_DN'
 '@BASEBOARD_FAB2_LIB.BASEBOARD_FAB2(SCH_1):SATA6G_P1_TX_C_DN':
 C_SIGNAL='@baseboard_fab2_lib.baseboard_fab2(sch_1):sata6g_p1_tx_c_dn';
NODE_NAME     J8A1 1C5
 '@BASEBOARD_FAB2_LIB.BASEBOARD_FAB2(SCH_1):PAGE173_I163@MSTR_CONN.CONN72_G97614002_A(CHIPS)':
 'TXA1_DN': CDS_PINID='TXA1_DN';
NODE_NAME     C2L44 1
 '@BASEBOARD_FAB2_LIB.BASEBOARD_FAB2(SCH_1):PAGE173_I228@DEV_DISCRETE.CAP_A(CHIPS)':
 'A': CDS_PINID='A';
NET_NAME
'SATA6G_P1_TX_C_DP'
 '@BASEBOARD_FAB2_LIB.BASEBOARD_FAB2(SCH_1):SATA6G_P1_TX_C_DP':
 C_SIGNAL='@baseboard_fab2_lib.baseboard_fab2(sch_1):sata6g_p1_tx_c_dp';
NODE_NAME     J8A1 1C4
 '@BASEBOARD_FAB2_LIB.BASEBOARD_FAB2(SCH_1):PAGE173_I163@MSTR_CONN.CONN72_G97614002_A(CHIPS)':
 'TXA1_DP': CDS_PINID='TXA1_DP';
NODE_NAME     C2L43 1
 '@BASEBOARD_FAB2_LIB.BASEBOARD_FAB2(SCH_1):PAGE173_I222@DEV_DISCRETE.CAP_A(CHIPS)':
 'A': CDS_PINID='A';
NET_NAME
'SATA6G_P2_RX_C_DN'
 '@BASEBOARD_FAB2_LIB.BASEBOARD_FAB2(SCH_1):SATA6G_P2_RX_C_DN':
 C_SIGNAL='@baseboard_fab2_lib.baseboard_fab2(sch_1):sata6g_p2_rx_c_dn';
NODE_NAME     J8A1 1B8
 '@BASEBOARD_FAB2_LIB.BASEBOARD_FAB2(SCH_1):PAGE173_I163@MSTR_CONN.CONN72_G97614002_A(CHIPS)':
 'RXA2_DN': CDS_PINID='RXA2_DN';
NODE_NAME     C2L13 2
 '@BASEBOARD_FAB2_LIB.BASEBOARD_FAB2(SCH_1):PAGE173_I165@DEV_DISCRETE.CAP_A(CHIPS)':
 'B': CDS_PINID='B';
NET_NAME
'SATA6G_P2_RX_C_DP'
 '@BASEBOARD_FAB2_LIB.BASEBOARD_FAB2(SCH_1):SATA6G_P2_RX_C_DP':
 C_SIGNAL='@baseboard_fab2_lib.baseboard_fab2(sch_1):sata6g_p2_rx_c_dp';
NODE_NAME     J8A1 1B7
 '@BASEBOARD_FAB2_LIB.BASEBOARD_FAB2(SCH_1):PAGE173_I163@MSTR_CONN.CONN72_G97614002_A(CHIPS)':
 'RXA2_DP': CDS_PINID='RXA2_DP';
NODE_NAME     C2L15 2
 '@BASEBOARD_FAB2_LIB.BASEBOARD_FAB2(SCH_1):PAGE173_I191@DEV_DISCRETE.CAP_A(CHIPS)':
 'B': CDS_PINID='B';
NET_NAME
'SATA6G_P2_TX_C_DN'
 '@BASEBOARD_FAB2_LIB.BASEBOARD_FAB2(SCH_1):SATA6G_P2_TX_C_DN':
 C_SIGNAL='@baseboard_fab2_lib.baseboard_fab2(sch_1):sata6g_p2_tx_c_dn';
NODE_NAME     J8A1 1D8
 '@BASEBOARD_FAB2_LIB.BASEBOARD_FAB2(SCH_1):PAGE173_I163@MSTR_CONN.CONN72_G97614002_A(CHIPS)':
 'TXA2_DN': CDS_PINID='TXA2_DN';
NODE_NAME     C2L42 1
 '@BASEBOARD_FAB2_LIB.BASEBOARD_FAB2(SCH_1):PAGE173_I233@DEV_DISCRETE.CAP_A(CHIPS)':
 'A': CDS_PINID='A';
NET_NAME
'SATA6G_P2_TX_C_DP'
 '@BASEBOARD_FAB2_LIB.BASEBOARD_FAB2(SCH_1):SATA6G_P2_TX_C_DP':
 C_SIGNAL='@baseboard_fab2_lib.baseboard_fab2(sch_1):sata6g_p2_tx_c_dp';
NODE_NAME     J8A1 1D7
 '@BASEBOARD_FAB2_LIB.BASEBOARD_FAB2(SCH_1):PAGE173_I163@MSTR_CONN.CONN72_G97614002_A(CHIPS)':
 'TXA2_DP': CDS_PINID='TXA2_DP';
NODE_NAME     C2L41 1
 '@BASEBOARD_FAB2_LIB.BASEBOARD_FAB2(SCH_1):PAGE173_I242@DEV_DISCRETE.CAP_A(CHIPS)':
 'A': CDS_PINID='A';
NET_NAME
'SATA6G_P3_RX_C_DN'
 '@BASEBOARD_FAB2_LIB.BASEBOARD_FAB2(SCH_1):SATA6G_P3_RX_C_DN':
 C_SIGNAL='@baseboard_fab2_lib.baseboard_fab2(sch_1):sata6g_p3_rx_c_dn';
NODE_NAME     J8A1 1A8
 '@BASEBOARD_FAB2_LIB.BASEBOARD_FAB2(SCH_1):PAGE173_I163@MSTR_CONN.CONN72_G97614002_A(CHIPS)':
 'RXA3_DN': CDS_PINID='RXA3_DN';
NODE_NAME     C2L3 2
 '@BASEBOARD_FAB2_LIB.BASEBOARD_FAB2(SCH_1):PAGE173_I194@DEV_DISCRETE.CAP_A(CHIPS)':
 'B': CDS_PINID='B';
NET_NAME
'SATA6G_P3_RX_C_DP'
 '@BASEBOARD_FAB2_LIB.BASEBOARD_FAB2(SCH_1):SATA6G_P3_RX_C_DP':
 C_SIGNAL='@baseboard_fab2_lib.baseboard_fab2(sch_1):sata6g_p3_rx_c_dp';
NODE_NAME     J8A1 1A7
 '@BASEBOARD_FAB2_LIB.BASEBOARD_FAB2(SCH_1):PAGE173_I163@MSTR_CONN.CONN72_G97614002_A(CHIPS)':
 'RXA3_DP': CDS_PINID='RXA3_DP';
NODE_NAME     C2L4 2
 '@BASEBOARD_FAB2_LIB.BASEBOARD_FAB2(SCH_1):PAGE173_I192@DEV_DISCRETE.CAP_A(CHIPS)':
 'B': CDS_PINID='B';
NET_NAME
'SATA6G_P3_TX_C_DN'
 '@BASEBOARD_FAB2_LIB.BASEBOARD_FAB2(SCH_1):SATA6G_P3_TX_C_DN':
 C_SIGNAL='@baseboard_fab2_lib.baseboard_fab2(sch_1):sata6g_p3_tx_c_dn';
NODE_NAME     J8A1 1C8
 '@BASEBOARD_FAB2_LIB.BASEBOARD_FAB2(SCH_1):PAGE173_I163@MSTR_CONN.CONN72_G97614002_A(CHIPS)':
 'TXA3_DN': CDS_PINID='TXA3_DN';
NODE_NAME     C2L22 1
 '@BASEBOARD_FAB2_LIB.BASEBOARD_FAB2(SCH_1):PAGE173_I234@DEV_DISCRETE.CAP_A(CHIPS)':
 'A': CDS_PINID='A';
NET_NAME
'SATA6G_P3_TX_C_DP'
 '@BASEBOARD_FAB2_LIB.BASEBOARD_FAB2(SCH_1):SATA6G_P3_TX_C_DP':
 C_SIGNAL='@baseboard_fab2_lib.baseboard_fab2(sch_1):sata6g_p3_tx_c_dp';
NODE_NAME     J8A1 1C7
 '@BASEBOARD_FAB2_LIB.BASEBOARD_FAB2(SCH_1):PAGE173_I163@MSTR_CONN.CONN72_G97614002_A(CHIPS)':
 'TXA3_DP': CDS_PINID='TXA3_DP';
NODE_NAME     C2L23 1
 '@BASEBOARD_FAB2_LIB.BASEBOARD_FAB2(SCH_1):PAGE173_I241@DEV_DISCRETE.CAP_A(CHIPS)':
 'A': CDS_PINID='A';
NET_NAME
'SATA6G_P4_RX_C_DN'
 '@BASEBOARD_FAB2_LIB.BASEBOARD_FAB2(SCH_1):SATA6G_P4_RX_C_DN':
 C_SIGNAL='@baseboard_fab2_lib.baseboard_fab2(sch_1):sata6g_p4_rx_c_dn';
NODE_NAME     J8A1 2B5
 '@BASEBOARD_FAB2_LIB.BASEBOARD_FAB2(SCH_1):PAGE173_I163@MSTR_CONN.CONN72_G97614002_A(CHIPS)':
 'RXB0_DN': CDS_PINID='RXB0_DN';
NODE_NAME     C2L18 2
 '@BASEBOARD_FAB2_LIB.BASEBOARD_FAB2(SCH_1):PAGE173_I197@DEV_DISCRETE.CAP_A(CHIPS)':
 'B': CDS_PINID='B';
NET_NAME
'SATA6G_P4_RX_C_DP'
 '@BASEBOARD_FAB2_LIB.BASEBOARD_FAB2(SCH_1):SATA6G_P4_RX_C_DP':
 C_SIGNAL='@baseboard_fab2_lib.baseboard_fab2(sch_1):sata6g_p4_rx_c_dp';
NODE_NAME     J8A1 2B4
 '@BASEBOARD_FAB2_LIB.BASEBOARD_FAB2(SCH_1):PAGE173_I163@MSTR_CONN.CONN72_G97614002_A(CHIPS)':
 'RXB0_DP': CDS_PINID='RXB0_DP';
NODE_NAME     C2L20 2
 '@BASEBOARD_FAB2_LIB.BASEBOARD_FAB2(SCH_1):PAGE173_I195@DEV_DISCRETE.CAP_A(CHIPS)':
 'B': CDS_PINID='B';
NET_NAME
'SATA6G_P4_TX_C_DN'
 '@BASEBOARD_FAB2_LIB.BASEBOARD_FAB2(SCH_1):SATA6G_P4_TX_C_DN':
 C_SIGNAL='@baseboard_fab2_lib.baseboard_fab2(sch_1):sata6g_p4_tx_c_dn';
NODE_NAME     J8A1 2D5
 '@BASEBOARD_FAB2_LIB.BASEBOARD_FAB2(SCH_1):PAGE173_I163@MSTR_CONN.CONN72_G97614002_A(CHIPS)':
 'TXB0_DN': CDS_PINID='TXB0_DN';
NODE_NAME     C2L37 1
 '@BASEBOARD_FAB2_LIB.BASEBOARD_FAB2(SCH_1):PAGE173_I238@DEV_DISCRETE.CAP_A(CHIPS)':
 'A': CDS_PINID='A';
NET_NAME
'SATA6G_P4_TX_C_DP'
 '@BASEBOARD_FAB2_LIB.BASEBOARD_FAB2(SCH_1):SATA6G_P4_TX_C_DP':
 C_SIGNAL='@baseboard_fab2_lib.baseboard_fab2(sch_1):sata6g_p4_tx_c_dp';
NODE_NAME     J8A1 2D4
 '@BASEBOARD_FAB2_LIB.BASEBOARD_FAB2(SCH_1):PAGE173_I163@MSTR_CONN.CONN72_G97614002_A(CHIPS)':
 'TXB0_DP': CDS_PINID='TXB0_DP';
NODE_NAME     C2L47 1
 '@BASEBOARD_FAB2_LIB.BASEBOARD_FAB2(SCH_1):PAGE173_I239@DEV_DISCRETE.CAP_A(CHIPS)':
 'A': CDS_PINID='A';
NET_NAME
'SATA6G_P5_RX_C_DN'
 '@BASEBOARD_FAB2_LIB.BASEBOARD_FAB2(SCH_1):SATA6G_P5_RX_C_DN':
 C_SIGNAL='@baseboard_fab2_lib.baseboard_fab2(sch_1):sata6g_p5_rx_c_dn';
NODE_NAME     J8A1 2A5
 '@BASEBOARD_FAB2_LIB.BASEBOARD_FAB2(SCH_1):PAGE173_I163@MSTR_CONN.CONN72_G97614002_A(CHIPS)':
 'RXB1_DN': CDS_PINID='RXB1_DN';
NODE_NAME     C2L9 2
 '@BASEBOARD_FAB2_LIB.BASEBOARD_FAB2(SCH_1):PAGE173_I207@DEV_DISCRETE.CAP_A(CHIPS)':
 'B': CDS_PINID='B';
NET_NAME
'SATA6G_P5_RX_C_DP'
 '@BASEBOARD_FAB2_LIB.BASEBOARD_FAB2(SCH_1):SATA6G_P5_RX_C_DP':
 C_SIGNAL='@baseboard_fab2_lib.baseboard_fab2(sch_1):sata6g_p5_rx_c_dp';
NODE_NAME     J8A1 2A4
 '@BASEBOARD_FAB2_LIB.BASEBOARD_FAB2(SCH_1):PAGE173_I163@MSTR_CONN.CONN72_G97614002_A(CHIPS)':
 'RXB1_DP': CDS_PINID='RXB1_DP';
NODE_NAME     C2L12 2
 '@BASEBOARD_FAB2_LIB.BASEBOARD_FAB2(SCH_1):PAGE173_I196@DEV_DISCRETE.CAP_A(CHIPS)':
 'B': CDS_PINID='B';
NET_NAME
'SATA6G_P5_TX_C_DN'
 '@BASEBOARD_FAB2_LIB.BASEBOARD_FAB2(SCH_1):SATA6G_P5_TX_C_DN':
 C_SIGNAL='@baseboard_fab2_lib.baseboard_fab2(sch_1):sata6g_p5_tx_c_dn';
NODE_NAME     J8A1 2C5
 '@BASEBOARD_FAB2_LIB.BASEBOARD_FAB2(SCH_1):PAGE173_I163@MSTR_CONN.CONN72_G97614002_A(CHIPS)':
 'TXB1_DN': CDS_PINID='TXB1_DN';
NODE_NAME     C2L26 1
 '@BASEBOARD_FAB2_LIB.BASEBOARD_FAB2(SCH_1):PAGE173_I255@DEV_DISCRETE.CAP_A(CHIPS)':
 'A': CDS_PINID='A';
NET_NAME
'SATA6G_P5_TX_C_DP'
 '@BASEBOARD_FAB2_LIB.BASEBOARD_FAB2(SCH_1):SATA6G_P5_TX_C_DP':
 C_SIGNAL='@baseboard_fab2_lib.baseboard_fab2(sch_1):sata6g_p5_tx_c_dp';
NODE_NAME     J8A1 2C4
 '@BASEBOARD_FAB2_LIB.BASEBOARD_FAB2(SCH_1):PAGE173_I163@MSTR_CONN.CONN72_G97614002_A(CHIPS)':
 'TXB1_DP': CDS_PINID='TXB1_DP';
NODE_NAME     C2L27 1
 '@BASEBOARD_FAB2_LIB.BASEBOARD_FAB2(SCH_1):PAGE173_I240@DEV_DISCRETE.CAP_A(CHIPS)':
 'A': CDS_PINID='A';
NET_NAME
'SATA6G_P6_RX_C_DN'
 '@BASEBOARD_FAB2_LIB.BASEBOARD_FAB2(SCH_1):SATA6G_P6_RX_C_DN':
 C_SIGNAL='@baseboard_fab2_lib.baseboard_fab2(sch_1):sata6g_p6_rx_c_dn';
NODE_NAME     J8A1 2B8
 '@BASEBOARD_FAB2_LIB.BASEBOARD_FAB2(SCH_1):PAGE173_I163@MSTR_CONN.CONN72_G97614002_A(CHIPS)':
 'RXB2_DN': CDS_PINID='RXB2_DN';
NODE_NAME     C2L14 2
 '@BASEBOARD_FAB2_LIB.BASEBOARD_FAB2(SCH_1):PAGE173_I208@DEV_DISCRETE.CAP_A(CHIPS)':
 'B': CDS_PINID='B';
NET_NAME
'SATA6G_P6_RX_C_DP'
 '@BASEBOARD_FAB2_LIB.BASEBOARD_FAB2(SCH_1):SATA6G_P6_RX_C_DP':
 C_SIGNAL='@baseboard_fab2_lib.baseboard_fab2(sch_1):sata6g_p6_rx_c_dp';
NODE_NAME     J8A1 2B7
 '@BASEBOARD_FAB2_LIB.BASEBOARD_FAB2(SCH_1):PAGE173_I163@MSTR_CONN.CONN72_G97614002_A(CHIPS)':
 'RXB2_DP': CDS_PINID='RXB2_DP';
NODE_NAME     C2L16 2
 '@BASEBOARD_FAB2_LIB.BASEBOARD_FAB2(SCH_1):PAGE173_I205@DEV_DISCRETE.CAP_A(CHIPS)':
 'B': CDS_PINID='B';
NET_NAME
'SATA6G_P6_TX_C_DN'
 '@BASEBOARD_FAB2_LIB.BASEBOARD_FAB2(SCH_1):SATA6G_P6_TX_C_DN':
 C_SIGNAL='@baseboard_fab2_lib.baseboard_fab2(sch_1):sata6g_p6_tx_c_dn';
NODE_NAME     J8A1 2D8
 '@BASEBOARD_FAB2_LIB.BASEBOARD_FAB2(SCH_1):PAGE173_I163@MSTR_CONN.CONN72_G97614002_A(CHIPS)':
 'TXB2_DN': CDS_PINID='TXB2_DN';
NODE_NAME     C2L38 1
 '@BASEBOARD_FAB2_LIB.BASEBOARD_FAB2(SCH_1):PAGE173_I256@DEV_DISCRETE.CAP_A(CHIPS)':
 'A': CDS_PINID='A';
NET_NAME
'SATA6G_P6_TX_C_DP'
 '@BASEBOARD_FAB2_LIB.BASEBOARD_FAB2(SCH_1):SATA6G_P6_TX_C_DP':
 C_SIGNAL='@baseboard_fab2_lib.baseboard_fab2(sch_1):sata6g_p6_tx_c_dp';
NODE_NAME     J8A1 2D7
 '@BASEBOARD_FAB2_LIB.BASEBOARD_FAB2(SCH_1):PAGE173_I163@MSTR_CONN.CONN72_G97614002_A(CHIPS)':
 'TXB2_DP': CDS_PINID='TXB2_DP';
NODE_NAME     C2L48 1
 '@BASEBOARD_FAB2_LIB.BASEBOARD_FAB2(SCH_1):PAGE173_I257@DEV_DISCRETE.CAP_A(CHIPS)':
 'A': CDS_PINID='A';
NET_NAME
'SATA6G_P7_RX_C_DN'
 '@BASEBOARD_FAB2_LIB.BASEBOARD_FAB2(SCH_1):SATA6G_P7_RX_C_DN':
 C_SIGNAL='@baseboard_fab2_lib.baseboard_fab2(sch_1):sata6g_p7_rx_c_dn';
NODE_NAME     J8A1 2A8
 '@BASEBOARD_FAB2_LIB.BASEBOARD_FAB2(SCH_1):PAGE173_I163@MSTR_CONN.CONN72_G97614002_A(CHIPS)':
 'RXB3_DN': CDS_PINID='RXB3_DN';
NODE_NAME     C2L5 2
 '@BASEBOARD_FAB2_LIB.BASEBOARD_FAB2(SCH_1):PAGE173_I209@DEV_DISCRETE.CAP_A(CHIPS)':
 'B': CDS_PINID='B';
NET_NAME
'SATA6G_P7_RX_C_DP'
 '@BASEBOARD_FAB2_LIB.BASEBOARD_FAB2(SCH_1):SATA6G_P7_RX_C_DP':
 C_SIGNAL='@baseboard_fab2_lib.baseboard_fab2(sch_1):sata6g_p7_rx_c_dp';
NODE_NAME     J8A1 2A7
 '@BASEBOARD_FAB2_LIB.BASEBOARD_FAB2(SCH_1):PAGE173_I163@MSTR_CONN.CONN72_G97614002_A(CHIPS)':
 'RXB3_DP': CDS_PINID='RXB3_DP';
NODE_NAME     C2L7 2
 '@BASEBOARD_FAB2_LIB.BASEBOARD_FAB2(SCH_1):PAGE173_I206@DEV_DISCRETE.CAP_A(CHIPS)':
 'B': CDS_PINID='B';
NET_NAME
'SATA6G_P7_TX_C_DN'
 '@BASEBOARD_FAB2_LIB.BASEBOARD_FAB2(SCH_1):SATA6G_P7_TX_C_DN':
 C_SIGNAL='@baseboard_fab2_lib.baseboard_fab2(sch_1):sata6g_p7_tx_c_dn';
NODE_NAME     J8A1 2C8
 '@BASEBOARD_FAB2_LIB.BASEBOARD_FAB2(SCH_1):PAGE173_I163@MSTR_CONN.CONN72_G97614002_A(CHIPS)':
 'TXB3_DN': CDS_PINID='TXB3_DN';
NODE_NAME     C2L21 1
 '@BASEBOARD_FAB2_LIB.BASEBOARD_FAB2(SCH_1):PAGE173_I259@DEV_DISCRETE.CAP_A(CHIPS)':
 'A': CDS_PINID='A';
NET_NAME
'SATA6G_P7_TX_C_DP'
 '@BASEBOARD_FAB2_LIB.BASEBOARD_FAB2(SCH_1):SATA6G_P7_TX_C_DP':
 C_SIGNAL='@baseboard_fab2_lib.baseboard_fab2(sch_1):sata6g_p7_tx_c_dp';
NODE_NAME     J8A1 2C7
 '@BASEBOARD_FAB2_LIB.BASEBOARD_FAB2(SCH_1):PAGE173_I163@MSTR_CONN.CONN72_G97614002_A(CHIPS)':
 'TXB3_DP': CDS_PINID='TXB3_DP';
NODE_NAME     C2L24 1
 '@BASEBOARD_FAB2_LIB.BASEBOARD_FAB2(SCH_1):PAGE173_I258@DEV_DISCRETE.CAP_A(CHIPS)':
 'A': CDS_PINID='A';
NET_NAME
'SATA6G_PCH_PCIE_UP_SATA_RXN<0>'
 '@BASEBOARD_FAB2_LIB.BASEBOARD_FAB2(SCH_1):SATA6G_PCH_PCIE_UP_SATA_RXN'<0>:
 C_SIGNAL='@baseboard_fab2_lib.baseboard_fab2(sch_1):sata6g_pch_pcie_up_sata_rxn~
(0)';
NODE_NAME     U7C1 AR61
 '@BASEBOARD_FAB2_LIB.BASEBOARD_FAB2(SCH_1):PAGE116_I220@MSTR_U_PROC.LBG_CORE_QAT_EXT_D(CHIPS)':
 'PCIE12_UP0_SATA0_RXN': CDS_PINID='PCIE12_UP0_SATA0_RXN';
NODE_NAME     C2L17 1
 '@BASEBOARD_FAB2_LIB.BASEBOARD_FAB2(SCH_1):PAGE173_I174@DEV_DISCRETE.CAP_A(CHIPS)':
 'A': CDS_PINID='A';
NET_NAME
'SATA6G_PCH_PCIE_UP_SATA_RXN<1>'
 '@BASEBOARD_FAB2_LIB.BASEBOARD_FAB2(SCH_1):SATA6G_PCH_PCIE_UP_SATA_RXN'<1>:
 C_SIGNAL='@baseboard_fab2_lib.baseboard_fab2(sch_1):sata6g_pch_pcie_up_sata_rxn~
(1)';
NODE_NAME     U7C1 AL66
 '@BASEBOARD_FAB2_LIB.BASEBOARD_FAB2(SCH_1):PAGE116_I220@MSTR_U_PROC.LBG_CORE_QAT_EXT_D(CHIPS)':
 'PCIE13_UP1_SATA1_RXN': CDS_PINID='PCIE13_UP1_SATA1_RXN';
NODE_NAME     C2L6 1
 '@BASEBOARD_FAB2_LIB.BASEBOARD_FAB2(SCH_1):PAGE173_I166@DEV_DISCRETE.CAP_A(CHIPS)':
 'A': CDS_PINID='A';
NET_NAME
'SATA6G_PCH_PCIE_UP_SATA_RXN<2>'
 '@BASEBOARD_FAB2_LIB.BASEBOARD_FAB2(SCH_1):SATA6G_PCH_PCIE_UP_SATA_RXN'<2>:
 C_SIGNAL='@baseboard_fab2_lib.baseboard_fab2(sch_1):sata6g_pch_pcie_up_sata_rxn~
(2)';
NODE_NAME     U7C1 AK65
 '@BASEBOARD_FAB2_LIB.BASEBOARD_FAB2(SCH_1):PAGE116_I220@MSTR_U_PROC.LBG_CORE_QAT_EXT_D(CHIPS)':
 'PCIE14_UP2_SATA2_RXN': CDS_PINID='PCIE14_UP2_SATA2_RXN';
NODE_NAME     C2L13 1
 '@BASEBOARD_FAB2_LIB.BASEBOARD_FAB2(SCH_1):PAGE173_I165@DEV_DISCRETE.CAP_A(CHIPS)':
 'A': CDS_PINID='A';
NET_NAME
'SATA6G_PCH_PCIE_UP_SATA_RXN<3>'
 '@BASEBOARD_FAB2_LIB.BASEBOARD_FAB2(SCH_1):SATA6G_PCH_PCIE_UP_SATA_RXN'<3>:
 C_SIGNAL='@baseboard_fab2_lib.baseboard_fab2(sch_1):sata6g_pch_pcie_up_sata_rxn~
(3)';
NODE_NAME     U7C1 AP63
 '@BASEBOARD_FAB2_LIB.BASEBOARD_FAB2(SCH_1):PAGE116_I220@MSTR_U_PROC.LBG_CORE_QAT_EXT_D(CHIPS)':
 'PCIE15_UP3_SATA3_RXN': CDS_PINID='PCIE15_UP3_SATA3_RXN';
NODE_NAME     C2L3 1
 '@BASEBOARD_FAB2_LIB.BASEBOARD_FAB2(SCH_1):PAGE173_I194@DEV_DISCRETE.CAP_A(CHIPS)':
 'A': CDS_PINID='A';
NET_NAME
'SATA6G_PCH_PCIE_UP_SATA_RXN<4>'
 '@BASEBOARD_FAB2_LIB.BASEBOARD_FAB2(SCH_1):SATA6G_PCH_PCIE_UP_SATA_RXN'<4>:
 C_SIGNAL='@baseboard_fab2_lib.baseboard_fab2(sch_1):sata6g_pch_pcie_up_sata_rxn~
(4)';
NODE_NAME     U7C1 AF65
 '@BASEBOARD_FAB2_LIB.BASEBOARD_FAB2(SCH_1):PAGE116_I220@MSTR_U_PROC.LBG_CORE_QAT_EXT_D(CHIPS)':
 'PCIE16_UP4_SATA4_RXN': CDS_PINID='PCIE16_UP4_SATA4_RXN';
NODE_NAME     C2L18 1
 '@BASEBOARD_FAB2_LIB.BASEBOARD_FAB2(SCH_1):PAGE173_I197@DEV_DISCRETE.CAP_A(CHIPS)':
 'A': CDS_PINID='A';
NET_NAME
'SATA6G_PCH_PCIE_UP_SATA_RXN<5>'
 '@BASEBOARD_FAB2_LIB.BASEBOARD_FAB2(SCH_1):SATA6G_PCH_PCIE_UP_SATA_RXN'<5>:
 C_SIGNAL='@baseboard_fab2_lib.baseboard_fab2(sch_1):sata6g_pch_pcie_up_sata_rxn~
(5)';
NODE_NAME     U7C1 AH61
 '@BASEBOARD_FAB2_LIB.BASEBOARD_FAB2(SCH_1):PAGE116_I220@MSTR_U_PROC.LBG_CORE_QAT_EXT_D(CHIPS)':
 'PCIE17_UP5_SATA5_RXN': CDS_PINID='PCIE17_UP5_SATA5_RXN';
NODE_NAME     C2L9 1
 '@BASEBOARD_FAB2_LIB.BASEBOARD_FAB2(SCH_1):PAGE173_I207@DEV_DISCRETE.CAP_A(CHIPS)':
 'A': CDS_PINID='A';
NET_NAME
'SATA6G_PCH_PCIE_UP_SATA_RXN<6>'
 '@BASEBOARD_FAB2_LIB.BASEBOARD_FAB2(SCH_1):SATA6G_PCH_PCIE_UP_SATA_RXN'<6>:
 C_SIGNAL='@baseboard_fab2_lib.baseboard_fab2(sch_1):sata6g_pch_pcie_up_sata_rxn~
(6)';
NODE_NAME     U7C1 AP59
 '@BASEBOARD_FAB2_LIB.BASEBOARD_FAB2(SCH_1):PAGE116_I220@MSTR_U_PROC.LBG_CORE_QAT_EXT_D(CHIPS)':
 'PCIE18_UP6_SATA6_RXN': CDS_PINID='PCIE18_UP6_SATA6_RXN';
NODE_NAME     C2L14 1
 '@BASEBOARD_FAB2_LIB.BASEBOARD_FAB2(SCH_1):PAGE173_I208@DEV_DISCRETE.CAP_A(CHIPS)':
 'A': CDS_PINID='A';
NET_NAME
'SATA6G_PCH_PCIE_UP_SATA_RXN<7>'
 '@BASEBOARD_FAB2_LIB.BASEBOARD_FAB2(SCH_1):SATA6G_PCH_PCIE_UP_SATA_RXN'<7>:
 C_SIGNAL='@baseboard_fab2_lib.baseboard_fab2(sch_1):sata6g_pch_pcie_up_sata_rxn~
(7)';
NODE_NAME     U7C1 AA61
 '@BASEBOARD_FAB2_LIB.BASEBOARD_FAB2(SCH_1):PAGE116_I220@MSTR_U_PROC.LBG_CORE_QAT_EXT_D(CHIPS)':
 'PCIE19_UP7_SATA7_RXN': CDS_PINID='PCIE19_UP7_SATA7_RXN';
NODE_NAME     C2L5 1
 '@BASEBOARD_FAB2_LIB.BASEBOARD_FAB2(SCH_1):PAGE173_I209@DEV_DISCRETE.CAP_A(CHIPS)':
 'A': CDS_PINID='A';
NET_NAME
'SATA6G_PCH_PCIE_UP_SATA_RXP<0>'
 '@BASEBOARD_FAB2_LIB.BASEBOARD_FAB2(SCH_1):SATA6G_PCH_PCIE_UP_SATA_RXP'<0>:
 C_SIGNAL='@baseboard_fab2_lib.baseboard_fab2(sch_1):sata6g_pch_pcie_up_sata_rxp~
(0)';
NODE_NAME     U7C1 AT63
 '@BASEBOARD_FAB2_LIB.BASEBOARD_FAB2(SCH_1):PAGE116_I220@MSTR_U_PROC.LBG_CORE_QAT_EXT_D(CHIPS)':
 'PCIE12_UP0_SATA0_RXP': CDS_PINID='PCIE12_UP0_SATA0_RXP';
NODE_NAME     C2L19 1
 '@BASEBOARD_FAB2_LIB.BASEBOARD_FAB2(SCH_1):PAGE173_I172@DEV_DISCRETE.CAP_A(CHIPS)':
 'A': CDS_PINID='A';
NET_NAME
'SATA6G_PCH_PCIE_UP_SATA_RXP<1>'
 '@BASEBOARD_FAB2_LIB.BASEBOARD_FAB2(SCH_1):SATA6G_PCH_PCIE_UP_SATA_RXP'<1>:
 C_SIGNAL='@baseboard_fab2_lib.baseboard_fab2(sch_1):sata6g_pch_pcie_up_sata_rxp~
(1)';
NODE_NAME     U7C1 AN65
 '@BASEBOARD_FAB2_LIB.BASEBOARD_FAB2(SCH_1):PAGE116_I220@MSTR_U_PROC.LBG_CORE_QAT_EXT_D(CHIPS)':
 'PCIE13_UP1_SATA1_RXP': CDS_PINID='PCIE13_UP1_SATA1_RXP';
NODE_NAME     C2L10 1
 '@BASEBOARD_FAB2_LIB.BASEBOARD_FAB2(SCH_1):PAGE173_I173@DEV_DISCRETE.CAP_A(CHIPS)':
 'A': CDS_PINID='A';
NET_NAME
'SATA6G_PCH_PCIE_UP_SATA_RXP<2>'
 '@BASEBOARD_FAB2_LIB.BASEBOARD_FAB2(SCH_1):SATA6G_PCH_PCIE_UP_SATA_RXP'<2>:
 C_SIGNAL='@baseboard_fab2_lib.baseboard_fab2(sch_1):sata6g_pch_pcie_up_sata_rxp~
(2)';
NODE_NAME     U7C1 AJ63
 '@BASEBOARD_FAB2_LIB.BASEBOARD_FAB2(SCH_1):PAGE116_I220@MSTR_U_PROC.LBG_CORE_QAT_EXT_D(CHIPS)':
 'PCIE14_UP2_SATA2_RXP': CDS_PINID='PCIE14_UP2_SATA2_RXP';
NODE_NAME     C2L15 1
 '@BASEBOARD_FAB2_LIB.BASEBOARD_FAB2(SCH_1):PAGE173_I191@DEV_DISCRETE.CAP_A(CHIPS)':
 'A': CDS_PINID='A';
NET_NAME
'SATA6G_PCH_PCIE_UP_SATA_RXP<3>'
 '@BASEBOARD_FAB2_LIB.BASEBOARD_FAB2(SCH_1):SATA6G_PCH_PCIE_UP_SATA_RXP'<3>:
 C_SIGNAL='@baseboard_fab2_lib.baseboard_fab2(sch_1):sata6g_pch_pcie_up_sata_rxp~
(3)';
NODE_NAME     U7C1 AL63
 '@BASEBOARD_FAB2_LIB.BASEBOARD_FAB2(SCH_1):PAGE116_I220@MSTR_U_PROC.LBG_CORE_QAT_EXT_D(CHIPS)':
 'PCIE15_UP3_SATA3_RXP': CDS_PINID='PCIE15_UP3_SATA3_RXP';
NODE_NAME     C2L4 1
 '@BASEBOARD_FAB2_LIB.BASEBOARD_FAB2(SCH_1):PAGE173_I192@DEV_DISCRETE.CAP_A(CHIPS)':
 'A': CDS_PINID='A';
NET_NAME
'SATA6G_PCH_PCIE_UP_SATA_RXP<4>'
 '@BASEBOARD_FAB2_LIB.BASEBOARD_FAB2(SCH_1):SATA6G_PCH_PCIE_UP_SATA_RXP'<4>:
 C_SIGNAL='@baseboard_fab2_lib.baseboard_fab2(sch_1):sata6g_pch_pcie_up_sata_rxp~
(4)';
NODE_NAME     U7C1 AH65
 '@BASEBOARD_FAB2_LIB.BASEBOARD_FAB2(SCH_1):PAGE116_I220@MSTR_U_PROC.LBG_CORE_QAT_EXT_D(CHIPS)':
 'PCIE16_UP4_SATA4_RXP': CDS_PINID='PCIE16_UP4_SATA4_RXP';
NODE_NAME     C2L20 1
 '@BASEBOARD_FAB2_LIB.BASEBOARD_FAB2(SCH_1):PAGE173_I195@DEV_DISCRETE.CAP_A(CHIPS)':
 'A': CDS_PINID='A';
NET_NAME
'SATA6G_PCH_PCIE_UP_SATA_RXP<5>'
 '@BASEBOARD_FAB2_LIB.BASEBOARD_FAB2(SCH_1):SATA6G_PCH_PCIE_UP_SATA_RXP'<5>:
 C_SIGNAL='@baseboard_fab2_lib.baseboard_fab2(sch_1):sata6g_pch_pcie_up_sata_rxp~
(5)';
NODE_NAME     U7C1 AG63
 '@BASEBOARD_FAB2_LIB.BASEBOARD_FAB2(SCH_1):PAGE116_I220@MSTR_U_PROC.LBG_CORE_QAT_EXT_D(CHIPS)':
 'PCIE17_UP5_SATA5_RXP': CDS_PINID='PCIE17_UP5_SATA5_RXP';
NODE_NAME     C2L12 1
 '@BASEBOARD_FAB2_LIB.BASEBOARD_FAB2(SCH_1):PAGE173_I196@DEV_DISCRETE.CAP_A(CHIPS)':
 'A': CDS_PINID='A';
NET_NAME
'SATA6G_PCH_PCIE_UP_SATA_RXP<6>'
 '@BASEBOARD_FAB2_LIB.BASEBOARD_FAB2(SCH_1):SATA6G_PCH_PCIE_UP_SATA_RXP'<6>:
 C_SIGNAL='@baseboard_fab2_lib.baseboard_fab2(sch_1):sata6g_pch_pcie_up_sata_rxp~
(6)';
NODE_NAME     U7C1 AN61
 '@BASEBOARD_FAB2_LIB.BASEBOARD_FAB2(SCH_1):PAGE116_I220@MSTR_U_PROC.LBG_CORE_QAT_EXT_D(CHIPS)':
 'PCIE18_UP6_SATA6_RXP': CDS_PINID='PCIE18_UP6_SATA6_RXP';
NODE_NAME     C2L16 1
 '@BASEBOARD_FAB2_LIB.BASEBOARD_FAB2(SCH_1):PAGE173_I205@DEV_DISCRETE.CAP_A(CHIPS)':
 'A': CDS_PINID='A';
NET_NAME
'SATA6G_PCH_PCIE_UP_SATA_RXP<7>'
 '@BASEBOARD_FAB2_LIB.BASEBOARD_FAB2(SCH_1):SATA6G_PCH_PCIE_UP_SATA_RXP'<7>:
 C_SIGNAL='@baseboard_fab2_lib.baseboard_fab2(sch_1):sata6g_pch_pcie_up_sata_rxp~
(7)';
NODE_NAME     U7C1 AD61
 '@BASEBOARD_FAB2_LIB.BASEBOARD_FAB2(SCH_1):PAGE116_I220@MSTR_U_PROC.LBG_CORE_QAT_EXT_D(CHIPS)':
 'PCIE19_UP7_SATA7_RXP': CDS_PINID='PCIE19_UP7_SATA7_RXP';
NODE_NAME     C2L7 1
 '@BASEBOARD_FAB2_LIB.BASEBOARD_FAB2(SCH_1):PAGE173_I206@DEV_DISCRETE.CAP_A(CHIPS)':
 'A': CDS_PINID='A';
NET_NAME
'SATA6G_PCH_PCIE_UP_SATA_TXN<0>'
 '@BASEBOARD_FAB2_LIB.BASEBOARD_FAB2(SCH_1):SATA6G_PCH_PCIE_UP_SATA_TXN'<0>:
 C_SIGNAL='@baseboard_fab2_lib.baseboard_fab2(sch_1):sata6g_pch_pcie_up_sata_txn~
(0)';
NODE_NAME     U7C1 W69
 '@BASEBOARD_FAB2_LIB.BASEBOARD_FAB2(SCH_1):PAGE116_I220@MSTR_U_PROC.LBG_CORE_QAT_EXT_D(CHIPS)':
 'PCIE12_UP0_SATA0_TXN': CDS_PINID='PCIE12_UP0_SATA0_TXN';
NODE_NAME     C2L40 2
 '@BASEBOARD_FAB2_LIB.BASEBOARD_FAB2(SCH_1):PAGE173_I220@DEV_DISCRETE.CAP_A(CHIPS)':
 'B': CDS_PINID='B';
NET_NAME
'SATA6G_PCH_PCIE_UP_SATA_TXN<1>'
 '@BASEBOARD_FAB2_LIB.BASEBOARD_FAB2(SCH_1):SATA6G_PCH_PCIE_UP_SATA_TXN'<1>:
 C_SIGNAL='@baseboard_fab2_lib.baseboard_fab2(sch_1):sata6g_pch_pcie_up_sata_txn~
(1)';
NODE_NAME     U7C1 V70
 '@BASEBOARD_FAB2_LIB.BASEBOARD_FAB2(SCH_1):PAGE116_I220@MSTR_U_PROC.LBG_CORE_QAT_EXT_D(CHIPS)':
 'PCIE13_UP1_SATA1_TXN': CDS_PINID='PCIE13_UP1_SATA1_TXN';
NODE_NAME     C2L44 2
 '@BASEBOARD_FAB2_LIB.BASEBOARD_FAB2(SCH_1):PAGE173_I228@DEV_DISCRETE.CAP_A(CHIPS)':
 'B': CDS_PINID='B';
NET_NAME
'SATA6G_PCH_PCIE_UP_SATA_TXN<2>'
 '@BASEBOARD_FAB2_LIB.BASEBOARD_FAB2(SCH_1):SATA6G_PCH_PCIE_UP_SATA_TXN'<2>:
 C_SIGNAL='@baseboard_fab2_lib.baseboard_fab2(sch_1):sata6g_pch_pcie_up_sata_txn~
(2)';
NODE_NAME     U7C1 T69
 '@BASEBOARD_FAB2_LIB.BASEBOARD_FAB2(SCH_1):PAGE116_I220@MSTR_U_PROC.LBG_CORE_QAT_EXT_D(CHIPS)':
 'PCIE14_UP2_SATA2_TXN': CDS_PINID='PCIE14_UP2_SATA2_TXN';
NODE_NAME     C2L42 2
 '@BASEBOARD_FAB2_LIB.BASEBOARD_FAB2(SCH_1):PAGE173_I233@DEV_DISCRETE.CAP_A(CHIPS)':
 'B': CDS_PINID='B';
NET_NAME
'SATA6G_PCH_PCIE_UP_SATA_TXN<3>'
 '@BASEBOARD_FAB2_LIB.BASEBOARD_FAB2(SCH_1):SATA6G_PCH_PCIE_UP_SATA_TXN'<3>:
 C_SIGNAL='@baseboard_fab2_lib.baseboard_fab2(sch_1):sata6g_pch_pcie_up_sata_txn~
(3)';
NODE_NAME     U7C1 R70
 '@BASEBOARD_FAB2_LIB.BASEBOARD_FAB2(SCH_1):PAGE116_I220@MSTR_U_PROC.LBG_CORE_QAT_EXT_D(CHIPS)':
 'PCIE15_UP3_SATA3_TXN': CDS_PINID='PCIE15_UP3_SATA3_TXN';
NODE_NAME     C2L22 2
 '@BASEBOARD_FAB2_LIB.BASEBOARD_FAB2(SCH_1):PAGE173_I234@DEV_DISCRETE.CAP_A(CHIPS)':
 'B': CDS_PINID='B';
NET_NAME
'SATA6G_PCH_PCIE_UP_SATA_TXN<4>'
 '@BASEBOARD_FAB2_LIB.BASEBOARD_FAB2(SCH_1):SATA6G_PCH_PCIE_UP_SATA_TXN'<4>:
 C_SIGNAL='@baseboard_fab2_lib.baseboard_fab2(sch_1):sata6g_pch_pcie_up_sata_txn~
(4)';
NODE_NAME     U7C1 P69
 '@BASEBOARD_FAB2_LIB.BASEBOARD_FAB2(SCH_1):PAGE116_I220@MSTR_U_PROC.LBG_CORE_QAT_EXT_D(CHIPS)':
 'PCIE16_UP4_SATA4_TXN': CDS_PINID='PCIE16_UP4_SATA4_TXN';
NODE_NAME     C2L37 2
 '@BASEBOARD_FAB2_LIB.BASEBOARD_FAB2(SCH_1):PAGE173_I238@DEV_DISCRETE.CAP_A(CHIPS)':
 'B': CDS_PINID='B';
NET_NAME
'SATA6G_PCH_PCIE_UP_SATA_TXN<5>'
 '@BASEBOARD_FAB2_LIB.BASEBOARD_FAB2(SCH_1):SATA6G_PCH_PCIE_UP_SATA_TXN'<5>:
 C_SIGNAL='@baseboard_fab2_lib.baseboard_fab2(sch_1):sata6g_pch_pcie_up_sata_txn~
(5)';
NODE_NAME     U7C1 N70
 '@BASEBOARD_FAB2_LIB.BASEBOARD_FAB2(SCH_1):PAGE116_I220@MSTR_U_PROC.LBG_CORE_QAT_EXT_D(CHIPS)':
 'PCIE17_UP5_SATA5_TXN': CDS_PINID='PCIE17_UP5_SATA5_TXN';
NODE_NAME     C2L26 2
 '@BASEBOARD_FAB2_LIB.BASEBOARD_FAB2(SCH_1):PAGE173_I255@DEV_DISCRETE.CAP_A(CHIPS)':
 'B': CDS_PINID='B';
NET_NAME
'SATA6G_PCH_PCIE_UP_SATA_TXN<6>'
 '@BASEBOARD_FAB2_LIB.BASEBOARD_FAB2(SCH_1):SATA6G_PCH_PCIE_UP_SATA_TXN'<6>:
 C_SIGNAL='@baseboard_fab2_lib.baseboard_fab2(sch_1):sata6g_pch_pcie_up_sata_txn~
(6)';
NODE_NAME     U7C1 M69
 '@BASEBOARD_FAB2_LIB.BASEBOARD_FAB2(SCH_1):PAGE116_I220@MSTR_U_PROC.LBG_CORE_QAT_EXT_D(CHIPS)':
 'PCIE18_UP6_SATA6_TXN': CDS_PINID='PCIE18_UP6_SATA6_TXN';
NODE_NAME     C2L38 2
 '@BASEBOARD_FAB2_LIB.BASEBOARD_FAB2(SCH_1):PAGE173_I256@DEV_DISCRETE.CAP_A(CHIPS)':
 'B': CDS_PINID='B';
NET_NAME
'SATA6G_PCH_PCIE_UP_SATA_TXN<7>'
 '@BASEBOARD_FAB2_LIB.BASEBOARD_FAB2(SCH_1):SATA6G_PCH_PCIE_UP_SATA_TXN'<7>:
 C_SIGNAL='@baseboard_fab2_lib.baseboard_fab2(sch_1):sata6g_pch_pcie_up_sata_txn~
(7)';
NODE_NAME     U7C1 L70
 '@BASEBOARD_FAB2_LIB.BASEBOARD_FAB2(SCH_1):PAGE116_I220@MSTR_U_PROC.LBG_CORE_QAT_EXT_D(CHIPS)':
 'PCIE19_UP7_SATA7_TXN': CDS_PINID='PCIE19_UP7_SATA7_TXN';
NODE_NAME     C2L21 2
 '@BASEBOARD_FAB2_LIB.BASEBOARD_FAB2(SCH_1):PAGE173_I259@DEV_DISCRETE.CAP_A(CHIPS)':
 'B': CDS_PINID='B';
NET_NAME
'SATA6G_PCH_PCIE_UP_SATA_TXP<0>'
 '@BASEBOARD_FAB2_LIB.BASEBOARD_FAB2(SCH_1):SATA6G_PCH_PCIE_UP_SATA_TXP'<0>:
 C_SIGNAL='@baseboard_fab2_lib.baseboard_fab2(sch_1):sata6g_pch_pcie_up_sata_txp~
(0)';
NODE_NAME     U7C1 W71
 '@BASEBOARD_FAB2_LIB.BASEBOARD_FAB2(SCH_1):PAGE116_I220@MSTR_U_PROC.LBG_CORE_QAT_EXT_D(CHIPS)':
 'PCIE12_UP0_SATA0_TXP': CDS_PINID='PCIE12_UP0_SATA0_TXP';
NODE_NAME     C2L39 2
 '@BASEBOARD_FAB2_LIB.BASEBOARD_FAB2(SCH_1):PAGE173_I221@DEV_DISCRETE.CAP_A(CHIPS)':
 'B': CDS_PINID='B';
NET_NAME
'SATA6G_PCH_PCIE_UP_SATA_TXP<1>'
 '@BASEBOARD_FAB2_LIB.BASEBOARD_FAB2(SCH_1):SATA6G_PCH_PCIE_UP_SATA_TXP'<1>:
 C_SIGNAL='@baseboard_fab2_lib.baseboard_fab2(sch_1):sata6g_pch_pcie_up_sata_txp~
(1)';
NODE_NAME     U7C1 V72
 '@BASEBOARD_FAB2_LIB.BASEBOARD_FAB2(SCH_1):PAGE116_I220@MSTR_U_PROC.LBG_CORE_QAT_EXT_D(CHIPS)':
 'PCIE13_UP1_SATA1_TXP': CDS_PINID='PCIE13_UP1_SATA1_TXP';
NODE_NAME     C2L43 2
 '@BASEBOARD_FAB2_LIB.BASEBOARD_FAB2(SCH_1):PAGE173_I222@DEV_DISCRETE.CAP_A(CHIPS)':
 'B': CDS_PINID='B';
NET_NAME
'SATA6G_PCH_PCIE_UP_SATA_TXP<2>'
 '@BASEBOARD_FAB2_LIB.BASEBOARD_FAB2(SCH_1):SATA6G_PCH_PCIE_UP_SATA_TXP'<2>:
 C_SIGNAL='@baseboard_fab2_lib.baseboard_fab2(sch_1):sata6g_pch_pcie_up_sata_txp~
(2)';
NODE_NAME     U7C1 T71
 '@BASEBOARD_FAB2_LIB.BASEBOARD_FAB2(SCH_1):PAGE116_I220@MSTR_U_PROC.LBG_CORE_QAT_EXT_D(CHIPS)':
 'PCIE14_UP2_SATA2_TXP': CDS_PINID='PCIE14_UP2_SATA2_TXP';
NODE_NAME     C2L41 2
 '@BASEBOARD_FAB2_LIB.BASEBOARD_FAB2(SCH_1):PAGE173_I242@DEV_DISCRETE.CAP_A(CHIPS)':
 'B': CDS_PINID='B';
NET_NAME
'SATA6G_PCH_PCIE_UP_SATA_TXP<3>'
 '@BASEBOARD_FAB2_LIB.BASEBOARD_FAB2(SCH_1):SATA6G_PCH_PCIE_UP_SATA_TXP'<3>:
 C_SIGNAL='@baseboard_fab2_lib.baseboard_fab2(sch_1):sata6g_pch_pcie_up_sata_txp~
(3)';
NODE_NAME     U7C1 R72
 '@BASEBOARD_FAB2_LIB.BASEBOARD_FAB2(SCH_1):PAGE116_I220@MSTR_U_PROC.LBG_CORE_QAT_EXT_D(CHIPS)':
 'PCIE15_UP3_SATA3_TXP': CDS_PINID='PCIE15_UP3_SATA3_TXP';
NODE_NAME     C2L23 2
 '@BASEBOARD_FAB2_LIB.BASEBOARD_FAB2(SCH_1):PAGE173_I241@DEV_DISCRETE.CAP_A(CHIPS)':
 'B': CDS_PINID='B';
NET_NAME
'SATA6G_PCH_PCIE_UP_SATA_TXP<4>'
 '@BASEBOARD_FAB2_LIB.BASEBOARD_FAB2(SCH_1):SATA6G_PCH_PCIE_UP_SATA_TXP'<4>:
 C_SIGNAL='@baseboard_fab2_lib.baseboard_fab2(sch_1):sata6g_pch_pcie_up_sata_txp~
(4)';
NODE_NAME     U7C1 P71
 '@BASEBOARD_FAB2_LIB.BASEBOARD_FAB2(SCH_1):PAGE116_I220@MSTR_U_PROC.LBG_CORE_QAT_EXT_D(CHIPS)':
 'PCIE16_UP4_SATA4_TXP': CDS_PINID='PCIE16_UP4_SATA4_TXP';
NODE_NAME     C2L47 2
 '@BASEBOARD_FAB2_LIB.BASEBOARD_FAB2(SCH_1):PAGE173_I239@DEV_DISCRETE.CAP_A(CHIPS)':
 'B': CDS_PINID='B';
NET_NAME
'SATA6G_PCH_PCIE_UP_SATA_TXP<5>'
 '@BASEBOARD_FAB2_LIB.BASEBOARD_FAB2(SCH_1):SATA6G_PCH_PCIE_UP_SATA_TXP'<5>:
 C_SIGNAL='@baseboard_fab2_lib.baseboard_fab2(sch_1):sata6g_pch_pcie_up_sata_txp~
(5)';
NODE_NAME     U7C1 N72
 '@BASEBOARD_FAB2_LIB.BASEBOARD_FAB2(SCH_1):PAGE116_I220@MSTR_U_PROC.LBG_CORE_QAT_EXT_D(CHIPS)':
 'PCIE17_UP5_SATA5_TXP': CDS_PINID='PCIE17_UP5_SATA5_TXP';
NODE_NAME     C2L27 2
 '@BASEBOARD_FAB2_LIB.BASEBOARD_FAB2(SCH_1):PAGE173_I240@DEV_DISCRETE.CAP_A(CHIPS)':
 'B': CDS_PINID='B';
NET_NAME
'SATA6G_PCH_PCIE_UP_SATA_TXP<6>'
 '@BASEBOARD_FAB2_LIB.BASEBOARD_FAB2(SCH_1):SATA6G_PCH_PCIE_UP_SATA_TXP'<6>:
 C_SIGNAL='@baseboard_fab2_lib.baseboard_fab2(sch_1):sata6g_pch_pcie_up_sata_txp~
(6)';
NODE_NAME     U7C1 M71
 '@BASEBOARD_FAB2_LIB.BASEBOARD_FAB2(SCH_1):PAGE116_I220@MSTR_U_PROC.LBG_CORE_QAT_EXT_D(CHIPS)':
 'PCIE18_UP6_SATA6_TXP': CDS_PINID='PCIE18_UP6_SATA6_TXP';
NODE_NAME     C2L48 2
 '@BASEBOARD_FAB2_LIB.BASEBOARD_FAB2(SCH_1):PAGE173_I257@DEV_DISCRETE.CAP_A(CHIPS)':
 'B': CDS_PINID='B';
NET_NAME
'SATA6G_PCH_PCIE_UP_SATA_TXP<7>'
 '@BASEBOARD_FAB2_LIB.BASEBOARD_FAB2(SCH_1):SATA6G_PCH_PCIE_UP_SATA_TXP'<7>:
 C_SIGNAL='@baseboard_fab2_lib.baseboard_fab2(sch_1):sata6g_pch_pcie_up_sata_txp~
(7)';
NODE_NAME     U7C1 L72
 '@BASEBOARD_FAB2_LIB.BASEBOARD_FAB2(SCH_1):PAGE116_I220@MSTR_U_PROC.LBG_CORE_QAT_EXT_D(CHIPS)':
 'PCIE19_UP7_SATA7_TXP': CDS_PINID='PCIE19_UP7_SATA7_TXP';
NODE_NAME     C2L24 2
 '@BASEBOARD_FAB2_LIB.BASEBOARD_FAB2(SCH_1):PAGE173_I258@DEV_DISCRETE.CAP_A(CHIPS)':
 'B': CDS_PINID='B';
NET_NAME
'SATA6G_S0_RX_DN'
 '@BASEBOARD_FAB2_LIB.BASEBOARD_FAB2(SCH_1):SATA6G_S0_RX_DN':
 C_SIGNAL='@baseboard_fab2_lib.baseboard_fab2(sch_1):sata6g_s0_rx_dn';
NODE_NAME     U7C1 BB63
 '@BASEBOARD_FAB2_LIB.BASEBOARD_FAB2(SCH_1):PAGE116_I220@MSTR_U_PROC.LBG_CORE_QAT_EXT_D(CHIPS)':
 'PCIE6_SSATA0_RXN': CDS_PINID='PCIE6_SSATA0_RXN';
NODE_NAME     C8F15 1
 '@BASEBOARD_FAB2_LIB.BASEBOARD_FAB2(SCH_1):PAGE185_I142@DEV_DISCRETE.CAP_A(CHIPS)':
 'A': CDS_PINID='A';
NET_NAME
'SATA6G_S0_RX_DP'
 '@BASEBOARD_FAB2_LIB.BASEBOARD_FAB2(SCH_1):SATA6G_S0_RX_DP':
 C_SIGNAL='@baseboard_fab2_lib.baseboard_fab2(sch_1):sata6g_s0_rx_dp';
NODE_NAME     U7C1 BD61
 '@BASEBOARD_FAB2_LIB.BASEBOARD_FAB2(SCH_1):PAGE116_I220@MSTR_U_PROC.LBG_CORE_QAT_EXT_D(CHIPS)':
 'PCIE6_SSATA0_RXP': CDS_PINID='PCIE6_SSATA0_RXP';
NODE_NAME     C8F13 1
 '@BASEBOARD_FAB2_LIB.BASEBOARD_FAB2(SCH_1):PAGE185_I141@DEV_DISCRETE.CAP_A(CHIPS)':
 'A': CDS_PINID='A';
NET_NAME
'SATA6G_S0_TX_DN'
 '@BASEBOARD_FAB2_LIB.BASEBOARD_FAB2(SCH_1):SATA6G_S0_TX_DN':
 C_SIGNAL='@baseboard_fab2_lib.baseboard_fab2(sch_1):sata6g_s0_tx_dn';
NODE_NAME     U7C1 AJ70
 '@BASEBOARD_FAB2_LIB.BASEBOARD_FAB2(SCH_1):PAGE116_I220@MSTR_U_PROC.LBG_CORE_QAT_EXT_D(CHIPS)':
 'PCIE6_SSATA0_TXN': CDS_PINID='PCIE6_SSATA0_TXN';
NODE_NAME     C8F11 1
 '@BASEBOARD_FAB2_LIB.BASEBOARD_FAB2(SCH_1):PAGE185_I139@DEV_DISCRETE.CAP_A(CHIPS)':
 'A': CDS_PINID='A';
NET_NAME
'SATA6G_S0_TX_DP'
 '@BASEBOARD_FAB2_LIB.BASEBOARD_FAB2(SCH_1):SATA6G_S0_TX_DP':
 C_SIGNAL='@baseboard_fab2_lib.baseboard_fab2(sch_1):sata6g_s0_tx_dp';
NODE_NAME     U7C1 AJ72
 '@BASEBOARD_FAB2_LIB.BASEBOARD_FAB2(SCH_1):PAGE116_I220@MSTR_U_PROC.LBG_CORE_QAT_EXT_D(CHIPS)':
 'PCIE6_SSATA0_TXP': CDS_PINID='PCIE6_SSATA0_TXP';
NODE_NAME     C8F6 1
 '@BASEBOARD_FAB2_LIB.BASEBOARD_FAB2(SCH_1):PAGE185_I138@DEV_DISCRETE.CAP_A(CHIPS)':
 'A': CDS_PINID='A';
NET_NAME
'SATA6G_S1_RX_C_DN'
 '@BASEBOARD_FAB2_LIB.BASEBOARD_FAB2(SCH_1):SATA6G_S1_RX_C_DN':
 C_SIGNAL='@baseboard_fab2_lib.baseboard_fab2(sch_1):sata6g_s1_rx_c_dn';
NODE_NAME     C2L50 1
 '@BASEBOARD_FAB2_LIB.BASEBOARD_FAB2(SCH_1):PAGE172_I7@DEV_DISCRETE.CAP_A(CHIPS)':
 'A': CDS_PINID='A';
NODE_NAME     J2W1 S5
 '@BASEBOARD_FAB2_LIB.BASEBOARD_FAB2(SCH_1):PAGE172_I67@W_HDL.SKT-SATA7P-6P-165-GP-U1(CHIPS)':
 'S5': CDS_PINID='S5';
NODE_NAME     J2W2 S5
 '@BASEBOARD_FAB2_LIB.BASEBOARD_FAB2(SCH_1):PAGE172_I68@W_HDL.SKT-SATA7P-6P-165-GP-U1(CHIPS)':
 'S5': CDS_PINID='S5';
NET_NAME
'SATA6G_S1_RX_C_DP'
 '@BASEBOARD_FAB2_LIB.BASEBOARD_FAB2(SCH_1):SATA6G_S1_RX_C_DP':
 C_SIGNAL='@baseboard_fab2_lib.baseboard_fab2(sch_1):sata6g_s1_rx_c_dp';
NODE_NAME     C2L49 1
 '@BASEBOARD_FAB2_LIB.BASEBOARD_FAB2(SCH_1):PAGE172_I5@DEV_DISCRETE.CAP_A(CHIPS)':
 'A': CDS_PINID='A';
NODE_NAME     J2W1 S6
 '@BASEBOARD_FAB2_LIB.BASEBOARD_FAB2(SCH_1):PAGE172_I67@W_HDL.SKT-SATA7P-6P-165-GP-U1(CHIPS)':
 'S6': CDS_PINID='S6';
NODE_NAME     J2W2 S6
 '@BASEBOARD_FAB2_LIB.BASEBOARD_FAB2(SCH_1):PAGE172_I68@W_HDL.SKT-SATA7P-6P-165-GP-U1(CHIPS)':
 'S6': CDS_PINID='S6';
NET_NAME
'SATA6G_S1_RX_DN'
 '@BASEBOARD_FAB2_LIB.BASEBOARD_FAB2(SCH_1):SATA6G_S1_RX_DN':
 C_SIGNAL='@baseboard_fab2_lib.baseboard_fab2(sch_1):sata6g_s1_rx_dn';
NODE_NAME     U7C1 AY59
 '@BASEBOARD_FAB2_LIB.BASEBOARD_FAB2(SCH_1):PAGE116_I220@MSTR_U_PROC.LBG_CORE_QAT_EXT_D(CHIPS)':
 'PCIE7_SSATA1_RXN': CDS_PINID='PCIE7_SSATA1_RXN';
NODE_NAME     C2L50 2
 '@BASEBOARD_FAB2_LIB.BASEBOARD_FAB2(SCH_1):PAGE172_I7@DEV_DISCRETE.CAP_A(CHIPS)':
 'B': CDS_PINID='B';
NET_NAME
'SATA6G_S1_RX_DP'
 '@BASEBOARD_FAB2_LIB.BASEBOARD_FAB2(SCH_1):SATA6G_S1_RX_DP':
 C_SIGNAL='@baseboard_fab2_lib.baseboard_fab2(sch_1):sata6g_s1_rx_dp';
NODE_NAME     U7C1 BA61
 '@BASEBOARD_FAB2_LIB.BASEBOARD_FAB2(SCH_1):PAGE116_I220@MSTR_U_PROC.LBG_CORE_QAT_EXT_D(CHIPS)':
 'PCIE7_SSATA1_RXP': CDS_PINID='PCIE7_SSATA1_RXP';
NODE_NAME     C2L49 2
 '@BASEBOARD_FAB2_LIB.BASEBOARD_FAB2(SCH_1):PAGE172_I5@DEV_DISCRETE.CAP_A(CHIPS)':
 'B': CDS_PINID='B';
NET_NAME
'SATA6G_S1_TX_C_DN'
 '@BASEBOARD_FAB2_LIB.BASEBOARD_FAB2(SCH_1):SATA6G_S1_TX_C_DN':
 C_SIGNAL='@baseboard_fab2_lib.baseboard_fab2(sch_1):sata6g_s1_tx_c_dn';
NODE_NAME     C2L51 1
 '@BASEBOARD_FAB2_LIB.BASEBOARD_FAB2(SCH_1):PAGE172_I8@DEV_DISCRETE.CAP_A(CHIPS)':
 'A': CDS_PINID='A';
NODE_NAME     J2W1 S3
 '@BASEBOARD_FAB2_LIB.BASEBOARD_FAB2(SCH_1):PAGE172_I67@W_HDL.SKT-SATA7P-6P-165-GP-U1(CHIPS)':
 'S3': CDS_PINID='S3';
NODE_NAME     J2W2 S3
 '@BASEBOARD_FAB2_LIB.BASEBOARD_FAB2(SCH_1):PAGE172_I68@W_HDL.SKT-SATA7P-6P-165-GP-U1(CHIPS)':
 'S3': CDS_PINID='S3';
NET_NAME
'SATA6G_S1_TX_C_DP'
 '@BASEBOARD_FAB2_LIB.BASEBOARD_FAB2(SCH_1):SATA6G_S1_TX_C_DP':
 C_SIGNAL='@baseboard_fab2_lib.baseboard_fab2(sch_1):sata6g_s1_tx_c_dp';
NODE_NAME     C2L52 1
 '@BASEBOARD_FAB2_LIB.BASEBOARD_FAB2(SCH_1):PAGE172_I6@DEV_DISCRETE.CAP_A(CHIPS)':
 'A': CDS_PINID='A';
NODE_NAME     J2W1 S2
 '@BASEBOARD_FAB2_LIB.BASEBOARD_FAB2(SCH_1):PAGE172_I67@W_HDL.SKT-SATA7P-6P-165-GP-U1(CHIPS)':
 'S2': CDS_PINID='S2';
NODE_NAME     J2W2 S2
 '@BASEBOARD_FAB2_LIB.BASEBOARD_FAB2(SCH_1):PAGE172_I68@W_HDL.SKT-SATA7P-6P-165-GP-U1(CHIPS)':
 'S2': CDS_PINID='S2';
NET_NAME
'SATA6G_S1_TX_DN'
 '@BASEBOARD_FAB2_LIB.BASEBOARD_FAB2(SCH_1):SATA6G_S1_TX_DN':
 C_SIGNAL='@baseboard_fab2_lib.baseboard_fab2(sch_1):sata6g_s1_tx_dn';
NODE_NAME     U7C1 AH69
 '@BASEBOARD_FAB2_LIB.BASEBOARD_FAB2(SCH_1):PAGE116_I220@MSTR_U_PROC.LBG_CORE_QAT_EXT_D(CHIPS)':
 'PCIE7_SSATA1_TXN': CDS_PINID='PCIE7_SSATA1_TXN';
NODE_NAME     C2L51 2
 '@BASEBOARD_FAB2_LIB.BASEBOARD_FAB2(SCH_1):PAGE172_I8@DEV_DISCRETE.CAP_A(CHIPS)':
 'B': CDS_PINID='B';
NET_NAME
'SATA6G_S1_TX_DP'
 '@BASEBOARD_FAB2_LIB.BASEBOARD_FAB2(SCH_1):SATA6G_S1_TX_DP':
 C_SIGNAL='@baseboard_fab2_lib.baseboard_fab2(sch_1):sata6g_s1_tx_dp';
NODE_NAME     U7C1 AH71
 '@BASEBOARD_FAB2_LIB.BASEBOARD_FAB2(SCH_1):PAGE116_I220@MSTR_U_PROC.LBG_CORE_QAT_EXT_D(CHIPS)':
 'PCIE7_SSATA1_TXP': CDS_PINID='PCIE7_SSATA1_TXP';
NODE_NAME     C2L52 2
 '@BASEBOARD_FAB2_LIB.BASEBOARD_FAB2(SCH_1):PAGE172_I6@DEV_DISCRETE.CAP_A(CHIPS)':
 'B': CDS_PINID='B';
NET_NAME
'SGPIO_BMC_CLK'
 '@BASEBOARD_FAB2_LIB.BASEBOARD_FAB2(SCH_1):SGPIO_BMC_CLK':
 C_SIGNAL='@baseboard_fab2_lib.baseboard_fab2(sch_1):sgpio_bmc_clk';
NODE_NAME     U8D7 J1
 '@BASEBOARD_FAB2_LIB.BASEBOARD_FAB2(SCH_1):PAGE190_I179@MSTR_MEMORY.LCMXO2_A(CHIPS)':
 'PL7C_PCLKT4_0': CDS_PINID='PL7C_PCLKT4_0';
NODE_NAME     R1U14 2
 '@BASEBOARD_FAB2_LIB.BASEBOARD_FAB2(SCH_1):PAGE144_I57@MSTR_DISCRETE.RES(CHIPS)':
 'B': CDS_PINID='B';
NET_NAME
'SGPIO_BMC_CLK_R'
 '@BASEBOARD_FAB2_LIB.BASEBOARD_FAB2(SCH_1):SGPIO_BMC_CLK_R':
 C_SIGNAL='@baseboard_fab2_lib.baseboard_fab2(sch_1):sgpio_bmc_clk_r';
NODE_NAME     R1U14 1
 '@BASEBOARD_FAB2_LIB.BASEBOARD_FAB2(SCH_1):PAGE144_I57@MSTR_DISCRETE.RES(CHIPS)':
 'A': CDS_PINID='A';
NODE_NAME     U25W4 R2
 '@BASEBOARD_FAB2_LIB.BASEBOARD_FAB2(SCH_1):PAGE144_I95@W_HDL.AST2520A1-GP-GP(CHIPS)':
 'GPIOJ0_SGPMCK': CDS_PINID='GPIOJ0_SGPMCK';
NET_NAME
'SGPIO_BMC_DIN'
 '@BASEBOARD_FAB2_LIB.BASEBOARD_FAB2(SCH_1):SGPIO_BMC_DIN':
 C_SIGNAL='@baseboard_fab2_lib.baseboard_fab2(sch_1):sgpio_bmc_din';
NODE_NAME     R2R6 2
 '@BASEBOARD_FAB2_LIB.BASEBOARD_FAB2(SCH_1):PAGE191_I166@MSTR_DISCRETE.RES(CHIPS)':
 'B': CDS_PINID='B';
NODE_NAME     U25W4 N4
 '@BASEBOARD_FAB2_LIB.BASEBOARD_FAB2(SCH_1):PAGE144_I95@W_HDL.AST2520A1-GP-GP(CHIPS)':
 'GPIOJ3_SGPMI': CDS_PINID='GPIOJ3_SGPMI';
NET_NAME
'SGPIO_BMC_DIN_R'
 '@BASEBOARD_FAB2_LIB.BASEBOARD_FAB2(SCH_1):SGPIO_BMC_DIN_R':
 C_SIGNAL='@baseboard_fab2_lib.baseboard_fab2(sch_1):sgpio_bmc_din_r';
NODE_NAME     U8D7 F8
 '@BASEBOARD_FAB2_LIB.BASEBOARD_FAB2(SCH_1):PAGE191_I59@MSTR_MEMORY.LCMXO2_A(CHIPS)':
 'PT18A': CDS_PINID='PT18A';
NODE_NAME     R2R6 1
 '@BASEBOARD_FAB2_LIB.BASEBOARD_FAB2(SCH_1):PAGE191_I166@MSTR_DISCRETE.RES(CHIPS)':
 'A': CDS_PINID='A';
NET_NAME
'SGPIO_BMC_DOUT'
 '@BASEBOARD_FAB2_LIB.BASEBOARD_FAB2(SCH_1):SGPIO_BMC_DOUT':
 C_SIGNAL='@baseboard_fab2_lib.baseboard_fab2(sch_1):sgpio_bmc_dout';
NODE_NAME     U8D7 J2
 '@BASEBOARD_FAB2_LIB.BASEBOARD_FAB2(SCH_1):PAGE190_I179@MSTR_MEMORY.LCMXO2_A(CHIPS)':
 'PL9A': CDS_PINID='PL9A';
NODE_NAME     R1U13 2
 '@BASEBOARD_FAB2_LIB.BASEBOARD_FAB2(SCH_1):PAGE144_I58@MSTR_DISCRETE.RES(CHIPS)':
 'B': CDS_PINID='B';
NET_NAME
'SGPIO_BMC_DOUT_R'
 '@BASEBOARD_FAB2_LIB.BASEBOARD_FAB2(SCH_1):SGPIO_BMC_DOUT_R':
 C_SIGNAL='@baseboard_fab2_lib.baseboard_fab2(sch_1):sgpio_bmc_dout_r';
NODE_NAME     R1U13 1
 '@BASEBOARD_FAB2_LIB.BASEBOARD_FAB2(SCH_1):PAGE144_I58@MSTR_DISCRETE.RES(CHIPS)':
 'A': CDS_PINID='A';
NODE_NAME     U25W4 N3
 '@BASEBOARD_FAB2_LIB.BASEBOARD_FAB2(SCH_1):PAGE144_I95@W_HDL.AST2520A1-GP-GP(CHIPS)':
 'GPIOJ2_SGPMO': CDS_PINID='GPIOJ2_SGPMO';
NET_NAME
'SGPIO_BMC_LD_N'
 '@BASEBOARD_FAB2_LIB.BASEBOARD_FAB2(SCH_1):SGPIO_BMC_LD_N':
 C_SIGNAL='@baseboard_fab2_lib.baseboard_fab2(sch_1):sgpio_bmc_ld_n';
NODE_NAME     U8D7 K4
 '@BASEBOARD_FAB2_LIB.BASEBOARD_FAB2(SCH_1):PAGE190_I179@MSTR_MEMORY.LCMXO2_A(CHIPS)':
 'PL11C': CDS_PINID='PL11C';
NODE_NAME     R1U12 2
 '@BASEBOARD_FAB2_LIB.BASEBOARD_FAB2(SCH_1):PAGE144_I59@MSTR_DISCRETE.RES(CHIPS)':
 'B': CDS_PINID='B';
NET_NAME
'SGPIO_BMC_LD_R_N'
 '@BASEBOARD_FAB2_LIB.BASEBOARD_FAB2(SCH_1):SGPIO_BMC_LD_R_N':
 C_SIGNAL='@baseboard_fab2_lib.baseboard_fab2(sch_1):sgpio_bmc_ld_r_n';
NODE_NAME     R1U12 1
 '@BASEBOARD_FAB2_LIB.BASEBOARD_FAB2(SCH_1):PAGE144_I59@MSTR_DISCRETE.RES(CHIPS)':
 'A': CDS_PINID='A';
NODE_NAME     U25W4 L2
 '@BASEBOARD_FAB2_LIB.BASEBOARD_FAB2(SCH_1):PAGE144_I95@W_HDL.AST2520A1-GP-GP(CHIPS)':
 'GPIOJ1_SGPMLD': CDS_PINID='GPIOJ1_SGPMLD';
NET_NAME
'SGPIO_PCH_SATA_CLOCK'
 '@BASEBOARD_FAB2_LIB.BASEBOARD_FAB2(SCH_1):SGPIO_PCH_SATA_CLOCK':
 C_SIGNAL='@baseboard_fab2_lib.baseboard_fab2(sch_1):sgpio_pch_sata_clock';
NODE_NAME     U7C1 AL7
 '@BASEBOARD_FAB2_LIB.BASEBOARD_FAB2(SCH_1):PAGE120_I147@MSTR_U_PROC.LBG_CORE_QAT_EXT_D(CHIPS)':
 'GPP_F10_SATA_SCLOCK': CDS_PINID='GPP_F10_SATA_SCLOCK';
NODE_NAME     R2N31 1
 '@BASEBOARD_FAB2_LIB.BASEBOARD_FAB2(SCH_1):PAGE178_I11@MSTR_DISCRETE.RES(CHIPS)':
 'A': CDS_PINID='A';
NET_NAME
'SGPIO_PCH_SATA_CLOCK_R'
 '@BASEBOARD_FAB2_LIB.BASEBOARD_FAB2(SCH_1):SGPIO_PCH_SATA_CLOCK_R':
 C_SIGNAL='@baseboard_fab2_lib.baseboard_fab2(sch_1):sgpio_pch_sata_clock_r';
NODE_NAME     J8A1 1A2
 '@BASEBOARD_FAB2_LIB.BASEBOARD_FAB2(SCH_1):PAGE173_I163@MSTR_CONN.CONN72_G97614002_A(CHIPS)':
 'SIDEBANDA_0': CDS_PINID='SIDEBANDA_0';
NODE_NAME     R2N31 2
 '@BASEBOARD_FAB2_LIB.BASEBOARD_FAB2(SCH_1):PAGE178_I11@MSTR_DISCRETE.RES(CHIPS)':
 'B': CDS_PINID='B';
NODE_NAME     R2L11 2
 '@BASEBOARD_FAB2_LIB.BASEBOARD_FAB2(SCH_1):PAGE178_I13@MSTR_DISCRETE.RES(CHIPS)':
 'B': CDS_PINID='B';
NET_NAME
'SGPIO_PCH_SATA_DOUT0'
 '@BASEBOARD_FAB2_LIB.BASEBOARD_FAB2(SCH_1):SGPIO_PCH_SATA_DOUT0':
 C_SIGNAL='@baseboard_fab2_lib.baseboard_fab2(sch_1):sgpio_pch_sata_dout0';
NODE_NAME     U7C1 AP11
 '@BASEBOARD_FAB2_LIB.BASEBOARD_FAB2(SCH_1):PAGE120_I147@MSTR_U_PROC.LBG_CORE_QAT_EXT_D(CHIPS)':
 'GPP_F13_SATA_SDATAOUT0': CDS_PINID='GPP_F13_SATA_SDATAOUT0';
NODE_NAME     R8D19 1
 '@BASEBOARD_FAB2_LIB.BASEBOARD_FAB2(SCH_1):PAGE178_I8@MSTR_DISCRETE.RES(CHIPS)':
 'A': CDS_PINID='A';
NET_NAME
'SGPIO_PCH_SATA_DOUT0_R'
 '@BASEBOARD_FAB2_LIB.BASEBOARD_FAB2(SCH_1):SGPIO_PCH_SATA_DOUT0_R':
 C_SIGNAL='@baseboard_fab2_lib.baseboard_fab2(sch_1):sgpio_pch_sata_dout0_r';
NODE_NAME     J8A1 1C1
 '@BASEBOARD_FAB2_LIB.BASEBOARD_FAB2(SCH_1):PAGE173_I163@MSTR_CONN.CONN72_G97614002_A(CHIPS)':
 'SIDEBANDA_4': CDS_PINID='SIDEBANDA_4';
NODE_NAME     R8D19 2
 '@BASEBOARD_FAB2_LIB.BASEBOARD_FAB2(SCH_1):PAGE178_I8@MSTR_DISCRETE.RES(CHIPS)':
 'B': CDS_PINID='B';
NODE_NAME     R2L15 2
 '@BASEBOARD_FAB2_LIB.BASEBOARD_FAB2(SCH_1):PAGE178_I12@MSTR_DISCRETE.RES(CHIPS)':
 'B': CDS_PINID='B';
NET_NAME
'SGPIO_PCH_SATA_LOAD'
 '@BASEBOARD_FAB2_LIB.BASEBOARD_FAB2(SCH_1):SGPIO_PCH_SATA_LOAD':
 C_SIGNAL='@baseboard_fab2_lib.baseboard_fab2(sch_1):sgpio_pch_sata_load';
NODE_NAME     U7C1 AR9
 '@BASEBOARD_FAB2_LIB.BASEBOARD_FAB2(SCH_1):PAGE120_I147@MSTR_U_PROC.LBG_CORE_QAT_EXT_D(CHIPS)':
 'GPP_F11_SATA_SLOAD': CDS_PINID='GPP_F11_SATA_SLOAD';
NODE_NAME     R8D20 1
 '@BASEBOARD_FAB2_LIB.BASEBOARD_FAB2(SCH_1):PAGE178_I1@MSTR_DISCRETE.RES(CHIPS)':
 'A': CDS_PINID='A';
NET_NAME
'SGPIO_PCH_SATA_LOAD_R'
 '@BASEBOARD_FAB2_LIB.BASEBOARD_FAB2(SCH_1):SGPIO_PCH_SATA_LOAD_R':
 C_SIGNAL='@baseboard_fab2_lib.baseboard_fab2(sch_1):sgpio_pch_sata_load_r';
NODE_NAME     J8A1 1B2
 '@BASEBOARD_FAB2_LIB.BASEBOARD_FAB2(SCH_1):PAGE173_I163@MSTR_CONN.CONN72_G97614002_A(CHIPS)':
 'SIDEBANDA_1': CDS_PINID='SIDEBANDA_1';
NODE_NAME     R8D20 2
 '@BASEBOARD_FAB2_LIB.BASEBOARD_FAB2(SCH_1):PAGE178_I1@MSTR_DISCRETE.RES(CHIPS)':
 'B': CDS_PINID='B';
NODE_NAME     R2L12 2
 '@BASEBOARD_FAB2_LIB.BASEBOARD_FAB2(SCH_1):PAGE178_I2@MSTR_DISCRETE.RES(CHIPS)':
 'B': CDS_PINID='B';
NET_NAME
'SGPIO_PCH_SSATA_CLOCK'
 '@BASEBOARD_FAB2_LIB.BASEBOARD_FAB2(SCH_1):SGPIO_PCH_SSATA_CLOCK':
 C_SIGNAL='@baseboard_fab2_lib.baseboard_fab2(sch_1):sgpio_pch_ssata_clock';
NODE_NAME     U7C1 AP18
 '@BASEBOARD_FAB2_LIB.BASEBOARD_FAB2(SCH_1):PAGE120_I147@MSTR_U_PROC.LBG_CORE_QAT_EXT_D(CHIPS)':
 'GPP_F22_SSATA_SCLOCK': CDS_PINID='GPP_F22_SSATA_SCLOCK';
NODE_NAME     R2N22 1
 '@BASEBOARD_FAB2_LIB.BASEBOARD_FAB2(SCH_1):PAGE178_I23@MSTR_DISCRETE.RES(CHIPS)':
 'A': CDS_PINID='A';
NET_NAME
'SGPIO_PCH_SSATA_CLOCK_R'
 '@BASEBOARD_FAB2_LIB.BASEBOARD_FAB2(SCH_1):SGPIO_PCH_SSATA_CLOCK_R':
 C_SIGNAL='@baseboard_fab2_lib.baseboard_fab2(sch_1):sgpio_pch_ssata_clock_r';
NODE_NAME     R2L6 2
 '@BASEBOARD_FAB2_LIB.BASEBOARD_FAB2(SCH_1):PAGE178_I17@MSTR_DISCRETE.RES(CHIPS)':
 'B': CDS_PINID='B';
NODE_NAME     R2N22 2
 '@BASEBOARD_FAB2_LIB.BASEBOARD_FAB2(SCH_1):PAGE178_I23@MSTR_DISCRETE.RES(CHIPS)':
 'B': CDS_PINID='B';
NET_NAME
'SGPIO_PCH_SSATA_DOUT0'
 '@BASEBOARD_FAB2_LIB.BASEBOARD_FAB2(SCH_1):SGPIO_PCH_SSATA_DOUT0':
 C_SIGNAL='@baseboard_fab2_lib.baseboard_fab2(sch_1):sgpio_pch_ssata_dout0';
NODE_NAME     U7C1 BW43
 '@BASEBOARD_FAB2_LIB.BASEBOARD_FAB2(SCH_1):PAGE119_I115@MSTR_U_PROC.LBG_CORE_QAT_EXT_D(CHIPS)':
 'GPP_D15_SSATA_SDATAOUT0': CDS_PINID='GPP_D15_SSATA_SDATAOUT0';
NODE_NAME     R8B29 1
 '@BASEBOARD_FAB2_LIB.BASEBOARD_FAB2(SCH_1):PAGE178_I21@MSTR_DISCRETE.RES(CHIPS)':
 'A': CDS_PINID='A';
NET_NAME
'SGPIO_PCH_SSATA_DOUT0_R'
 '@BASEBOARD_FAB2_LIB.BASEBOARD_FAB2(SCH_1):SGPIO_PCH_SSATA_DOUT0_R':
 C_SIGNAL='@baseboard_fab2_lib.baseboard_fab2(sch_1):sgpio_pch_ssata_dout0_r';
NODE_NAME     R2L4 2
 '@BASEBOARD_FAB2_LIB.BASEBOARD_FAB2(SCH_1):PAGE178_I18@MSTR_DISCRETE.RES(CHIPS)':
 'B': CDS_PINID='B';
NODE_NAME     R8B29 2
 '@BASEBOARD_FAB2_LIB.BASEBOARD_FAB2(SCH_1):PAGE178_I21@MSTR_DISCRETE.RES(CHIPS)':
 'B': CDS_PINID='B';
NET_NAME
'SGPIO_PCH_SSATA_LOAD'
 '@BASEBOARD_FAB2_LIB.BASEBOARD_FAB2(SCH_1):SGPIO_PCH_SSATA_LOAD':
 C_SIGNAL='@baseboard_fab2_lib.baseboard_fab2(sch_1):sgpio_pch_ssata_load';
NODE_NAME     U7C1 AU17
 '@BASEBOARD_FAB2_LIB.BASEBOARD_FAB2(SCH_1):PAGE120_I147@MSTR_U_PROC.LBG_CORE_QAT_EXT_D(CHIPS)':
 'GPP_F23_SSATA_SLOAD': CDS_PINID='GPP_F23_SSATA_SLOAD';
NODE_NAME     R2N19 1
 '@BASEBOARD_FAB2_LIB.BASEBOARD_FAB2(SCH_1):PAGE178_I22@MSTR_DISCRETE.RES(CHIPS)':
 'A': CDS_PINID='A';
NET_NAME
'SGPIO_PCH_SSATA_LOAD_R'
 '@BASEBOARD_FAB2_LIB.BASEBOARD_FAB2(SCH_1):SGPIO_PCH_SSATA_LOAD_R':
 C_SIGNAL='@baseboard_fab2_lib.baseboard_fab2(sch_1):sgpio_pch_ssata_load_r';
NODE_NAME     R2L5 2
 '@BASEBOARD_FAB2_LIB.BASEBOARD_FAB2(SCH_1):PAGE178_I20@MSTR_DISCRETE.RES(CHIPS)':
 'B': CDS_PINID='B';
NODE_NAME     R2N19 2
 '@BASEBOARD_FAB2_LIB.BASEBOARD_FAB2(SCH_1):PAGE178_I22@MSTR_DISCRETE.RES(CHIPS)':
 'B': CDS_PINID='B';
NET_NAME
'SMB_3V3SB_HSC_SCL_R'
 '@BASEBOARD_FAB2_LIB.BASEBOARD_FAB2(SCH_1):SMB_3V3SB_HSC_SCL_R':
 C_SIGNAL='@baseboard_fab2_lib.baseboard_fab2(sch_1):smb_3v3sb_hsc_scl_r';
NODE_NAME     EU1D2 16
 '@BASEBOARD_FAB2_LIB.BASEBOARD_FAB2(SCH_1):PAGE199_I10@MSTR_CONTROLLER.ADM1278(CHIPS)':
 'SCL': CDS_PINID='SCL';
NODE_NAME     R1D24 2
 '@BASEBOARD_FAB2_LIB.BASEBOARD_FAB2(SCH_1):PAGE199_I27@MSTR_DISCRETE.RES(CHIPS)':
 'B': CDS_PINID='B';
NET_NAME
'SMB_3V3SB_HSC_SDA_R'
 '@BASEBOARD_FAB2_LIB.BASEBOARD_FAB2(SCH_1):SMB_3V3SB_HSC_SDA_R':
 C_SIGNAL='@baseboard_fab2_lib.baseboard_fab2(sch_1):smb_3v3sb_hsc_sda_r';
NODE_NAME     EU1D2 15
 '@BASEBOARD_FAB2_LIB.BASEBOARD_FAB2(SCH_1):PAGE199_I10@MSTR_CONTROLLER.ADM1278(CHIPS)':
 'SDA': CDS_PINID='SDA';
NODE_NAME     R1D25 2
 '@BASEBOARD_FAB2_LIB.BASEBOARD_FAB2(SCH_1):PAGE199_I28@MSTR_DISCRETE.RES(CHIPS)':
 'B': CDS_PINID='B';
NET_NAME
'SMB_BMC_PMBUS_STBY_LVC3_SCL'
 '@BASEBOARD_FAB2_LIB.BASEBOARD_FAB2(SCH_1):SMB_BMC_PMBUS_STBY_LVC3_SCL':
 C_SIGNAL='@baseboard_fab2_lib.baseboard_fab2(sch_1):smb_bmc_pmbus_stby_lvc3_scl~
';
NODE_NAME     R2T54 2
 '@BASEBOARD_FAB2_LIB.BASEBOARD_FAB2(SCH_1):PAGE138_I84@MSTR_DISCRETE.RES(CHIPS)':
 'B': CDS_PINID='B';
NODE_NAME     R2U1 2
 '@BASEBOARD_FAB2_LIB.BASEBOARD_FAB2(SCH_1):PAGE159_I218@MSTR_DISCRETE.RES(CHIPS)':
 'B': CDS_PINID='B';
NODE_NAME     R1D24 1
 '@BASEBOARD_FAB2_LIB.BASEBOARD_FAB2(SCH_1):PAGE199_I27@MSTR_DISCRETE.RES(CHIPS)':
 'A': CDS_PINID='A';
NODE_NAME     U6W2 7
 '@BASEBOARD_FAB2_LIB.BASEBOARD_FAB2(SCH_1):PAGE247_I118@W_HDL.TCA9517DGKR-GP(CHIPS)':
 'SCLB': CDS_PINID='SCLB';
NODE_NAME     J1F3 7
 '@BASEBOARD_FAB2_LIB.BASEBOARD_FAB2(SCH_1):PAGE181_I106@MSTR_CONN.CONN8_H62179001(CHIPS)':
 'IO7': CDS_PINID='IO7';
NODE_NAME     J1F1 C6
 '@BASEBOARD_FAB2_LIB.BASEBOARD_FAB2(SCH_1):PAGE181_I134@W_HDL.DM-FCI-CONN76-8R-GP-U-01(CHIPS)':
 'PMBUS_CLK': CDS_PINID='PMBUS_CLK';
NET_NAME
'SMB_BMC_PMBUS_STBY_LVC3_SCL_R'
 '@BASEBOARD_FAB2_LIB.BASEBOARD_FAB2(SCH_1):SMB_BMC_PMBUS_STBY_LVC3_SCL_R':
 C_SIGNAL='@baseboard_fab2_lib.baseboard_fab2(sch_1):smb_bmc_pmbus_stby_lvc3_scl~
_r';
NODE_NAME     R2U1 1
 '@BASEBOARD_FAB2_LIB.BASEBOARD_FAB2(SCH_1):PAGE159_I218@MSTR_DISCRETE.RES(CHIPS)':
 'A': CDS_PINID='A';
NODE_NAME     U25W4 P2
 '@BASEBOARD_FAB2_LIB.BASEBOARD_FAB2(SCH_1):PAGE144_I95@W_HDL.AST2520A1-GP-GP(CHIPS)':
 'GPIOK6_SCL8': CDS_PINID='GPIOK6_SCL8';
NET_NAME
'SMB_BMC_PMBUS_STBY_LVC3_SDA'
 '@BASEBOARD_FAB2_LIB.BASEBOARD_FAB2(SCH_1):SMB_BMC_PMBUS_STBY_LVC3_SDA':
 C_SIGNAL='@baseboard_fab2_lib.baseboard_fab2(sch_1):smb_bmc_pmbus_stby_lvc3_sda~
';
NODE_NAME     R2T53 2
 '@BASEBOARD_FAB2_LIB.BASEBOARD_FAB2(SCH_1):PAGE138_I83@MSTR_DISCRETE.RES(CHIPS)':
 'B': CDS_PINID='B';
NODE_NAME     R2T49 2
 '@BASEBOARD_FAB2_LIB.BASEBOARD_FAB2(SCH_1):PAGE159_I219@MSTR_DISCRETE.RES(CHIPS)':
 'B': CDS_PINID='B';
NODE_NAME     R1D25 1
 '@BASEBOARD_FAB2_LIB.BASEBOARD_FAB2(SCH_1):PAGE199_I28@MSTR_DISCRETE.RES(CHIPS)':
 'A': CDS_PINID='A';
NODE_NAME     U6W2 6
 '@BASEBOARD_FAB2_LIB.BASEBOARD_FAB2(SCH_1):PAGE247_I118@W_HDL.TCA9517DGKR-GP(CHIPS)':
 'SDAB': CDS_PINID='SDAB';
NODE_NAME     J1F3 6
 '@BASEBOARD_FAB2_LIB.BASEBOARD_FAB2(SCH_1):PAGE181_I106@MSTR_CONN.CONN8_H62179001(CHIPS)':
 'IO6': CDS_PINID='IO6';
NODE_NAME     J1F1 B6
 '@BASEBOARD_FAB2_LIB.BASEBOARD_FAB2(SCH_1):PAGE181_I134@W_HDL.DM-FCI-CONN76-8R-GP-U-01(CHIPS)':
 'PMBUS_DATA': CDS_PINID='PMBUS_DATA';
NET_NAME
'SMB_BMC_PMBUS_STBY_LVC3_SDA_R'
 '@BASEBOARD_FAB2_LIB.BASEBOARD_FAB2(SCH_1):SMB_BMC_PMBUS_STBY_LVC3_SDA_R':
 C_SIGNAL='@baseboard_fab2_lib.baseboard_fab2(sch_1):smb_bmc_pmbus_stby_lvc3_sda~
_r';
NODE_NAME     R2T49 1
 '@BASEBOARD_FAB2_LIB.BASEBOARD_FAB2(SCH_1):PAGE159_I219@MSTR_DISCRETE.RES(CHIPS)':
 'A': CDS_PINID='A';
NODE_NAME     U25W4 R1
 '@BASEBOARD_FAB2_LIB.BASEBOARD_FAB2(SCH_1):PAGE144_I95@W_HDL.AST2520A1-GP-GP(CHIPS)':
 'GPIOK7_SDA8': CDS_PINID='GPIOK7_SDA8';
NET_NAME
'SMB_CPU0_PE_HP_GTL_R_SCL'
 '@BASEBOARD_FAB2_LIB.BASEBOARD_FAB2(SCH_1):SMB_CPU0_PE_HP_GTL_R_SCL':
 C_SIGNAL='@baseboard_fab2_lib.baseboard_fab2(sch_1):smb_cpu0_pe_hp_gtl_r_scl';
NODE_NAME     R6W26 2
 '@BASEBOARD_FAB2_LIB.BASEBOARD_FAB2(SCH_1):PAGE248_I24@MSTR_DISCRETE.RES(CHIPS)':
 'B': CDS_PINID='B';
NODE_NAME     R9W19 2
 '@BASEBOARD_FAB2_LIB.BASEBOARD_FAB2(SCH_1):PAGE248_I26@MSTR_DISCRETE.RES(CHIPS)':
 'B': CDS_PINID='B';
NODE_NAME     U1W2 2
 '@BASEBOARD_FAB2_LIB.BASEBOARD_FAB2(SCH_1):PAGE248_I49@W_HDL.TCA9517DGKR-GP(CHIPS)':
 'SCLA': CDS_PINID='SCLA';
NET_NAME
'SMB_CPU0_PE_HP_GTL_R_SDA'
 '@BASEBOARD_FAB2_LIB.BASEBOARD_FAB2(SCH_1):SMB_CPU0_PE_HP_GTL_R_SDA':
 C_SIGNAL='@baseboard_fab2_lib.baseboard_fab2(sch_1):smb_cpu0_pe_hp_gtl_r_sda';
NODE_NAME     R6W27 2
 '@BASEBOARD_FAB2_LIB.BASEBOARD_FAB2(SCH_1):PAGE248_I25@MSTR_DISCRETE.RES(CHIPS)':
 'B': CDS_PINID='B';
NODE_NAME     R9W18 2
 '@BASEBOARD_FAB2_LIB.BASEBOARD_FAB2(SCH_1):PAGE248_I27@MSTR_DISCRETE.RES(CHIPS)':
 'B': CDS_PINID='B';
NODE_NAME     U1W2 3
 '@BASEBOARD_FAB2_LIB.BASEBOARD_FAB2(SCH_1):PAGE248_I49@W_HDL.TCA9517DGKR-GP(CHIPS)':
 'SDAA': CDS_PINID='SDAA';
NET_NAME
'SMB_CPU0_PE_HP_GTL_SCL'
 '@BASEBOARD_FAB2_LIB.BASEBOARD_FAB2(SCH_1):SMB_CPU0_PE_HP_GTL_SCL':
 C_SIGNAL='@baseboard_fab2_lib.baseboard_fab2(sch_1):smb_cpu0_pe_hp_gtl_scl';
NODE_NAME     U5D1 AM19
 '@BASEBOARD_FAB2_LIB.BASEBOARD_FAB2(SCH_1):PAGE21_I259@CHPSET_LIB.SKX_EXT_B(CHIPS)':
 'PE_HP_SCL': CDS_PINID='PE_HP_SCL';
NODE_NAME     R6W26 1
 '@BASEBOARD_FAB2_LIB.BASEBOARD_FAB2(SCH_1):PAGE248_I24@MSTR_DISCRETE.RES(CHIPS)':
 'A': CDS_PINID='A';
NET_NAME
'SMB_CPU0_PE_HP_GTL_SDA'
 '@BASEBOARD_FAB2_LIB.BASEBOARD_FAB2(SCH_1):SMB_CPU0_PE_HP_GTL_SDA':
 C_SIGNAL='@baseboard_fab2_lib.baseboard_fab2(sch_1):smb_cpu0_pe_hp_gtl_sda';
NODE_NAME     U5D1 AL18
 '@BASEBOARD_FAB2_LIB.BASEBOARD_FAB2(SCH_1):PAGE21_I259@CHPSET_LIB.SKX_EXT_B(CHIPS)':
 'PE_HP_SDA': CDS_PINID='PE_HP_SDA';
NODE_NAME     R6W27 1
 '@BASEBOARD_FAB2_LIB.BASEBOARD_FAB2(SCH_1):PAGE248_I25@MSTR_DISCRETE.RES(CHIPS)':
 'A': CDS_PINID='A';
NET_NAME
'SMB_CPU1_PE_HP_GTL_R_SCL'
 '@BASEBOARD_FAB2_LIB.BASEBOARD_FAB2(SCH_1):SMB_CPU1_PE_HP_GTL_R_SCL':
 C_SIGNAL='@baseboard_fab2_lib.baseboard_fab2(sch_1):smb_cpu1_pe_hp_gtl_r_scl';
NODE_NAME     R6N8 2
 '@BASEBOARD_FAB2_LIB.BASEBOARD_FAB2(SCH_1):PAGE163_I2@MSTR_DISCRETE.RES(CHIPS)':
 'B': CDS_PINID='B';
NODE_NAME     R9M19 2
 '@BASEBOARD_FAB2_LIB.BASEBOARD_FAB2(SCH_1):PAGE163_I7@MSTR_DISCRETE.RES(CHIPS)':
 'B': CDS_PINID='B';
NODE_NAME     U1B2 2
 '@BASEBOARD_FAB2_LIB.BASEBOARD_FAB2(SCH_1):PAGE163_I28@W_HDL.TCA9517DGKR-GP(CHIPS)':
 'SCLA': CDS_PINID='SCLA';
NET_NAME
'SMB_CPU1_PE_HP_GTL_R_SDA'
 '@BASEBOARD_FAB2_LIB.BASEBOARD_FAB2(SCH_1):SMB_CPU1_PE_HP_GTL_R_SDA':
 C_SIGNAL='@baseboard_fab2_lib.baseboard_fab2(sch_1):smb_cpu1_pe_hp_gtl_r_sda';
NODE_NAME     R6N9 2
 '@BASEBOARD_FAB2_LIB.BASEBOARD_FAB2(SCH_1):PAGE163_I3@MSTR_DISCRETE.RES(CHIPS)':
 'B': CDS_PINID='B';
NODE_NAME     R9M18 2
 '@BASEBOARD_FAB2_LIB.BASEBOARD_FAB2(SCH_1):PAGE163_I6@MSTR_DISCRETE.RES(CHIPS)':
 'B': CDS_PINID='B';
NODE_NAME     U1B2 3
 '@BASEBOARD_FAB2_LIB.BASEBOARD_FAB2(SCH_1):PAGE163_I28@W_HDL.TCA9517DGKR-GP(CHIPS)':
 'SDAA': CDS_PINID='SDAA';
NET_NAME
'SMB_CPU1_PE_HP_GTL_SCL'
 '@BASEBOARD_FAB2_LIB.BASEBOARD_FAB2(SCH_1):SMB_CPU1_PE_HP_GTL_SCL':
 C_SIGNAL='@baseboard_fab2_lib.baseboard_fab2(sch_1):smb_cpu1_pe_hp_gtl_scl';
NODE_NAME     U2D1 AM19
 '@BASEBOARD_FAB2_LIB.BASEBOARD_FAB2(SCH_1):PAGE55_I172@CHPSET_LIB.SKX_EXT_B(CHIPS)':
 'PE_HP_SCL': CDS_PINID='PE_HP_SCL';
NODE_NAME     R6N8 1
 '@BASEBOARD_FAB2_LIB.BASEBOARD_FAB2(SCH_1):PAGE163_I2@MSTR_DISCRETE.RES(CHIPS)':
 'A': CDS_PINID='A';
NET_NAME
'SMB_CPU1_PE_HP_GTL_SDA'
 '@BASEBOARD_FAB2_LIB.BASEBOARD_FAB2(SCH_1):SMB_CPU1_PE_HP_GTL_SDA':
 C_SIGNAL='@baseboard_fab2_lib.baseboard_fab2(sch_1):smb_cpu1_pe_hp_gtl_sda';
NODE_NAME     U2D1 AL18
 '@BASEBOARD_FAB2_LIB.BASEBOARD_FAB2(SCH_1):PAGE55_I172@CHPSET_LIB.SKX_EXT_B(CHIPS)':
 'PE_HP_SDA': CDS_PINID='PE_HP_SDA';
NODE_NAME     R6N9 1
 '@BASEBOARD_FAB2_LIB.BASEBOARD_FAB2(SCH_1):PAGE163_I3@MSTR_DISCRETE.RES(CHIPS)':
 'A': CDS_PINID='A';
NET_NAME
'SMB_DDR_ABC_SCL_G'
 '@BASEBOARD_FAB2_LIB.BASEBOARD_FAB2(SCH_1):SMB_DDR_ABC_SCL_G':
 C_SIGNAL='@baseboard_fab2_lib.baseboard_fab2(sch_1):smb_ddr_abc_scl_g';
NODE_NAME     U6F1 2
 '@BASEBOARD_FAB2_LIB.BASEBOARD_FAB2(SCH_1):PAGE99_I15@MSTR_DIGITAL.PCA9617(CHIPS)':
 'SCLA': CDS_PINID='SCLA';
NODE_NAME     R4T5 2
 '@BASEBOARD_FAB2_LIB.BASEBOARD_FAB2(SCH_1):PAGE99_I19@MSTR_DISCRETE.RES(CHIPS)':
 'B': CDS_PINID='B';
NODE_NAME     R4T3 2
 '@BASEBOARD_FAB2_LIB.BASEBOARD_FAB2(SCH_1):PAGE99_I83@MSTR_DISCRETE.RES(CHIPS)':
 'B': CDS_PINID='B';
NET_NAME
'SMB_DDR_ABC_SCL_G_R'
 '@BASEBOARD_FAB2_LIB.BASEBOARD_FAB2(SCH_1):SMB_DDR_ABC_SCL_G_R':
 C_SIGNAL='@baseboard_fab2_lib.baseboard_fab2(sch_1):smb_ddr_abc_scl_g_r';
NODE_NAME     U5D1 AJ18
 '@BASEBOARD_FAB2_LIB.BASEBOARD_FAB2(SCH_1):PAGE21_I259@CHPSET_LIB.SKX_EXT_B(CHIPS)':
 'DDR012_SPDSCL': CDS_PINID='DDR012_SPDSCL';
NODE_NAME     R4T3 1
 '@BASEBOARD_FAB2_LIB.BASEBOARD_FAB2(SCH_1):PAGE99_I83@MSTR_DISCRETE.RES(CHIPS)':
 'A': CDS_PINID='A';
NET_NAME
'SMB_DDR_ABC_SDA_G'
 '@BASEBOARD_FAB2_LIB.BASEBOARD_FAB2(SCH_1):SMB_DDR_ABC_SDA_G':
 C_SIGNAL='@baseboard_fab2_lib.baseboard_fab2(sch_1):smb_ddr_abc_sda_g';
NODE_NAME     U6F1 3
 '@BASEBOARD_FAB2_LIB.BASEBOARD_FAB2(SCH_1):PAGE99_I15@MSTR_DIGITAL.PCA9617(CHIPS)':
 'SDAA': CDS_PINID='SDAA';
NODE_NAME     R4T6 2
 '@BASEBOARD_FAB2_LIB.BASEBOARD_FAB2(SCH_1):PAGE99_I17@MSTR_DISCRETE.RES(CHIPS)':
 'B': CDS_PINID='B';
NODE_NAME     R4T4 2
 '@BASEBOARD_FAB2_LIB.BASEBOARD_FAB2(SCH_1):PAGE99_I20@MSTR_DISCRETE.RES(CHIPS)':
 'B': CDS_PINID='B';
NET_NAME
'SMB_DDR_ABC_SDA_G_R'
 '@BASEBOARD_FAB2_LIB.BASEBOARD_FAB2(SCH_1):SMB_DDR_ABC_SDA_G_R':
 C_SIGNAL='@baseboard_fab2_lib.baseboard_fab2(sch_1):smb_ddr_abc_sda_g_r';
NODE_NAME     U5D1 AF17
 '@BASEBOARD_FAB2_LIB.BASEBOARD_FAB2(SCH_1):PAGE21_I259@CHPSET_LIB.SKX_EXT_B(CHIPS)':
 'DDR012_SPDSDA': CDS_PINID='DDR012_SPDSDA';
NODE_NAME     R4T4 1
 '@BASEBOARD_FAB2_LIB.BASEBOARD_FAB2(SCH_1):PAGE99_I20@MSTR_DISCRETE.RES(CHIPS)':
 'A': CDS_PINID='A';
NET_NAME
'SMB_DDR_ABC_VPP_SCL'
 '@BASEBOARD_FAB2_LIB.BASEBOARD_FAB2(SCH_1):SMB_DDR_ABC_VPP_SCL':
 C_SIGNAL='@baseboard_fab2_lib.baseboard_fab2(sch_1):smb_ddr_abc_vpp_scl';
NODE_NAME     J4G1 141
 '@BASEBOARD_FAB2_LIB.BASEBOARD_FAB2(SCH_1):PAGE43_I1@MSTR_SCONN.SCONN288_H44441004(CHIPS)':
 'SCL': CDS_PINID='SCL';
NODE_NAME     J6T1 141
 '@BASEBOARD_FAB2_LIB.BASEBOARD_FAB2(SCH_1):PAGE44_I13@MSTR_SCONN.SCONN288_H44441003(CHIPS)':
 'SCL': CDS_PINID='SCL';
NODE_NAME     J4G2 141
 '@BASEBOARD_FAB2_LIB.BASEBOARD_FAB2(SCH_1):PAGE45_I111@MSTR_SCONN.SCONN288_H44441004(CHIPS)':
 'SCL': CDS_PINID='SCL';
NODE_NAME     J6U1 141
 '@BASEBOARD_FAB2_LIB.BASEBOARD_FAB2(SCH_1):PAGE46_I14@MSTR_SCONN.SCONN288_H44441003(CHIPS)':
 'SCL': CDS_PINID='SCL';
NODE_NAME     J4G3 141
 '@BASEBOARD_FAB2_LIB.BASEBOARD_FAB2(SCH_1):PAGE47_I111@MSTR_SCONN.SCONN288_H44441004(CHIPS)':
 'SCL': CDS_PINID='SCL';
NODE_NAME     J6U2 141
 '@BASEBOARD_FAB2_LIB.BASEBOARD_FAB2(SCH_1):PAGE48_I111@MSTR_SCONN.SCONN288_H44441003(CHIPS)':
 'SCL': CDS_PINID='SCL';
NODE_NAME     R4T9 2
 '@BASEBOARD_FAB2_LIB.BASEBOARD_FAB2(SCH_1):PAGE99_I9@MSTR_DISCRETE.RES(CHIPS)':
 'B': CDS_PINID='B';
NET_NAME
'SMB_DDR_ABC_VPP_SCL_R'
 '@BASEBOARD_FAB2_LIB.BASEBOARD_FAB2(SCH_1):SMB_DDR_ABC_VPP_SCL_R':
 C_SIGNAL='@baseboard_fab2_lib.baseboard_fab2(sch_1):smb_ddr_abc_vpp_scl_r';
NODE_NAME     R4T9 1
 '@BASEBOARD_FAB2_LIB.BASEBOARD_FAB2(SCH_1):PAGE99_I9@MSTR_DISCRETE.RES(CHIPS)':
 'A': CDS_PINID='A';
NODE_NAME     R4T7 2
 '@BASEBOARD_FAB2_LIB.BASEBOARD_FAB2(SCH_1):PAGE99_I13@MSTR_DISCRETE.RES(CHIPS)':
 'B': CDS_PINID='B';
NODE_NAME     U6F1 7
 '@BASEBOARD_FAB2_LIB.BASEBOARD_FAB2(SCH_1):PAGE99_I15@MSTR_DIGITAL.PCA9617(CHIPS)':
 'SCLB': CDS_PINID='SCLB';
NET_NAME
'SMB_DDR_ABC_VPP_SDA'
 '@BASEBOARD_FAB2_LIB.BASEBOARD_FAB2(SCH_1):SMB_DDR_ABC_VPP_SDA':
 C_SIGNAL='@baseboard_fab2_lib.baseboard_fab2(sch_1):smb_ddr_abc_vpp_sda';
NODE_NAME     J4G1 285
 '@BASEBOARD_FAB2_LIB.BASEBOARD_FAB2(SCH_1):PAGE43_I1@MSTR_SCONN.SCONN288_H44441004(CHIPS)':
 'SDA': CDS_PINID='SDA';
NODE_NAME     J6T1 285
 '@BASEBOARD_FAB2_LIB.BASEBOARD_FAB2(SCH_1):PAGE44_I13@MSTR_SCONN.SCONN288_H44441003(CHIPS)':
 'SDA': CDS_PINID='SDA';
NODE_NAME     J4G2 285
 '@BASEBOARD_FAB2_LIB.BASEBOARD_FAB2(SCH_1):PAGE45_I111@MSTR_SCONN.SCONN288_H44441004(CHIPS)':
 'SDA': CDS_PINID='SDA';
NODE_NAME     J6U1 285
 '@BASEBOARD_FAB2_LIB.BASEBOARD_FAB2(SCH_1):PAGE46_I14@MSTR_SCONN.SCONN288_H44441003(CHIPS)':
 'SDA': CDS_PINID='SDA';
NODE_NAME     J4G3 285
 '@BASEBOARD_FAB2_LIB.BASEBOARD_FAB2(SCH_1):PAGE47_I111@MSTR_SCONN.SCONN288_H44441004(CHIPS)':
 'SDA': CDS_PINID='SDA';
NODE_NAME     J6U2 285
 '@BASEBOARD_FAB2_LIB.BASEBOARD_FAB2(SCH_1):PAGE48_I111@MSTR_SCONN.SCONN288_H44441003(CHIPS)':
 'SDA': CDS_PINID='SDA';
NODE_NAME     R4T10 2
 '@BASEBOARD_FAB2_LIB.BASEBOARD_FAB2(SCH_1):PAGE99_I10@MSTR_DISCRETE.RES(CHIPS)':
 'B': CDS_PINID='B';
NET_NAME
'SMB_DDR_ABC_VPP_SDA_R'
 '@BASEBOARD_FAB2_LIB.BASEBOARD_FAB2(SCH_1):SMB_DDR_ABC_VPP_SDA_R':
 C_SIGNAL='@baseboard_fab2_lib.baseboard_fab2(sch_1):smb_ddr_abc_vpp_sda_r';
NODE_NAME     R4T10 1
 '@BASEBOARD_FAB2_LIB.BASEBOARD_FAB2(SCH_1):PAGE99_I10@MSTR_DISCRETE.RES(CHIPS)':
 'A': CDS_PINID='A';
NODE_NAME     R4T8 2
 '@BASEBOARD_FAB2_LIB.BASEBOARD_FAB2(SCH_1):PAGE99_I11@MSTR_DISCRETE.RES(CHIPS)':
 'B': CDS_PINID='B';
NODE_NAME     U6F1 6
 '@BASEBOARD_FAB2_LIB.BASEBOARD_FAB2(SCH_1):PAGE99_I15@MSTR_DIGITAL.PCA9617(CHIPS)':
 'SDAB': CDS_PINID='SDAB';
NET_NAME
'SMB_DDR_DEF_SCL_G'
 '@BASEBOARD_FAB2_LIB.BASEBOARD_FAB2(SCH_1):SMB_DDR_DEF_SCL_G':
 C_SIGNAL='@baseboard_fab2_lib.baseboard_fab2(sch_1):smb_ddr_def_scl_g';
NODE_NAME     U7E1 2
 '@BASEBOARD_FAB2_LIB.BASEBOARD_FAB2(SCH_1):PAGE99_I61@MSTR_DIGITAL.PCA9617(CHIPS)':
 'SCLA': CDS_PINID='SCLA';
NODE_NAME     R3P60 2
 '@BASEBOARD_FAB2_LIB.BASEBOARD_FAB2(SCH_1):PAGE99_I67@MSTR_DISCRETE.RES(CHIPS)':
 'B': CDS_PINID='B';
NODE_NAME     R3R7 2
 '@BASEBOARD_FAB2_LIB.BASEBOARD_FAB2(SCH_1):PAGE99_I88@MSTR_DISCRETE.RES(CHIPS)':
 'B': CDS_PINID='B';
NET_NAME
'SMB_DDR_DEF_SCL_G_R'
 '@BASEBOARD_FAB2_LIB.BASEBOARD_FAB2(SCH_1):SMB_DDR_DEF_SCL_G_R':
 C_SIGNAL='@baseboard_fab2_lib.baseboard_fab2(sch_1):smb_ddr_def_scl_g_r';
NODE_NAME     U5D1 AE18
 '@BASEBOARD_FAB2_LIB.BASEBOARD_FAB2(SCH_1):PAGE21_I259@CHPSET_LIB.SKX_EXT_B(CHIPS)':
 'DDR345_SPDSCL': CDS_PINID='DDR345_SPDSCL';
NODE_NAME     R3R7 1
 '@BASEBOARD_FAB2_LIB.BASEBOARD_FAB2(SCH_1):PAGE99_I88@MSTR_DISCRETE.RES(CHIPS)':
 'A': CDS_PINID='A';
NET_NAME
'SMB_DDR_DEF_SDA_G'
 '@BASEBOARD_FAB2_LIB.BASEBOARD_FAB2(SCH_1):SMB_DDR_DEF_SDA_G':
 C_SIGNAL='@baseboard_fab2_lib.baseboard_fab2(sch_1):smb_ddr_def_sda_g';
NODE_NAME     U7E1 3
 '@BASEBOARD_FAB2_LIB.BASEBOARD_FAB2(SCH_1):PAGE99_I61@MSTR_DIGITAL.PCA9617(CHIPS)':
 'SDAA': CDS_PINID='SDAA';
NODE_NAME     R3R13 2
 '@BASEBOARD_FAB2_LIB.BASEBOARD_FAB2(SCH_1):PAGE99_I65@MSTR_DISCRETE.RES(CHIPS)':
 'B': CDS_PINID='B';
NODE_NAME     R3R14 2
 '@BASEBOARD_FAB2_LIB.BASEBOARD_FAB2(SCH_1):PAGE99_I110@MSTR_DISCRETE.RES(CHIPS)':
 'B': CDS_PINID='B';
NET_NAME
'SMB_DDR_DEF_SDA_G_R'
 '@BASEBOARD_FAB2_LIB.BASEBOARD_FAB2(SCH_1):SMB_DDR_DEF_SDA_G_R':
 C_SIGNAL='@baseboard_fab2_lib.baseboard_fab2(sch_1):smb_ddr_def_sda_g_r';
NODE_NAME     U5D1 AD17
 '@BASEBOARD_FAB2_LIB.BASEBOARD_FAB2(SCH_1):PAGE21_I259@CHPSET_LIB.SKX_EXT_B(CHIPS)':
 'DDR345_SPDSDA': CDS_PINID='DDR345_SPDSDA';
NODE_NAME     R3R14 1
 '@BASEBOARD_FAB2_LIB.BASEBOARD_FAB2(SCH_1):PAGE99_I110@MSTR_DISCRETE.RES(CHIPS)':
 'A': CDS_PINID='A';
NET_NAME
'SMB_DDR_DEF_VPP_SCL'
 '@BASEBOARD_FAB2_LIB.BASEBOARD_FAB2(SCH_1):SMB_DDR_DEF_VPP_SCL':
 C_SIGNAL='@baseboard_fab2_lib.baseboard_fab2(sch_1):smb_ddr_def_vpp_scl';
NODE_NAME     J4B1 141
 '@BASEBOARD_FAB2_LIB.BASEBOARD_FAB2(SCH_1):PAGE49_I111@MSTR_SCONN.SCONN288_H44441004(CHIPS)':
 'SCL': CDS_PINID='SCL';
NODE_NAME     J6M1 141
 '@BASEBOARD_FAB2_LIB.BASEBOARD_FAB2(SCH_1):PAGE50_I158@MSTR_SCONN.SCONN288_H44441003(CHIPS)':
 'SCL': CDS_PINID='SCL';
NODE_NAME     J4A2 141
 '@BASEBOARD_FAB2_LIB.BASEBOARD_FAB2(SCH_1):PAGE51_I111@MSTR_SCONN.SCONN288_H44441004(CHIPS)':
 'SCL': CDS_PINID='SCL';
NODE_NAME     J6L2 141
 '@BASEBOARD_FAB2_LIB.BASEBOARD_FAB2(SCH_1):PAGE52_I12@MSTR_SCONN.SCONN288_H44441003(CHIPS)':
 'SCL': CDS_PINID='SCL';
NODE_NAME     J4A1 141
 '@BASEBOARD_FAB2_LIB.BASEBOARD_FAB2(SCH_1):PAGE53_I111@MSTR_SCONN.SCONN288_H44441004(CHIPS)':
 'SCL': CDS_PINID='SCL';
NODE_NAME     J6L1 141
 '@BASEBOARD_FAB2_LIB.BASEBOARD_FAB2(SCH_1):PAGE54_I111@MSTR_SCONN.SCONN288_H44441003(CHIPS)':
 'SCL': CDS_PINID='SCL';
NODE_NAME     R3R8 2
 '@BASEBOARD_FAB2_LIB.BASEBOARD_FAB2(SCH_1):PAGE99_I35@MSTR_DISCRETE.RES(CHIPS)':
 'B': CDS_PINID='B';
NET_NAME
'SMB_DDR_DEF_VPP_SCL_R'
 '@BASEBOARD_FAB2_LIB.BASEBOARD_FAB2(SCH_1):SMB_DDR_DEF_VPP_SCL_R':
 C_SIGNAL='@baseboard_fab2_lib.baseboard_fab2(sch_1):smb_ddr_def_vpp_scl_r';
NODE_NAME     R3R8 1
 '@BASEBOARD_FAB2_LIB.BASEBOARD_FAB2(SCH_1):PAGE99_I35@MSTR_DISCRETE.RES(CHIPS)':
 'A': CDS_PINID='A';
NODE_NAME     U7E1 7
 '@BASEBOARD_FAB2_LIB.BASEBOARD_FAB2(SCH_1):PAGE99_I61@MSTR_DIGITAL.PCA9617(CHIPS)':
 'SCLB': CDS_PINID='SCLB';
NODE_NAME     R3R5 2
 '@BASEBOARD_FAB2_LIB.BASEBOARD_FAB2(SCH_1):PAGE99_I103@MSTR_DISCRETE.RES(CHIPS)':
 'B': CDS_PINID='B';
NET_NAME
'SMB_DDR_DEF_VPP_SDA'
 '@BASEBOARD_FAB2_LIB.BASEBOARD_FAB2(SCH_1):SMB_DDR_DEF_VPP_SDA':
 C_SIGNAL='@baseboard_fab2_lib.baseboard_fab2(sch_1):smb_ddr_def_vpp_sda';
NODE_NAME     J4B1 285
 '@BASEBOARD_FAB2_LIB.BASEBOARD_FAB2(SCH_1):PAGE49_I111@MSTR_SCONN.SCONN288_H44441004(CHIPS)':
 'SDA': CDS_PINID='SDA';
NODE_NAME     J6M1 285
 '@BASEBOARD_FAB2_LIB.BASEBOARD_FAB2(SCH_1):PAGE50_I158@MSTR_SCONN.SCONN288_H44441003(CHIPS)':
 'SDA': CDS_PINID='SDA';
NODE_NAME     J4A2 285
 '@BASEBOARD_FAB2_LIB.BASEBOARD_FAB2(SCH_1):PAGE51_I111@MSTR_SCONN.SCONN288_H44441004(CHIPS)':
 'SDA': CDS_PINID='SDA';
NODE_NAME     J6L2 285
 '@BASEBOARD_FAB2_LIB.BASEBOARD_FAB2(SCH_1):PAGE52_I12@MSTR_SCONN.SCONN288_H44441003(CHIPS)':
 'SDA': CDS_PINID='SDA';
NODE_NAME     J4A1 285
 '@BASEBOARD_FAB2_LIB.BASEBOARD_FAB2(SCH_1):PAGE53_I111@MSTR_SCONN.SCONN288_H44441004(CHIPS)':
 'SDA': CDS_PINID='SDA';
NODE_NAME     J6L1 285
 '@BASEBOARD_FAB2_LIB.BASEBOARD_FAB2(SCH_1):PAGE54_I111@MSTR_SCONN.SCONN288_H44441003(CHIPS)':
 'SDA': CDS_PINID='SDA';
NODE_NAME     R3R9 2
 '@BASEBOARD_FAB2_LIB.BASEBOARD_FAB2(SCH_1):PAGE99_I34@MSTR_DISCRETE.RES(CHIPS)':
 'B': CDS_PINID='B';
NET_NAME
'SMB_DDR_DEF_VPP_SDA_R'
 '@BASEBOARD_FAB2_LIB.BASEBOARD_FAB2(SCH_1):SMB_DDR_DEF_VPP_SDA_R':
 C_SIGNAL='@baseboard_fab2_lib.baseboard_fab2(sch_1):smb_ddr_def_vpp_sda_r';
NODE_NAME     R3R9 1
 '@BASEBOARD_FAB2_LIB.BASEBOARD_FAB2(SCH_1):PAGE99_I34@MSTR_DISCRETE.RES(CHIPS)':
 'A': CDS_PINID='A';
NODE_NAME     U7E1 6
 '@BASEBOARD_FAB2_LIB.BASEBOARD_FAB2(SCH_1):PAGE99_I61@MSTR_DIGITAL.PCA9617(CHIPS)':
 'SDAB': CDS_PINID='SDAB';
NODE_NAME     R3R12 2
 '@BASEBOARD_FAB2_LIB.BASEBOARD_FAB2(SCH_1):PAGE99_I101@MSTR_DISCRETE.RES(CHIPS)':
 'B': CDS_PINID='B';
NET_NAME
'SMB_DDR_GHJ_SCL_G'
 '@BASEBOARD_FAB2_LIB.BASEBOARD_FAB2(SCH_1):SMB_DDR_GHJ_SCL_G':
 C_SIGNAL='@baseboard_fab2_lib.baseboard_fab2(sch_1):smb_ddr_ghj_scl_g';
NODE_NAME     U4G1 2
 '@BASEBOARD_FAB2_LIB.BASEBOARD_FAB2(SCH_1):PAGE99_I63@MSTR_DIGITAL.PCA9617(CHIPS)':
 'SCLA': CDS_PINID='SCLA';
NODE_NAME     R6T2 2
 '@BASEBOARD_FAB2_LIB.BASEBOARD_FAB2(SCH_1):PAGE99_I72@MSTR_DISCRETE.RES(CHIPS)':
 'B': CDS_PINID='B';
NODE_NAME     R6T3 2
 '@BASEBOARD_FAB2_LIB.BASEBOARD_FAB2(SCH_1):PAGE99_I92@MSTR_DISCRETE.RES(CHIPS)':
 'B': CDS_PINID='B';
NET_NAME
'SMB_DDR_GHJ_SCL_G_R'
 '@BASEBOARD_FAB2_LIB.BASEBOARD_FAB2(SCH_1):SMB_DDR_GHJ_SCL_G_R':
 C_SIGNAL='@baseboard_fab2_lib.baseboard_fab2(sch_1):smb_ddr_ghj_scl_g_r';
NODE_NAME     U2D1 AJ18
 '@BASEBOARD_FAB2_LIB.BASEBOARD_FAB2(SCH_1):PAGE55_I172@CHPSET_LIB.SKX_EXT_B(CHIPS)':
 'DDR012_SPDSCL': CDS_PINID='DDR012_SPDSCL';
NODE_NAME     R6T3 1
 '@BASEBOARD_FAB2_LIB.BASEBOARD_FAB2(SCH_1):PAGE99_I92@MSTR_DISCRETE.RES(CHIPS)':
 'A': CDS_PINID='A';
NET_NAME
'SMB_DDR_GHJ_SDA_G'
 '@BASEBOARD_FAB2_LIB.BASEBOARD_FAB2(SCH_1):SMB_DDR_GHJ_SDA_G':
 C_SIGNAL='@baseboard_fab2_lib.baseboard_fab2(sch_1):smb_ddr_ghj_sda_g';
NODE_NAME     U4G1 3
 '@BASEBOARD_FAB2_LIB.BASEBOARD_FAB2(SCH_1):PAGE99_I63@MSTR_DIGITAL.PCA9617(CHIPS)':
 'SDAA': CDS_PINID='SDAA';
NODE_NAME     R6T1 2
 '@BASEBOARD_FAB2_LIB.BASEBOARD_FAB2(SCH_1):PAGE99_I70@MSTR_DISCRETE.RES(CHIPS)':
 'B': CDS_PINID='B';
NODE_NAME     R6T4 2
 '@BASEBOARD_FAB2_LIB.BASEBOARD_FAB2(SCH_1):PAGE99_I111@MSTR_DISCRETE.RES(CHIPS)':
 'B': CDS_PINID='B';
NET_NAME
'SMB_DDR_GHJ_SDA_G_R'
 '@BASEBOARD_FAB2_LIB.BASEBOARD_FAB2(SCH_1):SMB_DDR_GHJ_SDA_G_R':
 C_SIGNAL='@baseboard_fab2_lib.baseboard_fab2(sch_1):smb_ddr_ghj_sda_g_r';
NODE_NAME     U2D1 AF17
 '@BASEBOARD_FAB2_LIB.BASEBOARD_FAB2(SCH_1):PAGE55_I172@CHPSET_LIB.SKX_EXT_B(CHIPS)':
 'DDR012_SPDSDA': CDS_PINID='DDR012_SPDSDA';
NODE_NAME     R6T4 1
 '@BASEBOARD_FAB2_LIB.BASEBOARD_FAB2(SCH_1):PAGE99_I111@MSTR_DISCRETE.RES(CHIPS)':
 'A': CDS_PINID='A';
NET_NAME
'SMB_DDR_GHJ_VPP_SCL'
 '@BASEBOARD_FAB2_LIB.BASEBOARD_FAB2(SCH_1):SMB_DDR_GHJ_VPP_SCL':
 C_SIGNAL='@baseboard_fab2_lib.baseboard_fab2(sch_1):smb_ddr_ghj_vpp_scl';
NODE_NAME     J1G1 141
 '@BASEBOARD_FAB2_LIB.BASEBOARD_FAB2(SCH_1):PAGE77_I111@MSTR_SCONN.SCONN288_H44441004(CHIPS)':
 'SCL': CDS_PINID='SCL';
NODE_NAME     J9T1 141
 '@BASEBOARD_FAB2_LIB.BASEBOARD_FAB2(SCH_1):PAGE78_I13@MSTR_SCONN.SCONN288_H44441003(CHIPS)':
 'SCL': CDS_PINID='SCL';
NODE_NAME     J1G2 141
 '@BASEBOARD_FAB2_LIB.BASEBOARD_FAB2(SCH_1):PAGE79_I111@MSTR_SCONN.SCONN288_H44441004(CHIPS)':
 'SCL': CDS_PINID='SCL';
NODE_NAME     J9U1 141
 '@BASEBOARD_FAB2_LIB.BASEBOARD_FAB2(SCH_1):PAGE80_I24@MSTR_SCONN.SCONN288_H44441003(CHIPS)':
 'SCL': CDS_PINID='SCL';
NODE_NAME     J1G3 141
 '@BASEBOARD_FAB2_LIB.BASEBOARD_FAB2(SCH_1):PAGE81_I186@MSTR_SCONN.SCONN288_H44441004(CHIPS)':
 'SCL': CDS_PINID='SCL';
NODE_NAME     J9U2 141
 '@BASEBOARD_FAB2_LIB.BASEBOARD_FAB2(SCH_1):PAGE82_I187@MSTR_SCONN.SCONN288_H44441003(CHIPS)':
 'SCL': CDS_PINID='SCL';
NODE_NAME     R6U13 2
 '@BASEBOARD_FAB2_LIB.BASEBOARD_FAB2(SCH_1):PAGE99_I42@MSTR_DISCRETE.RES(CHIPS)':
 'B': CDS_PINID='B';
NET_NAME
'SMB_DDR_GHJ_VPP_SCL_R'
 '@BASEBOARD_FAB2_LIB.BASEBOARD_FAB2(SCH_1):SMB_DDR_GHJ_VPP_SCL_R':
 C_SIGNAL='@baseboard_fab2_lib.baseboard_fab2(sch_1):smb_ddr_ghj_vpp_scl_r';
NODE_NAME     R6U13 1
 '@BASEBOARD_FAB2_LIB.BASEBOARD_FAB2(SCH_1):PAGE99_I42@MSTR_DISCRETE.RES(CHIPS)':
 'A': CDS_PINID='A';
NODE_NAME     U4G1 7
 '@BASEBOARD_FAB2_LIB.BASEBOARD_FAB2(SCH_1):PAGE99_I63@MSTR_DIGITAL.PCA9617(CHIPS)':
 'SCLB': CDS_PINID='SCLB';
NODE_NAME     R6U17 2
 '@BASEBOARD_FAB2_LIB.BASEBOARD_FAB2(SCH_1):PAGE99_I106@MSTR_DISCRETE.RES(CHIPS)':
 'B': CDS_PINID='B';
NET_NAME
'SMB_DDR_GHJ_VPP_SDA'
 '@BASEBOARD_FAB2_LIB.BASEBOARD_FAB2(SCH_1):SMB_DDR_GHJ_VPP_SDA':
 C_SIGNAL='@baseboard_fab2_lib.baseboard_fab2(sch_1):smb_ddr_ghj_vpp_sda';
NODE_NAME     J1G1 285
 '@BASEBOARD_FAB2_LIB.BASEBOARD_FAB2(SCH_1):PAGE77_I111@MSTR_SCONN.SCONN288_H44441004(CHIPS)':
 'SDA': CDS_PINID='SDA';
NODE_NAME     J9T1 285
 '@BASEBOARD_FAB2_LIB.BASEBOARD_FAB2(SCH_1):PAGE78_I13@MSTR_SCONN.SCONN288_H44441003(CHIPS)':
 'SDA': CDS_PINID='SDA';
NODE_NAME     J1G2 285
 '@BASEBOARD_FAB2_LIB.BASEBOARD_FAB2(SCH_1):PAGE79_I111@MSTR_SCONN.SCONN288_H44441004(CHIPS)':
 'SDA': CDS_PINID='SDA';
NODE_NAME     J9U1 285
 '@BASEBOARD_FAB2_LIB.BASEBOARD_FAB2(SCH_1):PAGE80_I24@MSTR_SCONN.SCONN288_H44441003(CHIPS)':
 'SDA': CDS_PINID='SDA';
NODE_NAME     J1G3 285
 '@BASEBOARD_FAB2_LIB.BASEBOARD_FAB2(SCH_1):PAGE81_I186@MSTR_SCONN.SCONN288_H44441004(CHIPS)':
 'SDA': CDS_PINID='SDA';
NODE_NAME     J9U2 285
 '@BASEBOARD_FAB2_LIB.BASEBOARD_FAB2(SCH_1):PAGE82_I187@MSTR_SCONN.SCONN288_H44441003(CHIPS)':
 'SDA': CDS_PINID='SDA';
NODE_NAME     R6U14 2
 '@BASEBOARD_FAB2_LIB.BASEBOARD_FAB2(SCH_1):PAGE99_I115@MSTR_DISCRETE.RES(CHIPS)':
 'B': CDS_PINID='B';
NET_NAME
'SMB_DDR_GHJ_VPP_SDA_R'
 '@BASEBOARD_FAB2_LIB.BASEBOARD_FAB2(SCH_1):SMB_DDR_GHJ_VPP_SDA_R':
 C_SIGNAL='@baseboard_fab2_lib.baseboard_fab2(sch_1):smb_ddr_ghj_vpp_sda_r';
NODE_NAME     U4G1 6
 '@BASEBOARD_FAB2_LIB.BASEBOARD_FAB2(SCH_1):PAGE99_I63@MSTR_DIGITAL.PCA9617(CHIPS)':
 'SDAB': CDS_PINID='SDAB';
NODE_NAME     R6U18 2
 '@BASEBOARD_FAB2_LIB.BASEBOARD_FAB2(SCH_1):PAGE99_I104@MSTR_DISCRETE.RES(CHIPS)':
 'B': CDS_PINID='B';
NODE_NAME     R6U14 1
 '@BASEBOARD_FAB2_LIB.BASEBOARD_FAB2(SCH_1):PAGE99_I115@MSTR_DISCRETE.RES(CHIPS)':
 'A': CDS_PINID='A';
NET_NAME
'SMB_DDR_KLM_SCL_G'
 '@BASEBOARD_FAB2_LIB.BASEBOARD_FAB2(SCH_1):SMB_DDR_KLM_SCL_G':
 C_SIGNAL='@baseboard_fab2_lib.baseboard_fab2(sch_1):smb_ddr_klm_scl_g';
NODE_NAME     U3B1 2
 '@BASEBOARD_FAB2_LIB.BASEBOARD_FAB2(SCH_1):PAGE99_I75@MSTR_DIGITAL.PCA9617(CHIPS)':
 'SCLA': CDS_PINID='SCLA';
NODE_NAME     R7M2 2
 '@BASEBOARD_FAB2_LIB.BASEBOARD_FAB2(SCH_1):PAGE99_I79@MSTR_DISCRETE.RES(CHIPS)':
 'B': CDS_PINID='B';
NODE_NAME     R7M3 2
 '@BASEBOARD_FAB2_LIB.BASEBOARD_FAB2(SCH_1):PAGE99_I98@MSTR_DISCRETE.RES(CHIPS)':
 'B': CDS_PINID='B';
NET_NAME
'SMB_DDR_KLM_SCL_G_R'
 '@BASEBOARD_FAB2_LIB.BASEBOARD_FAB2(SCH_1):SMB_DDR_KLM_SCL_G_R':
 C_SIGNAL='@baseboard_fab2_lib.baseboard_fab2(sch_1):smb_ddr_klm_scl_g_r';
NODE_NAME     U2D1 AE18
 '@BASEBOARD_FAB2_LIB.BASEBOARD_FAB2(SCH_1):PAGE55_I172@CHPSET_LIB.SKX_EXT_B(CHIPS)':
 'DDR345_SPDSCL': CDS_PINID='DDR345_SPDSCL';
NODE_NAME     R7M3 1
 '@BASEBOARD_FAB2_LIB.BASEBOARD_FAB2(SCH_1):PAGE99_I98@MSTR_DISCRETE.RES(CHIPS)':
 'A': CDS_PINID='A';
NET_NAME
'SMB_DDR_KLM_SDA_G'
 '@BASEBOARD_FAB2_LIB.BASEBOARD_FAB2(SCH_1):SMB_DDR_KLM_SDA_G':
 C_SIGNAL='@baseboard_fab2_lib.baseboard_fab2(sch_1):smb_ddr_klm_sda_g';
NODE_NAME     U3B1 3
 '@BASEBOARD_FAB2_LIB.BASEBOARD_FAB2(SCH_1):PAGE99_I75@MSTR_DIGITAL.PCA9617(CHIPS)':
 'SDAA': CDS_PINID='SDAA';
NODE_NAME     R7M7 2
 '@BASEBOARD_FAB2_LIB.BASEBOARD_FAB2(SCH_1):PAGE99_I77@MSTR_DISCRETE.RES(CHIPS)':
 'B': CDS_PINID='B';
NODE_NAME     R7M8 2
 '@BASEBOARD_FAB2_LIB.BASEBOARD_FAB2(SCH_1):PAGE99_I112@MSTR_DISCRETE.RES(CHIPS)':
 'B': CDS_PINID='B';
NET_NAME
'SMB_DDR_KLM_SDA_G_R'
 '@BASEBOARD_FAB2_LIB.BASEBOARD_FAB2(SCH_1):SMB_DDR_KLM_SDA_G_R':
 C_SIGNAL='@baseboard_fab2_lib.baseboard_fab2(sch_1):smb_ddr_klm_sda_g_r';
NODE_NAME     U2D1 AD17
 '@BASEBOARD_FAB2_LIB.BASEBOARD_FAB2(SCH_1):PAGE55_I172@CHPSET_LIB.SKX_EXT_B(CHIPS)':
 'DDR345_SPDSDA': CDS_PINID='DDR345_SPDSDA';
NODE_NAME     R7M8 1
 '@BASEBOARD_FAB2_LIB.BASEBOARD_FAB2(SCH_1):PAGE99_I112@MSTR_DISCRETE.RES(CHIPS)':
 'A': CDS_PINID='A';
NET_NAME
'SMB_DDR_KLM_VPP_SCL'
 '@BASEBOARD_FAB2_LIB.BASEBOARD_FAB2(SCH_1):SMB_DDR_KLM_VPP_SCL':
 C_SIGNAL='@baseboard_fab2_lib.baseboard_fab2(sch_1):smb_ddr_klm_vpp_scl';
NODE_NAME     J1B1 141
 '@BASEBOARD_FAB2_LIB.BASEBOARD_FAB2(SCH_1):PAGE83_I111@MSTR_SCONN.SCONN288_H44441004(CHIPS)':
 'SCL': CDS_PINID='SCL';
NODE_NAME     J9M1 141
 '@BASEBOARD_FAB2_LIB.BASEBOARD_FAB2(SCH_1):PAGE84_I14@MSTR_SCONN.SCONN288_H44441003(CHIPS)':
 'SCL': CDS_PINID='SCL';
NODE_NAME     J1A2 141
 '@BASEBOARD_FAB2_LIB.BASEBOARD_FAB2(SCH_1):PAGE85_I111@MSTR_SCONN.SCONN288_H44441004(CHIPS)':
 'SCL': CDS_PINID='SCL';
NODE_NAME     J9L2 141
 '@BASEBOARD_FAB2_LIB.BASEBOARD_FAB2(SCH_1):PAGE86_I12@MSTR_SCONN.SCONN288_H44441003(CHIPS)':
 'SCL': CDS_PINID='SCL';
NODE_NAME     J1A1 141
 '@BASEBOARD_FAB2_LIB.BASEBOARD_FAB2(SCH_1):PAGE87_I186@MSTR_SCONN.SCONN288_H44441004(CHIPS)':
 'SCL': CDS_PINID='SCL';
NODE_NAME     J9L1 141
 '@BASEBOARD_FAB2_LIB.BASEBOARD_FAB2(SCH_1):PAGE88_I111@MSTR_SCONN.SCONN288_H44441003(CHIPS)':
 'SCL': CDS_PINID='SCL';
NODE_NAME     R7M4 2
 '@BASEBOARD_FAB2_LIB.BASEBOARD_FAB2(SCH_1):PAGE99_I56@MSTR_DISCRETE.RES(CHIPS)':
 'B': CDS_PINID='B';
NET_NAME
'SMB_DDR_KLM_VPP_SCL_R'
 '@BASEBOARD_FAB2_LIB.BASEBOARD_FAB2(SCH_1):SMB_DDR_KLM_VPP_SCL_R':
 C_SIGNAL='@baseboard_fab2_lib.baseboard_fab2(sch_1):smb_ddr_klm_vpp_scl_r';
NODE_NAME     R7M4 1
 '@BASEBOARD_FAB2_LIB.BASEBOARD_FAB2(SCH_1):PAGE99_I56@MSTR_DISCRETE.RES(CHIPS)':
 'A': CDS_PINID='A';
NODE_NAME     U3B1 7
 '@BASEBOARD_FAB2_LIB.BASEBOARD_FAB2(SCH_1):PAGE99_I75@MSTR_DIGITAL.PCA9617(CHIPS)':
 'SCLB': CDS_PINID='SCLB';
NODE_NAME     R7M1 2
 '@BASEBOARD_FAB2_LIB.BASEBOARD_FAB2(SCH_1):PAGE99_I109@MSTR_DISCRETE.RES(CHIPS)':
 'B': CDS_PINID='B';
NET_NAME
'SMB_DDR_KLM_VPP_SDA'
 '@BASEBOARD_FAB2_LIB.BASEBOARD_FAB2(SCH_1):SMB_DDR_KLM_VPP_SDA':
 C_SIGNAL='@baseboard_fab2_lib.baseboard_fab2(sch_1):smb_ddr_klm_vpp_sda';
NODE_NAME     J1B1 285
 '@BASEBOARD_FAB2_LIB.BASEBOARD_FAB2(SCH_1):PAGE83_I111@MSTR_SCONN.SCONN288_H44441004(CHIPS)':
 'SDA': CDS_PINID='SDA';
NODE_NAME     J9M1 285
 '@BASEBOARD_FAB2_LIB.BASEBOARD_FAB2(SCH_1):PAGE84_I14@MSTR_SCONN.SCONN288_H44441003(CHIPS)':
 'SDA': CDS_PINID='SDA';
NODE_NAME     J1A2 285
 '@BASEBOARD_FAB2_LIB.BASEBOARD_FAB2(SCH_1):PAGE85_I111@MSTR_SCONN.SCONN288_H44441004(CHIPS)':
 'SDA': CDS_PINID='SDA';
NODE_NAME     J9L2 285
 '@BASEBOARD_FAB2_LIB.BASEBOARD_FAB2(SCH_1):PAGE86_I12@MSTR_SCONN.SCONN288_H44441003(CHIPS)':
 'SDA': CDS_PINID='SDA';
NODE_NAME     J1A1 285
 '@BASEBOARD_FAB2_LIB.BASEBOARD_FAB2(SCH_1):PAGE87_I186@MSTR_SCONN.SCONN288_H44441004(CHIPS)':
 'SDA': CDS_PINID='SDA';
NODE_NAME     J9L1 285
 '@BASEBOARD_FAB2_LIB.BASEBOARD_FAB2(SCH_1):PAGE88_I111@MSTR_SCONN.SCONN288_H44441003(CHIPS)':
 'SDA': CDS_PINID='SDA';
NODE_NAME     R7M5 2
 '@BASEBOARD_FAB2_LIB.BASEBOARD_FAB2(SCH_1):PAGE99_I55@MSTR_DISCRETE.RES(CHIPS)':
 'B': CDS_PINID='B';
NET_NAME
'SMB_DDR_KLM_VPP_SDA_R'
 '@BASEBOARD_FAB2_LIB.BASEBOARD_FAB2(SCH_1):SMB_DDR_KLM_VPP_SDA_R':
 C_SIGNAL='@baseboard_fab2_lib.baseboard_fab2(sch_1):smb_ddr_klm_vpp_sda_r';
NODE_NAME     R7M5 1
 '@BASEBOARD_FAB2_LIB.BASEBOARD_FAB2(SCH_1):PAGE99_I55@MSTR_DISCRETE.RES(CHIPS)':
 'A': CDS_PINID='A';
NODE_NAME     U3B1 6
 '@BASEBOARD_FAB2_LIB.BASEBOARD_FAB2(SCH_1):PAGE99_I75@MSTR_DIGITAL.PCA9617(CHIPS)':
 'SDAB': CDS_PINID='SDAB';
NODE_NAME     R7M6 2
 '@BASEBOARD_FAB2_LIB.BASEBOARD_FAB2(SCH_1):PAGE99_I107@MSTR_DISCRETE.RES(CHIPS)':
 'B': CDS_PINID='B';
NET_NAME
'SMB_DEBUG_STBY_LVC3_SCL'
 '@BASEBOARD_FAB2_LIB.BASEBOARD_FAB2(SCH_1):SMB_DEBUG_STBY_LVC3_SCL':
 C_SIGNAL='@baseboard_fab2_lib.baseboard_fab2(sch_1):smb_debug_stby_lvc3_scl';
NODE_NAME     R6W17 1
 '@BASEBOARD_FAB2_LIB.BASEBOARD_FAB2(SCH_1):PAGE145_I120@MSTR_DISCRETE.RES(CHIPS)':
 'A': CDS_PINID='A';
NODE_NAME     R6W11 1
 '@BASEBOARD_FAB2_LIB.BASEBOARD_FAB2(SCH_1):PAGE247_I98@MSTR_DISCRETE.RES(CHIPS)':
 'A': CDS_PINID='A';
NODE_NAME     U6W1 22
 '@BASEBOARD_FAB2_LIB.BASEBOARD_FAB2(SCH_1):PAGE247_I120@W_HDL.TCA9555PWR-GP(CHIPS)':
 'SCL': CDS_PINID='SCL';
NODE_NAME     R1W33 2
 '@BASEBOARD_FAB2_LIB.BASEBOARD_FAB2(SCH_1):PAGE176_I142@MSTR_DISCRETE.RES(CHIPS)':
 'B': CDS_PINID='B';
NET_NAME
'SMB_DEBUG_STBY_LVC3_SCL_CONN'
 '@BASEBOARD_FAB2_LIB.BASEBOARD_FAB2(SCH_1):SMB_DEBUG_STBY_LVC3_SCL_CONN':
 C_SIGNAL='@baseboard_fab2_lib.baseboard_fab2(sch_1):smb_debug_stby_lvc3_scl_con~
n';
NODE_NAME     J9B1 5
 '@BASEBOARD_FAB2_LIB.BASEBOARD_FAB2(SCH_1):PAGE176_I69@MSTR_CONN.CONN9_H51826001(CHIPS)':
 'STDA_SSRXN': CDS_PINID='STDA_SSRXN';
NODE_NAME     U1W3 2
 '@BASEBOARD_FAB2_LIB.BASEBOARD_FAB2(SCH_1):PAGE176_I162@MSTR_DIGITAL.PCA9617(CHIPS)':
 'SCLA': CDS_PINID='SCLA';
NODE_NAME     R1W36 2
 '@BASEBOARD_FAB2_LIB.BASEBOARD_FAB2(SCH_1):PAGE176_I172@MSTR_DISCRETE.RES(CHIPS)':
 'B': CDS_PINID='B';
NODE_NAME     R1W38 1
 '@BASEBOARD_FAB2_LIB.BASEBOARD_FAB2(SCH_1):PAGE176_I176@MSTR_DISCRETE.RES(CHIPS)':
 'A': CDS_PINID='A';
NET_NAME
'SMB_DEBUG_STBY_LVC3_SCL_R'
 '@BASEBOARD_FAB2_LIB.BASEBOARD_FAB2(SCH_1):SMB_DEBUG_STBY_LVC3_SCL_R':
 C_SIGNAL='@baseboard_fab2_lib.baseboard_fab2(sch_1):smb_debug_stby_lvc3_scl_r';
NODE_NAME     U25W4 C12
 '@BASEBOARD_FAB2_LIB.BASEBOARD_FAB2(SCH_1):PAGE145_I117@W_HDL.AST2520A1-GP-GP(CHIPS)':
 'GPIOC0_SD1CLK_SCL10': CDS_PINID='GPIOC0_SD1CLK_SCL10';
NODE_NAME     R6W17 2
 '@BASEBOARD_FAB2_LIB.BASEBOARD_FAB2(SCH_1):PAGE145_I120@MSTR_DISCRETE.RES(CHIPS)':
 'B': CDS_PINID='B';
NET_NAME
'SMB_DEBUG_STBY_LVC3_SCL_R1'
 '@BASEBOARD_FAB2_LIB.BASEBOARD_FAB2(SCH_1):SMB_DEBUG_STBY_LVC3_SCL_R1':
 C_SIGNAL='@baseboard_fab2_lib.baseboard_fab2(sch_1):smb_debug_stby_lvc3_scl_r1';
NODE_NAME     R1W33 1
 '@BASEBOARD_FAB2_LIB.BASEBOARD_FAB2(SCH_1):PAGE176_I142@MSTR_DISCRETE.RES(CHIPS)':
 'A': CDS_PINID='A';
NODE_NAME     U1W3 7
 '@BASEBOARD_FAB2_LIB.BASEBOARD_FAB2(SCH_1):PAGE176_I162@MSTR_DIGITAL.PCA9617(CHIPS)':
 'SCLB': CDS_PINID='SCLB';
NODE_NAME     R1W38 2
 '@BASEBOARD_FAB2_LIB.BASEBOARD_FAB2(SCH_1):PAGE176_I176@MSTR_DISCRETE.RES(CHIPS)':
 'B': CDS_PINID='B';
NET_NAME
'SMB_DEBUG_STBY_LVC3_SDA'
 '@BASEBOARD_FAB2_LIB.BASEBOARD_FAB2(SCH_1):SMB_DEBUG_STBY_LVC3_SDA':
 C_SIGNAL='@baseboard_fab2_lib.baseboard_fab2(sch_1):smb_debug_stby_lvc3_sda';
NODE_NAME     R6W18 1
 '@BASEBOARD_FAB2_LIB.BASEBOARD_FAB2(SCH_1):PAGE145_I119@MSTR_DISCRETE.RES(CHIPS)':
 'A': CDS_PINID='A';
NODE_NAME     R6W12 1
 '@BASEBOARD_FAB2_LIB.BASEBOARD_FAB2(SCH_1):PAGE247_I99@MSTR_DISCRETE.RES(CHIPS)':
 'A': CDS_PINID='A';
NODE_NAME     U6W1 23
 '@BASEBOARD_FAB2_LIB.BASEBOARD_FAB2(SCH_1):PAGE247_I120@W_HDL.TCA9555PWR-GP(CHIPS)':
 'SDA': CDS_PINID='SDA';
NODE_NAME     R1W34 2
 '@BASEBOARD_FAB2_LIB.BASEBOARD_FAB2(SCH_1):PAGE176_I143@MSTR_DISCRETE.RES(CHIPS)':
 'B': CDS_PINID='B';
NET_NAME
'SMB_DEBUG_STBY_LVC3_SDA_CONN'
 '@BASEBOARD_FAB2_LIB.BASEBOARD_FAB2(SCH_1):SMB_DEBUG_STBY_LVC3_SDA_CONN':
 C_SIGNAL='@baseboard_fab2_lib.baseboard_fab2(sch_1):smb_debug_stby_lvc3_sda_con~
n';
NODE_NAME     J9B1 6
 '@BASEBOARD_FAB2_LIB.BASEBOARD_FAB2(SCH_1):PAGE176_I69@MSTR_CONN.CONN9_H51826001(CHIPS)':
 'STDA_SSRXP': CDS_PINID='STDA_SSRXP';
NODE_NAME     U1W3 3
 '@BASEBOARD_FAB2_LIB.BASEBOARD_FAB2(SCH_1):PAGE176_I162@MSTR_DIGITAL.PCA9617(CHIPS)':
 'SDAA': CDS_PINID='SDAA';
NODE_NAME     R1W37 2
 '@BASEBOARD_FAB2_LIB.BASEBOARD_FAB2(SCH_1):PAGE176_I173@MSTR_DISCRETE.RES(CHIPS)':
 'B': CDS_PINID='B';
NODE_NAME     R1W39 1
 '@BASEBOARD_FAB2_LIB.BASEBOARD_FAB2(SCH_1):PAGE176_I175@MSTR_DISCRETE.RES(CHIPS)':
 'A': CDS_PINID='A';
NET_NAME
'SMB_DEBUG_STBY_LVC3_SDA_R'
 '@BASEBOARD_FAB2_LIB.BASEBOARD_FAB2(SCH_1):SMB_DEBUG_STBY_LVC3_SDA_R':
 C_SIGNAL='@baseboard_fab2_lib.baseboard_fab2(sch_1):smb_debug_stby_lvc3_sda_r';
NODE_NAME     U25W4 A12
 '@BASEBOARD_FAB2_LIB.BASEBOARD_FAB2(SCH_1):PAGE145_I117@W_HDL.AST2520A1-GP-GP(CHIPS)':
 'GPIOC1_SD1CMD_SDA10': CDS_PINID='GPIOC1_SD1CMD_SDA10';
NODE_NAME     R6W18 2
 '@BASEBOARD_FAB2_LIB.BASEBOARD_FAB2(SCH_1):PAGE145_I119@MSTR_DISCRETE.RES(CHIPS)':
 'B': CDS_PINID='B';
NET_NAME
'SMB_DEBUG_STBY_LVC3_SDA_R1'
 '@BASEBOARD_FAB2_LIB.BASEBOARD_FAB2(SCH_1):SMB_DEBUG_STBY_LVC3_SDA_R1':
 C_SIGNAL='@baseboard_fab2_lib.baseboard_fab2(sch_1):smb_debug_stby_lvc3_sda_r1';
NODE_NAME     R1W34 1
 '@BASEBOARD_FAB2_LIB.BASEBOARD_FAB2(SCH_1):PAGE176_I143@MSTR_DISCRETE.RES(CHIPS)':
 'A': CDS_PINID='A';
NODE_NAME     U1W3 6
 '@BASEBOARD_FAB2_LIB.BASEBOARD_FAB2(SCH_1):PAGE176_I162@MSTR_DIGITAL.PCA9617(CHIPS)':
 'SDAB': CDS_PINID='SDAB';
NODE_NAME     R1W39 2
 '@BASEBOARD_FAB2_LIB.BASEBOARD_FAB2(SCH_1):PAGE176_I175@MSTR_DISCRETE.RES(CHIPS)':
 'B': CDS_PINID='B';
NET_NAME
'SMB_HFI0_CPU0_LVC2_SCL'
 '@BASEBOARD_FAB2_LIB.BASEBOARD_FAB2(SCH_1):SMB_HFI0_CPU0_LVC2_SCL':
 C_SIGNAL='@baseboard_fab2_lib.baseboard_fab2(sch_1):smb_hfi0_cpu0_lvc2_scl';
NODE_NAME     U5D1 BN22
 '@BASEBOARD_FAB2_LIB.BASEBOARD_FAB2(SCH_1):PAGE29_I61@CHPSET_LIB.SKX_EXT_B(CHIPS)':
 'CD_HFI0_I2CCLK': CDS_PINID='CD_HFI0_I2CCLK';
NODE_NAME     J8B1 2
 '@BASEBOARD_FAB2_LIB.BASEBOARD_FAB2(SCH_1):PAGE91_I1@MSTR_SCONN.SCONN24_H46321001(CHIPS)':
 'IO2': CDS_PINID='IO2';
NODE_NAME     R8B6 2
 '@BASEBOARD_FAB2_LIB.BASEBOARD_FAB2(SCH_1):PAGE91_I37@MSTR_DISCRETE.RES(CHIPS)':
 'B': CDS_PINID='B';
NET_NAME
'SMB_HFI0_CPU0_LVC2_SDA'
 '@BASEBOARD_FAB2_LIB.BASEBOARD_FAB2(SCH_1):SMB_HFI0_CPU0_LVC2_SDA':
 C_SIGNAL='@baseboard_fab2_lib.baseboard_fab2(sch_1):smb_hfi0_cpu0_lvc2_sda';
NODE_NAME     U5D1 BP23
 '@BASEBOARD_FAB2_LIB.BASEBOARD_FAB2(SCH_1):PAGE29_I61@CHPSET_LIB.SKX_EXT_B(CHIPS)':
 'CD_HFI0_I2CDAT': CDS_PINID='CD_HFI0_I2CDAT';
NODE_NAME     J8B1 4
 '@BASEBOARD_FAB2_LIB.BASEBOARD_FAB2(SCH_1):PAGE91_I1@MSTR_SCONN.SCONN24_H46321001(CHIPS)':
 'IO4': CDS_PINID='IO4';
NODE_NAME     R8B7 2
 '@BASEBOARD_FAB2_LIB.BASEBOARD_FAB2(SCH_1):PAGE91_I36@MSTR_DISCRETE.RES(CHIPS)':
 'B': CDS_PINID='B';
NET_NAME
'SMB_HFI1_CPU0_LVC2_SCL'
 '@BASEBOARD_FAB2_LIB.BASEBOARD_FAB2(SCH_1):SMB_HFI1_CPU0_LVC2_SCL':
 C_SIGNAL='@baseboard_fab2_lib.baseboard_fab2(sch_1):smb_hfi1_cpu0_lvc2_scl';
NODE_NAME     U5D1 BJ22
 '@BASEBOARD_FAB2_LIB.BASEBOARD_FAB2(SCH_1):PAGE29_I61@CHPSET_LIB.SKX_EXT_B(CHIPS)':
 'CD_HFI1_I2CCLK': CDS_PINID='CD_HFI1_I2CCLK';
NODE_NAME     J8B1 10
 '@BASEBOARD_FAB2_LIB.BASEBOARD_FAB2(SCH_1):PAGE91_I1@MSTR_SCONN.SCONN24_H46321001(CHIPS)':
 'IO10': CDS_PINID='IO10';
NODE_NAME     R8B11 2
 '@BASEBOARD_FAB2_LIB.BASEBOARD_FAB2(SCH_1):PAGE91_I35@MSTR_DISCRETE.RES(CHIPS)':
 'B': CDS_PINID='B';
NET_NAME
'SMB_HFI1_CPU0_LVC2_SDA'
 '@BASEBOARD_FAB2_LIB.BASEBOARD_FAB2(SCH_1):SMB_HFI1_CPU0_LVC2_SDA':
 C_SIGNAL='@baseboard_fab2_lib.baseboard_fab2(sch_1):smb_hfi1_cpu0_lvc2_sda';
NODE_NAME     U5D1 BH23
 '@BASEBOARD_FAB2_LIB.BASEBOARD_FAB2(SCH_1):PAGE29_I61@CHPSET_LIB.SKX_EXT_B(CHIPS)':
 'CD_HFI1_I2CDAT': CDS_PINID='CD_HFI1_I2CDAT';
NODE_NAME     J8B1 12
 '@BASEBOARD_FAB2_LIB.BASEBOARD_FAB2(SCH_1):PAGE91_I1@MSTR_SCONN.SCONN24_H46321001(CHIPS)':
 'IO12': CDS_PINID='IO12';
NODE_NAME     R8B13 2
 '@BASEBOARD_FAB2_LIB.BASEBOARD_FAB2(SCH_1):PAGE91_I34@MSTR_DISCRETE.RES(CHIPS)':
 'B': CDS_PINID='B';
NET_NAME
'SMB_HOST_STBY_LVC3_SCL'
 '@BASEBOARD_FAB2_LIB.BASEBOARD_FAB2(SCH_1):SMB_HOST_STBY_LVC3_SCL':
 C_SIGNAL='@baseboard_fab2_lib.baseboard_fab2(sch_1):smb_host_stby_lvc3_scl';
NODE_NAME     J9A3 53
 '@BASEBOARD_FAB2_LIB.BASEBOARD_FAB2(SCH_1):PAGE111_I26@MSTR_SCONN.SCONN60_C21100002(CHIPS)':
 'IO53': CDS_PINID='IO53';
NODE_NAME     R8C14 2
 '@BASEBOARD_FAB2_LIB.BASEBOARD_FAB2(SCH_1):PAGE138_I168@MSTR_DISCRETE.RES(CHIPS)':
 'B': CDS_PINID='B';
NODE_NAME     J8C1 3
 '@BASEBOARD_FAB2_LIB.BASEBOARD_FAB2(SCH_1):PAGE156_I285@MSTR_CONN.CONN3_C95678002(CHIPS)':
 'IO3': CDS_PINID='IO3';
NODE_NAME     R2U34 2
 '@BASEBOARD_FAB2_LIB.BASEBOARD_FAB2(SCH_1):PAGE159_I230@MSTR_DISCRETE.RES(CHIPS)':
 'B': CDS_PINID='B';
NODE_NAME     R6W22 1
 '@BASEBOARD_FAB2_LIB.BASEBOARD_FAB2(SCH_1):PAGE247_I94@MSTR_DISCRETE.RES(CHIPS)':
 'A': CDS_PINID='A';
NODE_NAME     R1W22 1
 '@BASEBOARD_FAB2_LIB.BASEBOARD_FAB2(SCH_1):PAGE101_I134@MSTR_DISCRETE.RES(CHIPS)':
 'A': CDS_PINID='A';
NODE_NAME     R8W5 1
 '@BASEBOARD_FAB2_LIB.BASEBOARD_FAB2(SCH_1):PAGE138_I194@MSTR_DISCRETE.RES(CHIPS)':
 'A': CDS_PINID='A';
NODE_NAME     Q4W1 3
 '@BASEBOARD_FAB2_LIB.BASEBOARD_FAB2(SCH_1):PAGE102_I101@MSTR_DISCRETE.FET_N_DUAL(CHIPS)':
 'DRAIN'<0>: CDS_PINID='DRAIN(0)';
NET_NAME
'SMB_HOST_STBY_LVC3_SCL_R'
 '@BASEBOARD_FAB2_LIB.BASEBOARD_FAB2(SCH_1):SMB_HOST_STBY_LVC3_SCL_R':
 C_SIGNAL='@baseboard_fab2_lib.baseboard_fab2(sch_1):smb_host_stby_lvc3_scl_r';
NODE_NAME     R2U34 1
 '@BASEBOARD_FAB2_LIB.BASEBOARD_FAB2(SCH_1):PAGE159_I230@MSTR_DISCRETE.RES(CHIPS)':
 'A': CDS_PINID='A';
NODE_NAME     U25W4 A9
 '@BASEBOARD_FAB2_LIB.BASEBOARD_FAB2(SCH_1):PAGE144_I95@W_HDL.AST2520A1-GP-GP(CHIPS)':
 'GPIOQ2_SCL4': CDS_PINID='GPIOQ2_SCL4';
NODE_NAME     R8C15 2
 '@BASEBOARD_FAB2_LIB.BASEBOARD_FAB2(SCH_1):PAGE159_I235@MSTR_DISCRETE.RES(CHIPS)':
 'B': CDS_PINID='B';
NET_NAME
'SMB_HOST_STBY_LVC3_SCL_R1'
 '@BASEBOARD_FAB2_LIB.BASEBOARD_FAB2(SCH_1):SMB_HOST_STBY_LVC3_SCL_R1':
 C_SIGNAL='@baseboard_fab2_lib.baseboard_fab2(sch_1):smb_host_stby_lvc3_scl_r1';
NODE_NAME     U7C1 BW28
 '@BASEBOARD_FAB2_LIB.BASEBOARD_FAB2(SCH_1):PAGE119_I115@MSTR_U_PROC.LBG_CORE_QAT_EXT_D(CHIPS)':
 'GPP_C0_SMBCLK': CDS_PINID='GPP_C0_SMBCLK';
NODE_NAME     R8C14 1
 '@BASEBOARD_FAB2_LIB.BASEBOARD_FAB2(SCH_1):PAGE138_I168@MSTR_DISCRETE.RES(CHIPS)':
 'A': CDS_PINID='A';
NET_NAME
'SMB_HOST_STBY_LVC3_SCL_R2'
 '@BASEBOARD_FAB2_LIB.BASEBOARD_FAB2(SCH_1):SMB_HOST_STBY_LVC3_SCL_R2':
 C_SIGNAL='@baseboard_fab2_lib.baseboard_fab2(sch_1):smb_host_stby_lvc3_scl_r2';
NODE_NAME     EU4D2 13
 '@BASEBOARD_FAB2_LIB.BASEBOARD_FAB2(SCH_1):PAGE102_I1@MSTR_CLOCK.NB3W1200L(CHIPS)':
 'SCL': CDS_PINID='SCL';
NODE_NAME     Q4W1 4
 '@BASEBOARD_FAB2_LIB.BASEBOARD_FAB2(SCH_1):PAGE102_I101@MSTR_DISCRETE.FET_N_DUAL(CHIPS)':
 'SOURCE'<0>: CDS_PINID='SOURCE(0)';
NODE_NAME     R4W4 2
 '@BASEBOARD_FAB2_LIB.BASEBOARD_FAB2(SCH_1):PAGE102_I106@MSTR_DISCRETE.RES(CHIPS)':
 'B': CDS_PINID='B';
NET_NAME
'SMB_HOST_STBY_LVC3_SCL_R3'
 '@BASEBOARD_FAB2_LIB.BASEBOARD_FAB2(SCH_1):SMB_HOST_STBY_LVC3_SCL_R3':
 C_SIGNAL='@baseboard_fab2_lib.baseboard_fab2(sch_1):smb_host_stby_lvc3_scl_r3';
NODE_NAME     U6W3 6
 '@BASEBOARD_FAB2_LIB.BASEBOARD_FAB2(SCH_1):PAGE247_I89@MSTR_MEMORY.AT24C64(CHIPS)':
 'SCL': CDS_PINID='SCL';
NODE_NAME     R6W22 2
 '@BASEBOARD_FAB2_LIB.BASEBOARD_FAB2(SCH_1):PAGE247_I94@MSTR_DISCRETE.RES(CHIPS)':
 'B': CDS_PINID='B';
NET_NAME
'SMB_HOST_STBY_LVC3_SCL_R4'
 '@BASEBOARD_FAB2_LIB.BASEBOARD_FAB2(SCH_1):SMB_HOST_STBY_LVC3_SCL_R4':
 C_SIGNAL='@baseboard_fab2_lib.baseboard_fab2(sch_1):smb_host_stby_lvc3_scl_r4';
NODE_NAME     EU8F2 38
 '@BASEBOARD_FAB2_LIB.BASEBOARD_FAB2(SCH_1):PAGE101_I34@MSTR_CLOCK.ICS9FGP204(CHIPS)':
 'SMBCLK': CDS_PINID='SMBCLK';
NODE_NAME     R1W22 2
 '@BASEBOARD_FAB2_LIB.BASEBOARD_FAB2(SCH_1):PAGE101_I134@MSTR_DISCRETE.RES(CHIPS)':
 'B': CDS_PINID='B';
NET_NAME
'SMB_HOST_STBY_LVC3_SCL_R5'
 '@BASEBOARD_FAB2_LIB.BASEBOARD_FAB2(SCH_1):SMB_HOST_STBY_LVC3_SCL_R5':
 C_SIGNAL='@baseboard_fab2_lib.baseboard_fab2(sch_1):smb_host_stby_lvc3_scl_r5';
NODE_NAME     J8G1 32
 '@BASEBOARD_FAB2_LIB.BASEBOARD_FAB2(SCH_1):PAGE108_I258@MSTR_SCONN.SCONN200_H68296001(CHIPS)':
 'IO32': CDS_PINID='IO32';
NODE_NAME     R8B26 2
 '@BASEBOARD_FAB2_LIB.BASEBOARD_FAB2(SCH_1):PAGE138_I187@MSTR_DISCRETE.RES(CHIPS)':
 'B': CDS_PINID='B';
NODE_NAME     R8W5 2
 '@BASEBOARD_FAB2_LIB.BASEBOARD_FAB2(SCH_1):PAGE138_I194@MSTR_DISCRETE.RES(CHIPS)':
 'B': CDS_PINID='B';
NET_NAME
'SMB_HOST_STBY_LVC3_SDA'
 '@BASEBOARD_FAB2_LIB.BASEBOARD_FAB2(SCH_1):SMB_HOST_STBY_LVC3_SDA':
 C_SIGNAL='@baseboard_fab2_lib.baseboard_fab2(sch_1):smb_host_stby_lvc3_sda';
NODE_NAME     J9A3 51
 '@BASEBOARD_FAB2_LIB.BASEBOARD_FAB2(SCH_1):PAGE111_I26@MSTR_SCONN.SCONN60_C21100002(CHIPS)':
 'IO51': CDS_PINID='IO51';
NODE_NAME     R8C20 2
 '@BASEBOARD_FAB2_LIB.BASEBOARD_FAB2(SCH_1):PAGE138_I167@MSTR_DISCRETE.RES(CHIPS)':
 'B': CDS_PINID='B';
NODE_NAME     J8C1 1
 '@BASEBOARD_FAB2_LIB.BASEBOARD_FAB2(SCH_1):PAGE156_I285@MSTR_CONN.CONN3_C95678002(CHIPS)':
 'IO1': CDS_PINID='IO1';
NODE_NAME     R2U33 2
 '@BASEBOARD_FAB2_LIB.BASEBOARD_FAB2(SCH_1):PAGE159_I231@MSTR_DISCRETE.RES(CHIPS)':
 'B': CDS_PINID='B';
NODE_NAME     R6W20 2
 '@BASEBOARD_FAB2_LIB.BASEBOARD_FAB2(SCH_1):PAGE247_I87@MSTR_DISCRETE.RES(CHIPS)':
 'B': CDS_PINID='B';
NODE_NAME     R1W23 1
 '@BASEBOARD_FAB2_LIB.BASEBOARD_FAB2(SCH_1):PAGE101_I135@MSTR_DISCRETE.RES(CHIPS)':
 'A': CDS_PINID='A';
NODE_NAME     R8W4 1
 '@BASEBOARD_FAB2_LIB.BASEBOARD_FAB2(SCH_1):PAGE138_I195@MSTR_DISCRETE.RES(CHIPS)':
 'A': CDS_PINID='A';
NODE_NAME     Q4W1 6
 '@BASEBOARD_FAB2_LIB.BASEBOARD_FAB2(SCH_1):PAGE102_I102@MSTR_DISCRETE.FET_N_DUAL(CHIPS)':
 'DRAIN'<0>: CDS_PINID='DRAIN(0)';
NET_NAME
'SMB_HOST_STBY_LVC3_SDA_R'
 '@BASEBOARD_FAB2_LIB.BASEBOARD_FAB2(SCH_1):SMB_HOST_STBY_LVC3_SDA_R':
 C_SIGNAL='@baseboard_fab2_lib.baseboard_fab2(sch_1):smb_host_stby_lvc3_sda_r';
NODE_NAME     R2U33 1
 '@BASEBOARD_FAB2_LIB.BASEBOARD_FAB2(SCH_1):PAGE159_I231@MSTR_DISCRETE.RES(CHIPS)':
 'A': CDS_PINID='A';
NODE_NAME     U25W4 B9
 '@BASEBOARD_FAB2_LIB.BASEBOARD_FAB2(SCH_1):PAGE144_I95@W_HDL.AST2520A1-GP-GP(CHIPS)':
 'GPIOQ3_SDA4': CDS_PINID='GPIOQ3_SDA4';
NODE_NAME     R8C16 2
 '@BASEBOARD_FAB2_LIB.BASEBOARD_FAB2(SCH_1):PAGE159_I237@MSTR_DISCRETE.RES(CHIPS)':
 'B': CDS_PINID='B';
NET_NAME
'SMB_HOST_STBY_LVC3_SDA_R1'
 '@BASEBOARD_FAB2_LIB.BASEBOARD_FAB2(SCH_1):SMB_HOST_STBY_LVC3_SDA_R1':
 C_SIGNAL='@baseboard_fab2_lib.baseboard_fab2(sch_1):smb_host_stby_lvc3_sda_r1';
NODE_NAME     U7C1 BV27
 '@BASEBOARD_FAB2_LIB.BASEBOARD_FAB2(SCH_1):PAGE119_I115@MSTR_U_PROC.LBG_CORE_QAT_EXT_D(CHIPS)':
 'GPP_C1_SMBDATA': CDS_PINID='GPP_C1_SMBDATA';
NODE_NAME     R8C20 1
 '@BASEBOARD_FAB2_LIB.BASEBOARD_FAB2(SCH_1):PAGE138_I167@MSTR_DISCRETE.RES(CHIPS)':
 'A': CDS_PINID='A';
NET_NAME
'SMB_HOST_STBY_LVC3_SDA_R2'
 '@BASEBOARD_FAB2_LIB.BASEBOARD_FAB2(SCH_1):SMB_HOST_STBY_LVC3_SDA_R2':
 C_SIGNAL='@baseboard_fab2_lib.baseboard_fab2(sch_1):smb_host_stby_lvc3_sda_r2';
NODE_NAME     EU4D2 12
 '@BASEBOARD_FAB2_LIB.BASEBOARD_FAB2(SCH_1):PAGE102_I1@MSTR_CLOCK.NB3W1200L(CHIPS)':
 'SDA': CDS_PINID='SDA';
NODE_NAME     Q4W1 1
 '@BASEBOARD_FAB2_LIB.BASEBOARD_FAB2(SCH_1):PAGE102_I102@MSTR_DISCRETE.FET_N_DUAL(CHIPS)':
 'SOURCE'<0>: CDS_PINID='SOURCE(0)';
NODE_NAME     R4W3 2
 '@BASEBOARD_FAB2_LIB.BASEBOARD_FAB2(SCH_1):PAGE102_I105@MSTR_DISCRETE.RES(CHIPS)':
 'B': CDS_PINID='B';
NET_NAME
'SMB_HOST_STBY_LVC3_SDA_R3'
 '@BASEBOARD_FAB2_LIB.BASEBOARD_FAB2(SCH_1):SMB_HOST_STBY_LVC3_SDA_R3':
 C_SIGNAL='@baseboard_fab2_lib.baseboard_fab2(sch_1):smb_host_stby_lvc3_sda_r3';
NODE_NAME     R6W20 1
 '@BASEBOARD_FAB2_LIB.BASEBOARD_FAB2(SCH_1):PAGE247_I87@MSTR_DISCRETE.RES(CHIPS)':
 'A': CDS_PINID='A';
NODE_NAME     U6W3 5
 '@BASEBOARD_FAB2_LIB.BASEBOARD_FAB2(SCH_1):PAGE247_I89@MSTR_MEMORY.AT24C64(CHIPS)':
 'SDA': CDS_PINID='SDA';
NET_NAME
'SMB_HOST_STBY_LVC3_SDA_R4'
 '@BASEBOARD_FAB2_LIB.BASEBOARD_FAB2(SCH_1):SMB_HOST_STBY_LVC3_SDA_R4':
 C_SIGNAL='@baseboard_fab2_lib.baseboard_fab2(sch_1):smb_host_stby_lvc3_sda_r4';
NODE_NAME     EU8F2 39
 '@BASEBOARD_FAB2_LIB.BASEBOARD_FAB2(SCH_1):PAGE101_I34@MSTR_CLOCK.ICS9FGP204(CHIPS)':
 'SMBDAT': CDS_PINID='SMBDAT';
NODE_NAME     R1W23 2
 '@BASEBOARD_FAB2_LIB.BASEBOARD_FAB2(SCH_1):PAGE101_I135@MSTR_DISCRETE.RES(CHIPS)':
 'B': CDS_PINID='B';
NET_NAME
'SMB_HOST_STBY_LVC3_SDA_R5'
 '@BASEBOARD_FAB2_LIB.BASEBOARD_FAB2(SCH_1):SMB_HOST_STBY_LVC3_SDA_R5':
 C_SIGNAL='@baseboard_fab2_lib.baseboard_fab2(sch_1):smb_host_stby_lvc3_sda_r5';
NODE_NAME     J8G1 30
 '@BASEBOARD_FAB2_LIB.BASEBOARD_FAB2(SCH_1):PAGE108_I258@MSTR_SCONN.SCONN200_H68296001(CHIPS)':
 'IO30': CDS_PINID='IO30';
NODE_NAME     R8B24 2
 '@BASEBOARD_FAB2_LIB.BASEBOARD_FAB2(SCH_1):PAGE138_I186@MSTR_DISCRETE.RES(CHIPS)':
 'B': CDS_PINID='B';
NODE_NAME     R8W4 2
 '@BASEBOARD_FAB2_LIB.BASEBOARD_FAB2(SCH_1):PAGE138_I195@MSTR_DISCRETE.RES(CHIPS)':
 'B': CDS_PINID='B';
NET_NAME
'SMB_LAN_STBY_LVC3_SCL'
 '@BASEBOARD_FAB2_LIB.BASEBOARD_FAB2(SCH_1):SMB_LAN_STBY_LVC3_SCL':
 C_SIGNAL='@baseboard_fab2_lib.baseboard_fab2(sch_1):smb_lan_stby_lvc3_scl';
NODE_NAME     R2U3 2
 '@BASEBOARD_FAB2_LIB.BASEBOARD_FAB2(SCH_1):PAGE138_I98@MSTR_DISCRETE.RES(CHIPS)':
 'B': CDS_PINID='B';
NODE_NAME     R2U8 1
 '@BASEBOARD_FAB2_LIB.BASEBOARD_FAB2(SCH_1):PAGE138_I158@MSTR_DISCRETE.RES(CHIPS)':
 'A': CDS_PINID='A';
NODE_NAME     R2U6 2
 '@BASEBOARD_FAB2_LIB.BASEBOARD_FAB2(SCH_1):PAGE138_I166@MSTR_DISCRETE.RES(CHIPS)':
 'B': CDS_PINID='B';
NODE_NAME     R2N21 2
 '@BASEBOARD_FAB2_LIB.BASEBOARD_FAB2(SCH_1):PAGE138_I175@MSTR_DISCRETE.RES(CHIPS)':
 'B': CDS_PINID='B';
NODE_NAME     R9M20 1
 '@BASEBOARD_FAB2_LIB.BASEBOARD_FAB2(SCH_1):PAGE156_I323@MSTR_DISCRETE.RES(CHIPS)':
 'A': CDS_PINID='A';
NODE_NAME     R4A9 1
 '@BASEBOARD_FAB2_LIB.BASEBOARD_FAB2(SCH_1):PAGE156_I324@MSTR_DISCRETE.RES(CHIPS)':
 'A': CDS_PINID='A';
NODE_NAME     R9F22 2
 '@BASEBOARD_FAB2_LIB.BASEBOARD_FAB2(SCH_1):PAGE160_I52@MSTR_DISCRETE.RES(CHIPS)':
 'B': CDS_PINID='B';
NODE_NAME     R1C11 1
 '@BASEBOARD_FAB2_LIB.BASEBOARD_FAB2(SCH_1):PAGE182_I10@MSTR_DISCRETE.RES(CHIPS)':
 'A': CDS_PINID='A';
NODE_NAME     J1C1 E5
 '@BASEBOARD_FAB2_LIB.BASEBOARD_FAB2(SCH_1):PAGE182_I79@W_HDL.DM-FCI-CONN76-8R-GP-U-01(CHIPS)':
 'MNG_RX_DN': CDS_PINID='MNG_RX_DN';
NET_NAME
'SMB_LAN_STBY_LVC3_SCL_R'
 '@BASEBOARD_FAB2_LIB.BASEBOARD_FAB2(SCH_1):SMB_LAN_STBY_LVC3_SCL_R':
 C_SIGNAL='@baseboard_fab2_lib.baseboard_fab2(sch_1):smb_lan_stby_lvc3_scl_r',
 PHYS_NET_NAME='H_CPU0_FAST_WAKE_LVT3_N';
NODE_NAME     R9F22 1
 '@BASEBOARD_FAB2_LIB.BASEBOARD_FAB2(SCH_1):PAGE160_I52@MSTR_DISCRETE.RES(CHIPS)':
 'A': CDS_PINID='A';
NODE_NAME     U25W4 M18
 '@BASEBOARD_FAB2_LIB.BASEBOARD_FAB2(SCH_1):PAGE144_I95@W_HDL.AST2520A1-GP-GP(CHIPS)':
 'GPIOY4_SCL1': CDS_PINID='GPIOY4_SCL1';
NET_NAME
'SMB_LAN_STBY_LVC3_SCL_R1'
 '@BASEBOARD_FAB2_LIB.BASEBOARD_FAB2(SCH_1):SMB_LAN_STBY_LVC3_SCL_R1':
 C_SIGNAL='@baseboard_fab2_lib.baseboard_fab2(sch_1):smb_lan_stby_lvc3_scl_r1';
NODE_NAME     U7C1 BF1
 '@BASEBOARD_FAB2_LIB.BASEBOARD_FAB2(SCH_1):PAGE120_I147@MSTR_U_PROC.LBG_CORE_QAT_EXT_D(CHIPS)':
 'GPP_H16_SML4CLK_IE': CDS_PINID='GPP_H16_SML4CLK_IE';
NODE_NAME     R2U6 1
 '@BASEBOARD_FAB2_LIB.BASEBOARD_FAB2(SCH_1):PAGE138_I166@MSTR_DISCRETE.RES(CHIPS)':
 'A': CDS_PINID='A';
NET_NAME
'SMB_LAN_STBY_LVC3_SCL_R2'
 '@BASEBOARD_FAB2_LIB.BASEBOARD_FAB2(SCH_1):SMB_LAN_STBY_LVC3_SCL_R2':
 C_SIGNAL='@baseboard_fab2_lib.baseboard_fab2(sch_1):smb_lan_stby_lvc3_scl_r2';
NODE_NAME     U7C1 AU9
 '@BASEBOARD_FAB2_LIB.BASEBOARD_FAB2(SCH_1):PAGE120_I147@MSTR_U_PROC.LBG_CORE_QAT_EXT_D(CHIPS)':
 'GPP_F19_LAN_SMBCLK': CDS_PINID='GPP_F19_LAN_SMBCLK';
NODE_NAME     R2N21 1
 '@BASEBOARD_FAB2_LIB.BASEBOARD_FAB2(SCH_1):PAGE138_I175@MSTR_DISCRETE.RES(CHIPS)':
 'A': CDS_PINID='A';
NET_NAME
'SMB_LAN_STBY_LVC3_SDA'
 '@BASEBOARD_FAB2_LIB.BASEBOARD_FAB2(SCH_1):SMB_LAN_STBY_LVC3_SDA':
 C_SIGNAL='@baseboard_fab2_lib.baseboard_fab2(sch_1):smb_lan_stby_lvc3_sda';
NODE_NAME     R2U11 2
 '@BASEBOARD_FAB2_LIB.BASEBOARD_FAB2(SCH_1):PAGE138_I97@MSTR_DISCRETE.RES(CHIPS)':
 'B': CDS_PINID='B';
NODE_NAME     R2U12 1
 '@BASEBOARD_FAB2_LIB.BASEBOARD_FAB2(SCH_1):PAGE138_I159@MSTR_DISCRETE.RES(CHIPS)':
 'A': CDS_PINID='A';
NODE_NAME     R2U9 2
 '@BASEBOARD_FAB2_LIB.BASEBOARD_FAB2(SCH_1):PAGE138_I165@MSTR_DISCRETE.RES(CHIPS)':
 'B': CDS_PINID='B';
NODE_NAME     R2N20 2
 '@BASEBOARD_FAB2_LIB.BASEBOARD_FAB2(SCH_1):PAGE138_I171@MSTR_DISCRETE.RES(CHIPS)':
 'B': CDS_PINID='B';
NODE_NAME     R9M21 1
 '@BASEBOARD_FAB2_LIB.BASEBOARD_FAB2(SCH_1):PAGE156_I321@MSTR_DISCRETE.RES(CHIPS)':
 'A': CDS_PINID='A';
NODE_NAME     R4A8 1
 '@BASEBOARD_FAB2_LIB.BASEBOARD_FAB2(SCH_1):PAGE156_I322@MSTR_DISCRETE.RES(CHIPS)':
 'A': CDS_PINID='A';
NODE_NAME     R9F23 2
 '@BASEBOARD_FAB2_LIB.BASEBOARD_FAB2(SCH_1):PAGE160_I51@MSTR_DISCRETE.RES(CHIPS)':
 'B': CDS_PINID='B';
NODE_NAME     R1C10 1
 '@BASEBOARD_FAB2_LIB.BASEBOARD_FAB2(SCH_1):PAGE182_I9@MSTR_DISCRETE.RES(CHIPS)':
 'A': CDS_PINID='A';
NODE_NAME     J1C1 D5
 '@BASEBOARD_FAB2_LIB.BASEBOARD_FAB2(SCH_1):PAGE182_I79@W_HDL.DM-FCI-CONN76-8R-GP-U-01(CHIPS)':
 'MNG_RX_DP': CDS_PINID='MNG_RX_DP';
NET_NAME
'SMB_LAN_STBY_LVC3_SDA_R'
 '@BASEBOARD_FAB2_LIB.BASEBOARD_FAB2(SCH_1):SMB_LAN_STBY_LVC3_SDA_R':
 C_SIGNAL='@baseboard_fab2_lib.baseboard_fab2(sch_1):smb_lan_stby_lvc3_sda_r',
 PHYS_NET_NAME='H_CPU0_FAST_WAKE_LVT3_N';
NODE_NAME     R9F23 1
 '@BASEBOARD_FAB2_LIB.BASEBOARD_FAB2(SCH_1):PAGE160_I51@MSTR_DISCRETE.RES(CHIPS)':
 'A': CDS_PINID='A';
NODE_NAME     U25W4 M19
 '@BASEBOARD_FAB2_LIB.BASEBOARD_FAB2(SCH_1):PAGE144_I95@W_HDL.AST2520A1-GP-GP(CHIPS)':
 'GPIOY5_SDA1': CDS_PINID='GPIOY5_SDA1';
NET_NAME
'SMB_LAN_STBY_LVC3_SDA_R1'
 '@BASEBOARD_FAB2_LIB.BASEBOARD_FAB2(SCH_1):SMB_LAN_STBY_LVC3_SDA_R1':
 C_SIGNAL='@baseboard_fab2_lib.baseboard_fab2(sch_1):smb_lan_stby_lvc3_sda_r1';
NODE_NAME     U7C1 BE4
 '@BASEBOARD_FAB2_LIB.BASEBOARD_FAB2(SCH_1):PAGE120_I147@MSTR_U_PROC.LBG_CORE_QAT_EXT_D(CHIPS)':
 'GPP_H17_SML4DATA_IE': CDS_PINID='GPP_H17_SML4DATA_IE';
NODE_NAME     R2U9 1
 '@BASEBOARD_FAB2_LIB.BASEBOARD_FAB2(SCH_1):PAGE138_I165@MSTR_DISCRETE.RES(CHIPS)':
 'A': CDS_PINID='A';
NET_NAME
'SMB_LAN_STBY_LVC3_SDA_R2'
 '@BASEBOARD_FAB2_LIB.BASEBOARD_FAB2(SCH_1):SMB_LAN_STBY_LVC3_SDA_R2':
 C_SIGNAL='@baseboard_fab2_lib.baseboard_fab2(sch_1):smb_lan_stby_lvc3_sda_r2';
NODE_NAME     U7C1 AU20
 '@BASEBOARD_FAB2_LIB.BASEBOARD_FAB2(SCH_1):PAGE120_I147@MSTR_U_PROC.LBG_CORE_QAT_EXT_D(CHIPS)':
 'GPP_F20_LAN_SMBDATA': CDS_PINID='GPP_F20_LAN_SMBDATA';
NODE_NAME     R2N20 1
 '@BASEBOARD_FAB2_LIB.BASEBOARD_FAB2(SCH_1):PAGE138_I171@MSTR_DISCRETE.RES(CHIPS)':
 'A': CDS_PINID='A';
NET_NAME
'SMB_M2_ALT_N'
 '@BASEBOARD_FAB2_LIB.BASEBOARD_FAB2(SCH_1):SMB_M2_ALT_N':
 C_SIGNAL='@baseboard_fab2_lib.baseboard_fab2(sch_1):smb_m2_alt_n';
NODE_NAME     J8F1 44
 '@BASEBOARD_FAB2_LIB.BASEBOARD_FAB2(SCH_1):PAGE185_I143@W_HDL.SKT-MINI67P-41-GP(CHIPS)':
 '44': CDS_PINID='\44\';
NODE_NAME     R32W12 1
 '@BASEBOARD_FAB2_LIB.BASEBOARD_FAB2(SCH_1):PAGE185_I187@MSTR_DISCRETE.RES(CHIPS)':
 'A': CDS_PINID='A';
NODE_NAME     R32W7 2
 '@BASEBOARD_FAB2_LIB.BASEBOARD_FAB2(SCH_1):PAGE185_I215@MSTR_DISCRETE.RES(CHIPS)':
 'B': CDS_PINID='B';
NET_NAME
'SMB_M2_ALT_R_N'
 '@BASEBOARD_FAB2_LIB.BASEBOARD_FAB2(SCH_1):SMB_M2_ALT_R_N':
 C_SIGNAL='@baseboard_fab2_lib.baseboard_fab2(sch_1):smb_m2_alt_r_n';
NODE_NAME     R32W12 2
 '@BASEBOARD_FAB2_LIB.BASEBOARD_FAB2(SCH_1):PAGE185_I187@MSTR_DISCRETE.RES(CHIPS)':
 'B': CDS_PINID='B';
NODE_NAME     U32W2 2
 '@BASEBOARD_FAB2_LIB.BASEBOARD_FAB2(SCH_1):PAGE185_I204@W_HDL.TCA9517DGKR-GP(CHIPS)':
 'SCLA': CDS_PINID='SCLA';
NET_NAME
'SMB_M2_SCL'
 '@BASEBOARD_FAB2_LIB.BASEBOARD_FAB2(SCH_1):SMB_M2_SCL':
 C_SIGNAL='@baseboard_fab2_lib.baseboard_fab2(sch_1):smb_m2_scl';
NODE_NAME     J8F1 40
 '@BASEBOARD_FAB2_LIB.BASEBOARD_FAB2(SCH_1):PAGE185_I143@W_HDL.SKT-MINI67P-41-GP(CHIPS)':
 '40': CDS_PINID='\40\';
NODE_NAME     R32W10 1
 '@BASEBOARD_FAB2_LIB.BASEBOARD_FAB2(SCH_1):PAGE185_I183@MSTR_DISCRETE.RES(CHIPS)':
 'A': CDS_PINID='A';
NODE_NAME     R32W5 2
 '@BASEBOARD_FAB2_LIB.BASEBOARD_FAB2(SCH_1):PAGE185_I216@MSTR_DISCRETE.RES(CHIPS)':
 'B': CDS_PINID='B';
NET_NAME
'SMB_M2_SCL_R'
 '@BASEBOARD_FAB2_LIB.BASEBOARD_FAB2(SCH_1):SMB_M2_SCL_R':
 C_SIGNAL='@baseboard_fab2_lib.baseboard_fab2(sch_1):smb_m2_scl_r';
NODE_NAME     R32W10 2
 '@BASEBOARD_FAB2_LIB.BASEBOARD_FAB2(SCH_1):PAGE185_I183@MSTR_DISCRETE.RES(CHIPS)':
 'B': CDS_PINID='B';
NODE_NAME     U32W1 2
 '@BASEBOARD_FAB2_LIB.BASEBOARD_FAB2(SCH_1):PAGE185_I191@W_HDL.TCA9517DGKR-GP(CHIPS)':
 'SCLA': CDS_PINID='SCLA';
NET_NAME
'SMB_M2_SDA'
 '@BASEBOARD_FAB2_LIB.BASEBOARD_FAB2(SCH_1):SMB_M2_SDA':
 C_SIGNAL='@baseboard_fab2_lib.baseboard_fab2(sch_1):smb_m2_sda';
NODE_NAME     J8F1 42
 '@BASEBOARD_FAB2_LIB.BASEBOARD_FAB2(SCH_1):PAGE185_I143@W_HDL.SKT-MINI67P-41-GP(CHIPS)':
 '42': CDS_PINID='\42\';
NODE_NAME     R32W11 1
 '@BASEBOARD_FAB2_LIB.BASEBOARD_FAB2(SCH_1):PAGE185_I184@MSTR_DISCRETE.RES(CHIPS)':
 'A': CDS_PINID='A';
NODE_NAME     R32W6 2
 '@BASEBOARD_FAB2_LIB.BASEBOARD_FAB2(SCH_1):PAGE185_I214@MSTR_DISCRETE.RES(CHIPS)':
 'B': CDS_PINID='B';
NET_NAME
'SMB_M2_SDA_R'
 '@BASEBOARD_FAB2_LIB.BASEBOARD_FAB2(SCH_1):SMB_M2_SDA_R':
 C_SIGNAL='@baseboard_fab2_lib.baseboard_fab2(sch_1):smb_m2_sda_r';
NODE_NAME     R32W11 2
 '@BASEBOARD_FAB2_LIB.BASEBOARD_FAB2(SCH_1):PAGE185_I184@MSTR_DISCRETE.RES(CHIPS)':
 'B': CDS_PINID='B';
NODE_NAME     U32W1 3
 '@BASEBOARD_FAB2_LIB.BASEBOARD_FAB2(SCH_1):PAGE185_I191@W_HDL.TCA9517DGKR-GP(CHIPS)':
 'SDAA': CDS_PINID='SDAA';
NET_NAME
'SMB_OCP_FRU_STBY_LVC3_SCL'
 '@BASEBOARD_FAB2_LIB.BASEBOARD_FAB2(SCH_1):SMB_OCP_FRU_STBY_LVC3_SCL':
 C_SIGNAL='@baseboard_fab2_lib.baseboard_fab2(sch_1):smb_ocp_fru_stby_lvc3_scl';
NODE_NAME     J8B1 22
 '@BASEBOARD_FAB2_LIB.BASEBOARD_FAB2(SCH_1):PAGE91_I1@MSTR_SCONN.SCONN24_H46321001(CHIPS)':
 'IO22': CDS_PINID='IO22';
NODE_NAME     R2U8 2
 '@BASEBOARD_FAB2_LIB.BASEBOARD_FAB2(SCH_1):PAGE138_I158@MSTR_DISCRETE.RES(CHIPS)':
 'B': CDS_PINID='B';
NODE_NAME     R2U7 2
 '@BASEBOARD_FAB2_LIB.BASEBOARD_FAB2(SCH_1):PAGE159_I220@MSTR_DISCRETE.RES(CHIPS)':
 'B': CDS_PINID='B';
NODE_NAME     J9B3 30
 '@BASEBOARD_FAB2_LIB.BASEBOARD_FAB2(SCH_1):PAGE186_I336@MSTR_SCONN.SCONN120_A28699018(CHIPS)':
 'IO30': CDS_PINID='IO30';
NODE_NAME     J8E4 1
 '@BASEBOARD_FAB2_LIB.BASEBOARD_FAB2(SCH_1):PAGE188_I27@MSTR_SCONN.SCONN64_H87568002_A(CHIPS)':
 'IO1': CDS_PINID='IO1';
NET_NAME
'SMB_OCP_FRU_STBY_LVC3_SCL_R'
 '@BASEBOARD_FAB2_LIB.BASEBOARD_FAB2(SCH_1):SMB_OCP_FRU_STBY_LVC3_SCL_R':
 C_SIGNAL='@baseboard_fab2_lib.baseboard_fab2(sch_1):smb_ocp_fru_stby_lvc3_scl_r~
';
NODE_NAME     R2U5 2
 '@BASEBOARD_FAB2_LIB.BASEBOARD_FAB2(SCH_1):PAGE159_I214@MSTR_DISCRETE.RES(CHIPS)':
 'B': CDS_PINID='B';
NODE_NAME     R2U7 1
 '@BASEBOARD_FAB2_LIB.BASEBOARD_FAB2(SCH_1):PAGE159_I220@MSTR_DISCRETE.RES(CHIPS)':
 'A': CDS_PINID='A';
NODE_NAME     U25W4 C14
 '@BASEBOARD_FAB2_LIB.BASEBOARD_FAB2(SCH_1):PAGE144_I95@W_HDL.AST2520A1-GP-GP(CHIPS)':
 'GPIOA4_TIMER5_SCL9': CDS_PINID='GPIOA4_TIMER5_SCL9';
NET_NAME
'SMB_OCP_FRU_STBY_LVC3_SDA'
 '@BASEBOARD_FAB2_LIB.BASEBOARD_FAB2(SCH_1):SMB_OCP_FRU_STBY_LVC3_SDA':
 C_SIGNAL='@baseboard_fab2_lib.baseboard_fab2(sch_1):smb_ocp_fru_stby_lvc3_sda';
NODE_NAME     J8B1 24
 '@BASEBOARD_FAB2_LIB.BASEBOARD_FAB2(SCH_1):PAGE91_I1@MSTR_SCONN.SCONN24_H46321001(CHIPS)':
 'IO24': CDS_PINID='IO24';
NODE_NAME     R2U12 2
 '@BASEBOARD_FAB2_LIB.BASEBOARD_FAB2(SCH_1):PAGE138_I159@MSTR_DISCRETE.RES(CHIPS)':
 'B': CDS_PINID='B';
NODE_NAME     R2U10 2
 '@BASEBOARD_FAB2_LIB.BASEBOARD_FAB2(SCH_1):PAGE159_I221@MSTR_DISCRETE.RES(CHIPS)':
 'B': CDS_PINID='B';
NODE_NAME     J9B3 32
 '@BASEBOARD_FAB2_LIB.BASEBOARD_FAB2(SCH_1):PAGE186_I336@MSTR_SCONN.SCONN120_A28699018(CHIPS)':
 'IO32': CDS_PINID='IO32';
NODE_NAME     J8E4 2
 '@BASEBOARD_FAB2_LIB.BASEBOARD_FAB2(SCH_1):PAGE188_I27@MSTR_SCONN.SCONN64_H87568002_A(CHIPS)':
 'IO2': CDS_PINID='IO2';
NET_NAME
'SMB_OCP_FRU_STBY_LVC3_SDA_R'
 '@BASEBOARD_FAB2_LIB.BASEBOARD_FAB2(SCH_1):SMB_OCP_FRU_STBY_LVC3_SDA_R':
 C_SIGNAL='@baseboard_fab2_lib.baseboard_fab2(sch_1):smb_ocp_fru_stby_lvc3_sda_r~
';
NODE_NAME     R2U13 2
 '@BASEBOARD_FAB2_LIB.BASEBOARD_FAB2(SCH_1):PAGE159_I216@MSTR_DISCRETE.RES(CHIPS)':
 'B': CDS_PINID='B';
NODE_NAME     R2U10 1
 '@BASEBOARD_FAB2_LIB.BASEBOARD_FAB2(SCH_1):PAGE159_I221@MSTR_DISCRETE.RES(CHIPS)':
 'A': CDS_PINID='A';
NODE_NAME     U25W4 A13
 '@BASEBOARD_FAB2_LIB.BASEBOARD_FAB2(SCH_1):PAGE144_I95@W_HDL.AST2520A1-GP-GP(CHIPS)':
 'GPIOA5_TIMER6_SDA9': CDS_PINID='GPIOA5_TIMER6_SDA9';
NET_NAME
'SMB_OCP_LAN_STBY_LVC3_SCL'
 '@BASEBOARD_FAB2_LIB.BASEBOARD_FAB2(SCH_1):SMB_OCP_LAN_STBY_LVC3_SCL':
 C_SIGNAL='@baseboard_fab2_lib.baseboard_fab2(sch_1):smb_ocp_lan_stby_lvc3_scl';
NODE_NAME     R9G13 1
 '@BASEBOARD_FAB2_LIB.BASEBOARD_FAB2(SCH_1):PAGE159_I227@MSTR_DISCRETE.RES(CHIPS)':
 'A': CDS_PINID='A';
NODE_NAME     R8G4 2
 '@BASEBOARD_FAB2_LIB.BASEBOARD_FAB2(SCH_1):PAGE159_I229@MSTR_DISCRETE.RES(CHIPS)':
 'B': CDS_PINID='B';
NODE_NAME     J9B3 35
 '@BASEBOARD_FAB2_LIB.BASEBOARD_FAB2(SCH_1):PAGE186_I336@MSTR_SCONN.SCONN120_A28699018(CHIPS)':
 'IO35': CDS_PINID='IO35';
NODE_NAME     U32W1 7
 '@BASEBOARD_FAB2_LIB.BASEBOARD_FAB2(SCH_1):PAGE185_I191@W_HDL.TCA9517DGKR-GP(CHIPS)':
 'SCLB': CDS_PINID='SCLB';
NET_NAME
'SMB_OCP_LAN_STBY_LVC3_SCL_R'
 '@BASEBOARD_FAB2_LIB.BASEBOARD_FAB2(SCH_1):SMB_OCP_LAN_STBY_LVC3_SCL_R':
 C_SIGNAL='@baseboard_fab2_lib.baseboard_fab2(sch_1):smb_ocp_lan_stby_lvc3_scl_r~
';
NODE_NAME     R8G3 2
 '@BASEBOARD_FAB2_LIB.BASEBOARD_FAB2(SCH_1):PAGE159_I210@MSTR_DISCRETE.RES(CHIPS)':
 'B': CDS_PINID='B';
NODE_NAME     R8G4 1
 '@BASEBOARD_FAB2_LIB.BASEBOARD_FAB2(SCH_1):PAGE159_I229@MSTR_DISCRETE.RES(CHIPS)':
 'A': CDS_PINID='A';
NODE_NAME     U25W4 A11
 '@BASEBOARD_FAB2_LIB.BASEBOARD_FAB2(SCH_1):PAGE144_I95@W_HDL.AST2520A1-GP-GP(CHIPS)':
 'GPIOQ0_SCL3': CDS_PINID='GPIOQ0_SCL3';
NET_NAME
'SMB_OCP_LAN_STBY_LVC3_SDA'
 '@BASEBOARD_FAB2_LIB.BASEBOARD_FAB2(SCH_1):SMB_OCP_LAN_STBY_LVC3_SDA':
 C_SIGNAL='@baseboard_fab2_lib.baseboard_fab2(sch_1):smb_ocp_lan_stby_lvc3_sda';
NODE_NAME     R9G12 1
 '@BASEBOARD_FAB2_LIB.BASEBOARD_FAB2(SCH_1):PAGE159_I224@MSTR_DISCRETE.RES(CHIPS)':
 'A': CDS_PINID='A';
NODE_NAME     R8G5 2
 '@BASEBOARD_FAB2_LIB.BASEBOARD_FAB2(SCH_1):PAGE159_I228@MSTR_DISCRETE.RES(CHIPS)':
 'B': CDS_PINID='B';
NODE_NAME     J9B3 37
 '@BASEBOARD_FAB2_LIB.BASEBOARD_FAB2(SCH_1):PAGE186_I336@MSTR_SCONN.SCONN120_A28699018(CHIPS)':
 'IO37': CDS_PINID='IO37';
NODE_NAME     U32W1 6
 '@BASEBOARD_FAB2_LIB.BASEBOARD_FAB2(SCH_1):PAGE185_I191@W_HDL.TCA9517DGKR-GP(CHIPS)':
 'SDAB': CDS_PINID='SDAB';
NET_NAME
'SMB_OCP_LAN_STBY_LVC3_SDA_R'
 '@BASEBOARD_FAB2_LIB.BASEBOARD_FAB2(SCH_1):SMB_OCP_LAN_STBY_LVC3_SDA_R':
 C_SIGNAL='@baseboard_fab2_lib.baseboard_fab2(sch_1):smb_ocp_lan_stby_lvc3_sda_r~
';
NODE_NAME     R8G6 2
 '@BASEBOARD_FAB2_LIB.BASEBOARD_FAB2(SCH_1):PAGE159_I212@MSTR_DISCRETE.RES(CHIPS)':
 'B': CDS_PINID='B';
NODE_NAME     R8G5 1
 '@BASEBOARD_FAB2_LIB.BASEBOARD_FAB2(SCH_1):PAGE159_I228@MSTR_DISCRETE.RES(CHIPS)':
 'A': CDS_PINID='A';
NODE_NAME     U25W4 A10
 '@BASEBOARD_FAB2_LIB.BASEBOARD_FAB2(SCH_1):PAGE144_I95@W_HDL.AST2520A1-GP-GP(CHIPS)':
 'GPIOQ1_SDA3': CDS_PINID='GPIOQ1_SDA3';
NET_NAME
'SMB_PCH_MEZZ_LOM0_SCL'
 '@BASEBOARD_FAB2_LIB.BASEBOARD_FAB2(SCH_1):SMB_PCH_MEZZ_LOM0_SCL':
 C_SIGNAL='@baseboard_fab2_lib.baseboard_fab2(sch_1):smb_pch_mezz_lom0_scl';
NODE_NAME     U7C1 BM4
 '@BASEBOARD_FAB2_LIB.BASEBOARD_FAB2(SCH_1):PAGE120_I147@MSTR_U_PROC.LBG_CORE_QAT_EXT_D(CHIPS)':
 'GPP_J8_LAN_I2C_SCL_MDC_P0': CDS_PINID='GPP_J8_LAN_I2C_SCL_MDC_P0';
NODE_NAME     J8E4 20
 '@BASEBOARD_FAB2_LIB.BASEBOARD_FAB2(SCH_1):PAGE188_I27@MSTR_SCONN.SCONN64_H87568002_A(CHIPS)':
 'IO20': CDS_PINID='IO20';
NODE_NAME     R1R18 2
 '@BASEBOARD_FAB2_LIB.BASEBOARD_FAB2(SCH_1):PAGE188_I88@MSTR_DISCRETE.RES(CHIPS)':
 'B': CDS_PINID='B';
NET_NAME
'SMB_PCH_MEZZ_LOM0_SDA'
 '@BASEBOARD_FAB2_LIB.BASEBOARD_FAB2(SCH_1):SMB_PCH_MEZZ_LOM0_SDA':
 C_SIGNAL='@baseboard_fab2_lib.baseboard_fab2(sch_1):smb_pch_mezz_lom0_sda';
NODE_NAME     U7C1 BN3
 '@BASEBOARD_FAB2_LIB.BASEBOARD_FAB2(SCH_1):PAGE120_I147@MSTR_U_PROC.LBG_CORE_QAT_EXT_D(CHIPS)':
 'GPP_J9_LAN_I2C_SDA_MDIO_P0': CDS_PINID='GPP_J9_LAN_I2C_SDA_MDIO_P0';
NODE_NAME     J8E4 21
 '@BASEBOARD_FAB2_LIB.BASEBOARD_FAB2(SCH_1):PAGE188_I27@MSTR_SCONN.SCONN64_H87568002_A(CHIPS)':
 'IO21': CDS_PINID='IO21';
NODE_NAME     R1R19 2
 '@BASEBOARD_FAB2_LIB.BASEBOARD_FAB2(SCH_1):PAGE188_I89@MSTR_DISCRETE.RES(CHIPS)':
 'B': CDS_PINID='B';
NET_NAME
'SMB_PCH_MEZZ_LOM1_SCL'
 '@BASEBOARD_FAB2_LIB.BASEBOARD_FAB2(SCH_1):SMB_PCH_MEZZ_LOM1_SCL':
 C_SIGNAL='@baseboard_fab2_lib.baseboard_fab2(sch_1):smb_pch_mezz_lom1_scl';
NODE_NAME     U7C1 BW5
 '@BASEBOARD_FAB2_LIB.BASEBOARD_FAB2(SCH_1):PAGE120_I147@MSTR_U_PROC.LBG_CORE_QAT_EXT_D(CHIPS)':
 'GPP_J10_LAN_I2C_SCL_MDC_P1': CDS_PINID='GPP_J10_LAN_I2C_SCL_MDC_P1';
NODE_NAME     J8E4 26
 '@BASEBOARD_FAB2_LIB.BASEBOARD_FAB2(SCH_1):PAGE188_I27@MSTR_SCONN.SCONN64_H87568002_A(CHIPS)':
 'IO26': CDS_PINID='IO26';
NODE_NAME     R1R20 2
 '@BASEBOARD_FAB2_LIB.BASEBOARD_FAB2(SCH_1):PAGE188_I91@MSTR_DISCRETE.RES(CHIPS)':
 'B': CDS_PINID='B';
NET_NAME
'SMB_PCH_MEZZ_LOM1_SDA'
 '@BASEBOARD_FAB2_LIB.BASEBOARD_FAB2(SCH_1):SMB_PCH_MEZZ_LOM1_SDA':
 C_SIGNAL='@baseboard_fab2_lib.baseboard_fab2(sch_1):smb_pch_mezz_lom1_sda';
NODE_NAME     U7C1 BV8
 '@BASEBOARD_FAB2_LIB.BASEBOARD_FAB2(SCH_1):PAGE120_I147@MSTR_U_PROC.LBG_CORE_QAT_EXT_D(CHIPS)':
 'GPP_J11_LAN_I2C_SDA_MDIO_P1': CDS_PINID='GPP_J11_LAN_I2C_SDA_MDIO_P1';
NODE_NAME     J8E4 27
 '@BASEBOARD_FAB2_LIB.BASEBOARD_FAB2(SCH_1):PAGE188_I27@MSTR_SCONN.SCONN64_H87568002_A(CHIPS)':
 'IO27': CDS_PINID='IO27';
NODE_NAME     R1R21 2
 '@BASEBOARD_FAB2_LIB.BASEBOARD_FAB2(SCH_1):PAGE188_I90@MSTR_DISCRETE.RES(CHIPS)':
 'B': CDS_PINID='B';
NET_NAME
'SMB_PCH_MEZZ_LOM2_SCL'
 '@BASEBOARD_FAB2_LIB.BASEBOARD_FAB2(SCH_1):SMB_PCH_MEZZ_LOM2_SCL':
 C_SIGNAL='@baseboard_fab2_lib.baseboard_fab2(sch_1):smb_pch_mezz_lom2_scl';
NODE_NAME     U7C1 BT5
 '@BASEBOARD_FAB2_LIB.BASEBOARD_FAB2(SCH_1):PAGE120_I147@MSTR_U_PROC.LBG_CORE_QAT_EXT_D(CHIPS)':
 'GPP_J12_LAN_I2C_SCL_MDC_P2': CDS_PINID='GPP_J12_LAN_I2C_SCL_MDC_P2';
NODE_NAME     J8E4 61
 '@BASEBOARD_FAB2_LIB.BASEBOARD_FAB2(SCH_1):PAGE188_I27@MSTR_SCONN.SCONN64_H87568002_A(CHIPS)':
 'IO61': CDS_PINID='IO61';
NODE_NAME     R1R16 2
 '@BASEBOARD_FAB2_LIB.BASEBOARD_FAB2(SCH_1):PAGE188_I93@MSTR_DISCRETE.RES(CHIPS)':
 'B': CDS_PINID='B';
NET_NAME
'SMB_PCH_MEZZ_LOM2_SDA'
 '@BASEBOARD_FAB2_LIB.BASEBOARD_FAB2(SCH_1):SMB_PCH_MEZZ_LOM2_SDA':
 C_SIGNAL='@baseboard_fab2_lib.baseboard_fab2(sch_1):smb_pch_mezz_lom2_sda';
NODE_NAME     U7C1 BW11
 '@BASEBOARD_FAB2_LIB.BASEBOARD_FAB2(SCH_1):PAGE120_I147@MSTR_U_PROC.LBG_CORE_QAT_EXT_D(CHIPS)':
 'GPP_J13_LAN_I2C_SDA_MDIO_P2': CDS_PINID='GPP_J13_LAN_I2C_SDA_MDIO_P2';
NODE_NAME     J8E4 62
 '@BASEBOARD_FAB2_LIB.BASEBOARD_FAB2(SCH_1):PAGE188_I27@MSTR_SCONN.SCONN64_H87568002_A(CHIPS)':
 'IO62': CDS_PINID='IO62';
NODE_NAME     R1R17 2
 '@BASEBOARD_FAB2_LIB.BASEBOARD_FAB2(SCH_1):PAGE188_I94@MSTR_DISCRETE.RES(CHIPS)':
 'B': CDS_PINID='B';
NET_NAME
'SMB_PCH_MEZZ_LOM3_SCL'
 '@BASEBOARD_FAB2_LIB.BASEBOARD_FAB2(SCH_1):SMB_PCH_MEZZ_LOM3_SCL':
 C_SIGNAL='@baseboard_fab2_lib.baseboard_fab2(sch_1):smb_pch_mezz_lom3_scl';
NODE_NAME     U7C1 BW6
 '@BASEBOARD_FAB2_LIB.BASEBOARD_FAB2(SCH_1):PAGE120_I147@MSTR_U_PROC.LBG_CORE_QAT_EXT_D(CHIPS)':
 'GPP_J14_LAN_I2C_SCL_MDC_P3': CDS_PINID='GPP_J14_LAN_I2C_SCL_MDC_P3';
NODE_NAME     J8E4 29
 '@BASEBOARD_FAB2_LIB.BASEBOARD_FAB2(SCH_1):PAGE188_I27@MSTR_SCONN.SCONN64_H87568002_A(CHIPS)':
 'IO29': CDS_PINID='IO29';
NODE_NAME     R1R23 2
 '@BASEBOARD_FAB2_LIB.BASEBOARD_FAB2(SCH_1):PAGE188_I95@MSTR_DISCRETE.RES(CHIPS)':
 'B': CDS_PINID='B';
NET_NAME
'SMB_PCH_MEZZ_LOM3_SDA'
 '@BASEBOARD_FAB2_LIB.BASEBOARD_FAB2(SCH_1):SMB_PCH_MEZZ_LOM3_SDA':
 C_SIGNAL='@baseboard_fab2_lib.baseboard_fab2(sch_1):smb_pch_mezz_lom3_sda';
NODE_NAME     U7C1 BW9
 '@BASEBOARD_FAB2_LIB.BASEBOARD_FAB2(SCH_1):PAGE120_I147@MSTR_U_PROC.LBG_CORE_QAT_EXT_D(CHIPS)':
 'GPP_J15_LAN_I2C_SDA_MDIO_P3': CDS_PINID='GPP_J15_LAN_I2C_SDA_MDIO_P3';
NODE_NAME     J8E4 30
 '@BASEBOARD_FAB2_LIB.BASEBOARD_FAB2(SCH_1):PAGE188_I27@MSTR_SCONN.SCONN64_H87568002_A(CHIPS)':
 'IO30': CDS_PINID='IO30';
NODE_NAME     R1R22 2
 '@BASEBOARD_FAB2_LIB.BASEBOARD_FAB2(SCH_1):PAGE188_I92@MSTR_DISCRETE.RES(CHIPS)':
 'B': CDS_PINID='B';
NET_NAME
'SMB_PEHPCPU0_STBY_LVC3_R2_SCL'
 '@BASEBOARD_FAB2_LIB.BASEBOARD_FAB2(SCH_1):SMB_PEHPCPU0_STBY_LVC3_R2_SCL':
 C_SIGNAL='@baseboard_fab2_lib.baseboard_fab2(sch_1):smb_pehpcpu0_stby_lvc3_r2_s~
cl';
NODE_NAME     U25W4 C11
 '@BASEBOARD_FAB2_LIB.BASEBOARD_FAB2(SCH_1):PAGE145_I117@W_HDL.AST2520A1-GP-GP(CHIPS)':
 'GPIOC6_SD1CD#_SCL13': CDS_PINID='\gpioc6_sd1cd#_scl13\';
NODE_NAME     R25W122 2
 '@BASEBOARD_FAB2_LIB.BASEBOARD_FAB2(SCH_1):PAGE145_I164@MSTR_DISCRETE.RES(CHIPS)':
 'B': CDS_PINID='B';
NET_NAME
'SMB_PEHPCPU0_STBY_LVC3_R2_SDA'
 '@BASEBOARD_FAB2_LIB.BASEBOARD_FAB2(SCH_1):SMB_PEHPCPU0_STBY_LVC3_R2_SDA':
 C_SIGNAL='@baseboard_fab2_lib.baseboard_fab2(sch_1):smb_pehpcpu0_stby_lvc3_r2_s~
da';
NODE_NAME     U25W4 B11
 '@BASEBOARD_FAB2_LIB.BASEBOARD_FAB2(SCH_1):PAGE145_I117@W_HDL.AST2520A1-GP-GP(CHIPS)':
 'GPIOC7_SD1WP#_SDA13': CDS_PINID='\gpioc7_sd1wp#_sda13\';
NODE_NAME     R25W121 2
 '@BASEBOARD_FAB2_LIB.BASEBOARD_FAB2(SCH_1):PAGE145_I163@MSTR_DISCRETE.RES(CHIPS)':
 'B': CDS_PINID='B';
NET_NAME
'SMB_PEHPCPU0_STBY_LVC3_R_SCL'
 '@BASEBOARD_FAB2_LIB.BASEBOARD_FAB2(SCH_1):SMB_PEHPCPU0_STBY_LVC3_R_SCL':
 C_SIGNAL='@baseboard_fab2_lib.baseboard_fab2(sch_1):smb_pehpcpu0_stby_lvc3_r_sc~
l';
NODE_NAME     R9W17 2
 '@BASEBOARD_FAB2_LIB.BASEBOARD_FAB2(SCH_1):PAGE248_I35@MSTR_DISCRETE.RES(CHIPS)':
 'B': CDS_PINID='B';
NODE_NAME     R9W14 1
 '@BASEBOARD_FAB2_LIB.BASEBOARD_FAB2(SCH_1):PAGE248_I37@MSTR_DISCRETE.RES(CHIPS)':
 'A': CDS_PINID='A';
NODE_NAME     U1W2 7
 '@BASEBOARD_FAB2_LIB.BASEBOARD_FAB2(SCH_1):PAGE248_I49@W_HDL.TCA9517DGKR-GP(CHIPS)':
 'SCLB': CDS_PINID='SCLB';
NODE_NAME     R25W122 1
 '@BASEBOARD_FAB2_LIB.BASEBOARD_FAB2(SCH_1):PAGE145_I164@MSTR_DISCRETE.RES(CHIPS)':
 'A': CDS_PINID='A';
NET_NAME
'SMB_PEHPCPU0_STBY_LVC3_R_SDA'
 '@BASEBOARD_FAB2_LIB.BASEBOARD_FAB2(SCH_1):SMB_PEHPCPU0_STBY_LVC3_R_SDA':
 C_SIGNAL='@baseboard_fab2_lib.baseboard_fab2(sch_1):smb_pehpcpu0_stby_lvc3_r_sd~
a';
NODE_NAME     R9W16 2
 '@BASEBOARD_FAB2_LIB.BASEBOARD_FAB2(SCH_1):PAGE248_I34@MSTR_DISCRETE.RES(CHIPS)':
 'B': CDS_PINID='B';
NODE_NAME     R9W13 1
 '@BASEBOARD_FAB2_LIB.BASEBOARD_FAB2(SCH_1):PAGE248_I38@MSTR_DISCRETE.RES(CHIPS)':
 'A': CDS_PINID='A';
NODE_NAME     U1W2 6
 '@BASEBOARD_FAB2_LIB.BASEBOARD_FAB2(SCH_1):PAGE248_I49@W_HDL.TCA9517DGKR-GP(CHIPS)':
 'SDAB': CDS_PINID='SDAB';
NODE_NAME     R25W121 1
 '@BASEBOARD_FAB2_LIB.BASEBOARD_FAB2(SCH_1):PAGE145_I163@MSTR_DISCRETE.RES(CHIPS)':
 'A': CDS_PINID='A';
NET_NAME
'SMB_PEHPCPU0_STBY_LVC3_SCL'
 '@BASEBOARD_FAB2_LIB.BASEBOARD_FAB2(SCH_1):SMB_PEHPCPU0_STBY_LVC3_SCL':
 C_SIGNAL='@baseboard_fab2_lib.baseboard_fab2(sch_1):smb_pehpcpu0_stby_lvc3_scl';
NODE_NAME     U25W4 B12
 '@BASEBOARD_FAB2_LIB.BASEBOARD_FAB2(SCH_1):PAGE145_I117@W_HDL.AST2520A1-GP-GP(CHIPS)':
 'GPIOC2_SD1DAT0_SCL11': CDS_PINID='GPIOC2_SD1DAT0_SCL11';
NODE_NAME     R9W14 2
 '@BASEBOARD_FAB2_LIB.BASEBOARD_FAB2(SCH_1):PAGE248_I37@MSTR_DISCRETE.RES(CHIPS)':
 'B': CDS_PINID='B';
NET_NAME
'SMB_PEHPCPU0_STBY_LVC3_SDA'
 '@BASEBOARD_FAB2_LIB.BASEBOARD_FAB2(SCH_1):SMB_PEHPCPU0_STBY_LVC3_SDA':
 C_SIGNAL='@baseboard_fab2_lib.baseboard_fab2(sch_1):smb_pehpcpu0_stby_lvc3_sda';
NODE_NAME     U25W4 D9
 '@BASEBOARD_FAB2_LIB.BASEBOARD_FAB2(SCH_1):PAGE145_I117@W_HDL.AST2520A1-GP-GP(CHIPS)':
 'GPIOC3_SD1DAT1_SDA11': CDS_PINID='GPIOC3_SD1DAT1_SDA11';
NODE_NAME     R9W13 2
 '@BASEBOARD_FAB2_LIB.BASEBOARD_FAB2(SCH_1):PAGE248_I38@MSTR_DISCRETE.RES(CHIPS)':
 'B': CDS_PINID='B';
NET_NAME
'SMB_PEHPCPU1_STBY_LVC3_R_SCL'
 '@BASEBOARD_FAB2_LIB.BASEBOARD_FAB2(SCH_1):SMB_PEHPCPU1_STBY_LVC3_R_SCL':
 C_SIGNAL='@baseboard_fab2_lib.baseboard_fab2(sch_1):smb_pehpcpu1_stby_lvc3_r_sc~
l';
NODE_NAME     R9M17 2
 '@BASEBOARD_FAB2_LIB.BASEBOARD_FAB2(SCH_1):PAGE163_I15@MSTR_DISCRETE.RES(CHIPS)':
 'B': CDS_PINID='B';
NODE_NAME     R9M14 1
 '@BASEBOARD_FAB2_LIB.BASEBOARD_FAB2(SCH_1):PAGE163_I20@MSTR_DISCRETE.RES(CHIPS)':
 'A': CDS_PINID='A';
NODE_NAME     U1B2 7
 '@BASEBOARD_FAB2_LIB.BASEBOARD_FAB2(SCH_1):PAGE163_I28@W_HDL.TCA9517DGKR-GP(CHIPS)':
 'SCLB': CDS_PINID='SCLB';
NET_NAME
'SMB_PEHPCPU1_STBY_LVC3_R_SDA'
 '@BASEBOARD_FAB2_LIB.BASEBOARD_FAB2(SCH_1):SMB_PEHPCPU1_STBY_LVC3_R_SDA':
 C_SIGNAL='@baseboard_fab2_lib.baseboard_fab2(sch_1):smb_pehpcpu1_stby_lvc3_r_sd~
a';
NODE_NAME     R9M16 2
 '@BASEBOARD_FAB2_LIB.BASEBOARD_FAB2(SCH_1):PAGE163_I16@MSTR_DISCRETE.RES(CHIPS)':
 'B': CDS_PINID='B';
NODE_NAME     R9M13 1
 '@BASEBOARD_FAB2_LIB.BASEBOARD_FAB2(SCH_1):PAGE163_I21@MSTR_DISCRETE.RES(CHIPS)':
 'A': CDS_PINID='A';
NODE_NAME     U1B2 6
 '@BASEBOARD_FAB2_LIB.BASEBOARD_FAB2(SCH_1):PAGE163_I28@W_HDL.TCA9517DGKR-GP(CHIPS)':
 'SDAB': CDS_PINID='SDAB';
NET_NAME
'SMB_PEHPCPU1_STBY_LVC3_SCL'
 '@BASEBOARD_FAB2_LIB.BASEBOARD_FAB2(SCH_1):SMB_PEHPCPU1_STBY_LVC3_SCL':
 C_SIGNAL='@baseboard_fab2_lib.baseboard_fab2(sch_1):smb_pehpcpu1_stby_lvc3_scl';
NODE_NAME     R9M14 2
 '@BASEBOARD_FAB2_LIB.BASEBOARD_FAB2(SCH_1):PAGE163_I20@MSTR_DISCRETE.RES(CHIPS)':
 'B': CDS_PINID='B';
NODE_NAME     U25W4 D10
 '@BASEBOARD_FAB2_LIB.BASEBOARD_FAB2(SCH_1):PAGE145_I117@W_HDL.AST2520A1-GP-GP(CHIPS)':
 'GPIOC4_SD1DAT2_SCL12': CDS_PINID='GPIOC4_SD1DAT2_SCL12';
NODE_NAME     J1C1 C6
 '@BASEBOARD_FAB2_LIB.BASEBOARD_FAB2(SCH_1):PAGE182_I79@W_HDL.DM-FCI-CONN76-8R-GP-U-01(CHIPS)':
 'PMBUS_CLK': CDS_PINID='PMBUS_CLK';
NET_NAME
'SMB_PEHPCPU1_STBY_LVC3_SDA'
 '@BASEBOARD_FAB2_LIB.BASEBOARD_FAB2(SCH_1):SMB_PEHPCPU1_STBY_LVC3_SDA':
 C_SIGNAL='@baseboard_fab2_lib.baseboard_fab2(sch_1):smb_pehpcpu1_stby_lvc3_sda';
NODE_NAME     R9M13 2
 '@BASEBOARD_FAB2_LIB.BASEBOARD_FAB2(SCH_1):PAGE163_I21@MSTR_DISCRETE.RES(CHIPS)':
 'B': CDS_PINID='B';
NODE_NAME     U25W4 E12
 '@BASEBOARD_FAB2_LIB.BASEBOARD_FAB2(SCH_1):PAGE145_I117@W_HDL.AST2520A1-GP-GP(CHIPS)':
 'GPIOC5_SD1DAT3_SDA12': CDS_PINID='GPIOC5_SD1DAT3_SDA12';
NODE_NAME     J1C1 B6
 '@BASEBOARD_FAB2_LIB.BASEBOARD_FAB2(SCH_1):PAGE182_I79@W_HDL.DM-FCI-CONN76-8R-GP-U-01(CHIPS)':
 'PMBUS_DATA': CDS_PINID='PMBUS_DATA';
NET_NAME
'SMB_PIROM_CPU0_SCL'
 '@BASEBOARD_FAB2_LIB.BASEBOARD_FAB2(SCH_1):SMB_PIROM_CPU0_SCL':
 C_SIGNAL='@baseboard_fab2_lib.baseboard_fab2(sch_1):smb_pirom_cpu0_scl';
NODE_NAME     U5D1 CT59
 '@BASEBOARD_FAB2_LIB.BASEBOARD_FAB2(SCH_1):PAGE21_I259@CHPSET_LIB.SKX_EXT_B(CHIPS)':
 'SMBCLK': CDS_PINID='SMBCLK';
NODE_NAME     R4A9 2
 '@BASEBOARD_FAB2_LIB.BASEBOARD_FAB2(SCH_1):PAGE156_I324@MSTR_DISCRETE.RES(CHIPS)':
 'B': CDS_PINID='B';
NET_NAME
'SMB_PIROM_CPU0_SDA'
 '@BASEBOARD_FAB2_LIB.BASEBOARD_FAB2(SCH_1):SMB_PIROM_CPU0_SDA':
 C_SIGNAL='@baseboard_fab2_lib.baseboard_fab2(sch_1):smb_pirom_cpu0_sda';
NODE_NAME     U5D1 CW58
 '@BASEBOARD_FAB2_LIB.BASEBOARD_FAB2(SCH_1):PAGE21_I259@CHPSET_LIB.SKX_EXT_B(CHIPS)':
 'SMBDAT': CDS_PINID='SMBDAT';
NODE_NAME     R4A8 2
 '@BASEBOARD_FAB2_LIB.BASEBOARD_FAB2(SCH_1):PAGE156_I322@MSTR_DISCRETE.RES(CHIPS)':
 'B': CDS_PINID='B';
NET_NAME
'SMB_PIROM_CPU1_SCL'
 '@BASEBOARD_FAB2_LIB.BASEBOARD_FAB2(SCH_1):SMB_PIROM_CPU1_SCL':
 C_SIGNAL='@baseboard_fab2_lib.baseboard_fab2(sch_1):smb_pirom_cpu1_scl';
NODE_NAME     U2D1 CT59
 '@BASEBOARD_FAB2_LIB.BASEBOARD_FAB2(SCH_1):PAGE55_I172@CHPSET_LIB.SKX_EXT_B(CHIPS)':
 'SMBCLK': CDS_PINID='SMBCLK';
NODE_NAME     R9M20 2
 '@BASEBOARD_FAB2_LIB.BASEBOARD_FAB2(SCH_1):PAGE156_I323@MSTR_DISCRETE.RES(CHIPS)':
 'B': CDS_PINID='B';
NET_NAME
'SMB_PIROM_CPU1_SDA'
 '@BASEBOARD_FAB2_LIB.BASEBOARD_FAB2(SCH_1):SMB_PIROM_CPU1_SDA':
 C_SIGNAL='@baseboard_fab2_lib.baseboard_fab2(sch_1):smb_pirom_cpu1_sda';
NODE_NAME     U2D1 CW58
 '@BASEBOARD_FAB2_LIB.BASEBOARD_FAB2(SCH_1):PAGE55_I172@CHPSET_LIB.SKX_EXT_B(CHIPS)':
 'SMBDAT': CDS_PINID='SMBDAT';
NODE_NAME     R9M21 2
 '@BASEBOARD_FAB2_LIB.BASEBOARD_FAB2(SCH_1):PAGE156_I321@MSTR_DISCRETE.RES(CHIPS)':
 'B': CDS_PINID='B';
NET_NAME
'SMB_PMBUS_BMC_STBY_LVC3_SCL_R1'
 '@BASEBOARD_FAB2_LIB.BASEBOARD_FAB2(SCH_1):SMB_PMBUS_BMC_STBY_LVC3_SCL_R1':
 C_SIGNAL='@baseboard_fab2_lib.baseboard_fab2(sch_1):smb_pmbus_bmc_stby_lvc3_scl~
_r1';
NODE_NAME     U7C1 CA28
 '@BASEBOARD_FAB2_LIB.BASEBOARD_FAB2(SCH_1):PAGE119_I115@MSTR_U_PROC.LBG_CORE_QAT_EXT_D(CHIPS)':
 'GPP_C6_SML1CLK_IE': CDS_PINID='GPP_C6_SML1CLK_IE';
NODE_NAME     R6W25 2
 '@BASEBOARD_FAB2_LIB.BASEBOARD_FAB2(SCH_1):PAGE247_I101@MSTR_DISCRETE.RES(CHIPS)':
 'B': CDS_PINID='B';
NODE_NAME     U6W2 2
 '@BASEBOARD_FAB2_LIB.BASEBOARD_FAB2(SCH_1):PAGE247_I118@W_HDL.TCA9517DGKR-GP(CHIPS)':
 'SCLA': CDS_PINID='SCLA';
NET_NAME
'SMB_PMBUS_BMC_STBY_LVC3_SDA_R1'
 '@BASEBOARD_FAB2_LIB.BASEBOARD_FAB2(SCH_1):SMB_PMBUS_BMC_STBY_LVC3_SDA_R1':
 C_SIGNAL='@baseboard_fab2_lib.baseboard_fab2(sch_1):smb_pmbus_bmc_stby_lvc3_sda~
_r1';
NODE_NAME     U7C1 BV35
 '@BASEBOARD_FAB2_LIB.BASEBOARD_FAB2(SCH_1):PAGE119_I115@MSTR_U_PROC.LBG_CORE_QAT_EXT_D(CHIPS)':
 'GPP_C7_SML1DATA_IE': CDS_PINID='GPP_C7_SML1DATA_IE';
NODE_NAME     R6W24 2
 '@BASEBOARD_FAB2_LIB.BASEBOARD_FAB2(SCH_1):PAGE247_I100@MSTR_DISCRETE.RES(CHIPS)':
 'B': CDS_PINID='B';
NODE_NAME     U6W2 3
 '@BASEBOARD_FAB2_LIB.BASEBOARD_FAB2(SCH_1):PAGE247_I118@W_HDL.TCA9517DGKR-GP(CHIPS)':
 'SDAA': CDS_PINID='SDAA';
NET_NAME
'SMB_SENSOR_BMC_STBY_LVC3_SCL'
 '@BASEBOARD_FAB2_LIB.BASEBOARD_FAB2(SCH_1):SMB_SENSOR_BMC_STBY_LVC3_SCL':
 C_SIGNAL='@baseboard_fab2_lib.baseboard_fab2(sch_1):smb_sensor_bmc_stby_lvc3_sc~
l';
NODE_NAME     R9G14 1
 '@BASEBOARD_FAB2_LIB.BASEBOARD_FAB2(SCH_1):PAGE167_I77@MSTR_DISCRETE.RES(CHIPS)':
 'A': CDS_PINID='A';
NODE_NAME     U25W4 N1
 '@BASEBOARD_FAB2_LIB.BASEBOARD_FAB2(SCH_1):PAGE144_I95@W_HDL.AST2520A1-GP-GP(CHIPS)':
 'GPIOK4_SCL7': CDS_PINID='GPIOK4_SCL7';
NET_NAME
'SMB_SENSOR_BMC_STBY_LVC3_SDA'
 '@BASEBOARD_FAB2_LIB.BASEBOARD_FAB2(SCH_1):SMB_SENSOR_BMC_STBY_LVC3_SDA':
 C_SIGNAL='@baseboard_fab2_lib.baseboard_fab2(sch_1):smb_sensor_bmc_stby_lvc3_sd~
a';
NODE_NAME     R9G15 1
 '@BASEBOARD_FAB2_LIB.BASEBOARD_FAB2(SCH_1):PAGE167_I58@MSTR_DISCRETE.RES(CHIPS)':
 'A': CDS_PINID='A';
NODE_NAME     U25W4 P1
 '@BASEBOARD_FAB2_LIB.BASEBOARD_FAB2(SCH_1):PAGE144_I95@W_HDL.AST2520A1-GP-GP(CHIPS)':
 'GPIOK5_SDA7': CDS_PINID='GPIOK5_SDA7';
NET_NAME
'SMB_SENSOR_STBY_LVC3_SCL'
 '@BASEBOARD_FAB2_LIB.BASEBOARD_FAB2(SCH_1):SMB_SENSOR_STBY_LVC3_SCL':
 C_SIGNAL='@baseboard_fab2_lib.baseboard_fab2(sch_1):smb_sensor_stby_lvc3_scl';
NODE_NAME     R1M8 2
 '@BASEBOARD_FAB2_LIB.BASEBOARD_FAB2(SCH_1):PAGE167_I74@MSTR_DISCRETE.RES(CHIPS)':
 'B': CDS_PINID='B';
NODE_NAME     R9R7 2
 '@BASEBOARD_FAB2_LIB.BASEBOARD_FAB2(SCH_1):PAGE167_I75@MSTR_DISCRETE.RES(CHIPS)':
 'B': CDS_PINID='B';
NODE_NAME     R9G14 2
 '@BASEBOARD_FAB2_LIB.BASEBOARD_FAB2(SCH_1):PAGE167_I77@MSTR_DISCRETE.RES(CHIPS)':
 'B': CDS_PINID='B';
NODE_NAME     R2U38 2
 '@BASEBOARD_FAB2_LIB.BASEBOARD_FAB2(SCH_1):PAGE167_I80@MSTR_DISCRETE.RES(CHIPS)':
 'B': CDS_PINID='B';
NODE_NAME     R8D24 1
 '@BASEBOARD_FAB2_LIB.BASEBOARD_FAB2(SCH_1):PAGE167_I84@MSTR_DISCRETE.RES(CHIPS)':
 'A': CDS_PINID='A';
NODE_NAME     J8E1 10
 '@BASEBOARD_FAB2_LIB.BASEBOARD_FAB2(SCH_1):PAGE184_I87@MSTR_SCONN.SCONN11_H67026001(CHIPS)':
 'IO10': CDS_PINID='IO10';
NODE_NAME     U8D7 A9
 '@BASEBOARD_FAB2_LIB.BASEBOARD_FAB2(SCH_1):PAGE191_I59@MSTR_MEMORY.LCMXO2_A(CHIPS)':
 'PT18C_SCL_PCLKT0_0': CDS_PINID='PT18C_SCL_PCLKT0_0';
NODE_NAME     U6W11 14
 '@BASEBOARD_FAB2_LIB.BASEBOARD_FAB2(SCH_1):PAGE164_I97@W_HDL.PCA9554PWR-GP(CHIPS)':
 'SCL': CDS_PINID='SCL';
NET_NAME
'SMB_SENSOR_STBY_LVC3_SCL_R2'
 '@BASEBOARD_FAB2_LIB.BASEBOARD_FAB2(SCH_1):SMB_SENSOR_STBY_LVC3_SCL_R2':
 C_SIGNAL='@baseboard_fab2_lib.baseboard_fab2(sch_1):smb_sensor_stby_lvc3_scl_r2~
';
NODE_NAME     U8D4 6
 '@BASEBOARD_FAB2_LIB.BASEBOARD_FAB2(SCH_1):PAGE167_I49@MSTR_MEMORY.AT24C64(CHIPS)':
 'SCL': CDS_PINID='SCL';
NODE_NAME     R8D24 2
 '@BASEBOARD_FAB2_LIB.BASEBOARD_FAB2(SCH_1):PAGE167_I84@MSTR_DISCRETE.RES(CHIPS)':
 'B': CDS_PINID='B';
NET_NAME
'SMB_SENSOR_STBY_LVC3_SDA'
 '@BASEBOARD_FAB2_LIB.BASEBOARD_FAB2(SCH_1):SMB_SENSOR_STBY_LVC3_SDA':
 C_SIGNAL='@baseboard_fab2_lib.baseboard_fab2(sch_1):smb_sensor_stby_lvc3_sda';
NODE_NAME     R1M9 2
 '@BASEBOARD_FAB2_LIB.BASEBOARD_FAB2(SCH_1):PAGE167_I8@MSTR_DISCRETE.RES(CHIPS)':
 'B': CDS_PINID='B';
NODE_NAME     R9G15 2
 '@BASEBOARD_FAB2_LIB.BASEBOARD_FAB2(SCH_1):PAGE167_I58@MSTR_DISCRETE.RES(CHIPS)':
 'B': CDS_PINID='B';
NODE_NAME     R9R8 2
 '@BASEBOARD_FAB2_LIB.BASEBOARD_FAB2(SCH_1):PAGE167_I76@MSTR_DISCRETE.RES(CHIPS)':
 'B': CDS_PINID='B';
NODE_NAME     R2U39 2
 '@BASEBOARD_FAB2_LIB.BASEBOARD_FAB2(SCH_1):PAGE167_I83@MSTR_DISCRETE.RES(CHIPS)':
 'B': CDS_PINID='B';
NODE_NAME     R8D23 2
 '@BASEBOARD_FAB2_LIB.BASEBOARD_FAB2(SCH_1):PAGE167_I85@MSTR_DISCRETE.RES(CHIPS)':
 'B': CDS_PINID='B';
NODE_NAME     J8E1 6
 '@BASEBOARD_FAB2_LIB.BASEBOARD_FAB2(SCH_1):PAGE184_I87@MSTR_SCONN.SCONN11_H67026001(CHIPS)':
 'IO6': CDS_PINID='IO6';
NODE_NAME     U8D7 C9
 '@BASEBOARD_FAB2_LIB.BASEBOARD_FAB2(SCH_1):PAGE191_I59@MSTR_MEMORY.LCMXO2_A(CHIPS)':
 'PT18D_SDA_PCLKC0_0': CDS_PINID='PT18D_SDA_PCLKC0_0';
NODE_NAME     U6W11 15
 '@BASEBOARD_FAB2_LIB.BASEBOARD_FAB2(SCH_1):PAGE164_I97@W_HDL.PCA9554PWR-GP(CHIPS)':
 'SDA': CDS_PINID='SDA';
NET_NAME
'SMB_SENSOR_STBY_LVC3_SDA_R2'
 '@BASEBOARD_FAB2_LIB.BASEBOARD_FAB2(SCH_1):SMB_SENSOR_STBY_LVC3_SDA_R2':
 C_SIGNAL='@baseboard_fab2_lib.baseboard_fab2(sch_1):smb_sensor_stby_lvc3_sda_r2~
';
NODE_NAME     U8D4 5
 '@BASEBOARD_FAB2_LIB.BASEBOARD_FAB2(SCH_1):PAGE167_I49@MSTR_MEMORY.AT24C64(CHIPS)':
 'SDA': CDS_PINID='SDA';
NODE_NAME     R8D23 1
 '@BASEBOARD_FAB2_LIB.BASEBOARD_FAB2(SCH_1):PAGE167_I85@MSTR_DISCRETE.RES(CHIPS)':
 'A': CDS_PINID='A';
NET_NAME
'SMB_SENSOR_TMP421_1_SCL'
 '@BASEBOARD_FAB2_LIB.BASEBOARD_FAB2(SCH_1):SMB_SENSOR_TMP421_1_SCL':
 C_SIGNAL='@baseboard_fab2_lib.baseboard_fab2(sch_1):smb_sensor_tmp421_1_scl';
NODE_NAME     U9B4 7
 '@BASEBOARD_FAB2_LIB.BASEBOARD_FAB2(SCH_1):PAGE167_I1@MSTR_ANALOG.TMP421(CHIPS)':
 'SCL': CDS_PINID='SCL';
NODE_NAME     R1M8 1
 '@BASEBOARD_FAB2_LIB.BASEBOARD_FAB2(SCH_1):PAGE167_I74@MSTR_DISCRETE.RES(CHIPS)':
 'A': CDS_PINID='A';
NET_NAME
'SMB_SENSOR_TMP421_1_SDA'
 '@BASEBOARD_FAB2_LIB.BASEBOARD_FAB2(SCH_1):SMB_SENSOR_TMP421_1_SDA':
 C_SIGNAL='@baseboard_fab2_lib.baseboard_fab2(sch_1):smb_sensor_tmp421_1_sda';
NODE_NAME     U9B4 6
 '@BASEBOARD_FAB2_LIB.BASEBOARD_FAB2(SCH_1):PAGE167_I1@MSTR_ANALOG.TMP421(CHIPS)':
 'SDA': CDS_PINID='SDA';
NODE_NAME     R1M9 1
 '@BASEBOARD_FAB2_LIB.BASEBOARD_FAB2(SCH_1):PAGE167_I8@MSTR_DISCRETE.RES(CHIPS)':
 'A': CDS_PINID='A';
NET_NAME
'SMB_SENSOR_TMP421_2_SCL'
 '@BASEBOARD_FAB2_LIB.BASEBOARD_FAB2(SCH_1):SMB_SENSOR_TMP421_2_SCL':
 C_SIGNAL='@baseboard_fab2_lib.baseboard_fab2(sch_1):smb_sensor_tmp421_2_scl';
NODE_NAME     U1E1 7
 '@BASEBOARD_FAB2_LIB.BASEBOARD_FAB2(SCH_1):PAGE167_I30@MSTR_ANALOG.TMP421(CHIPS)':
 'SCL': CDS_PINID='SCL';
NODE_NAME     R9R7 1
 '@BASEBOARD_FAB2_LIB.BASEBOARD_FAB2(SCH_1):PAGE167_I75@MSTR_DISCRETE.RES(CHIPS)':
 'A': CDS_PINID='A';
NET_NAME
'SMB_SENSOR_TMP421_2_SDA'
 '@BASEBOARD_FAB2_LIB.BASEBOARD_FAB2(SCH_1):SMB_SENSOR_TMP421_2_SDA':
 C_SIGNAL='@baseboard_fab2_lib.baseboard_fab2(sch_1):smb_sensor_tmp421_2_sda';
NODE_NAME     U1E1 6
 '@BASEBOARD_FAB2_LIB.BASEBOARD_FAB2(SCH_1):PAGE167_I30@MSTR_ANALOG.TMP421(CHIPS)':
 'SDA': CDS_PINID='SDA';
NODE_NAME     R9R8 1
 '@BASEBOARD_FAB2_LIB.BASEBOARD_FAB2(SCH_1):PAGE167_I76@MSTR_DISCRETE.RES(CHIPS)':
 'A': CDS_PINID='A';
NET_NAME
'SMB_SLOTX24_BMC_STBY_LVC3_SCL'
 '@BASEBOARD_FAB2_LIB.BASEBOARD_FAB2(SCH_1):SMB_SLOTX24_BMC_STBY_LVC3_SCL':
 C_SIGNAL='@baseboard_fab2_lib.baseboard_fab2(sch_1):smb_slotx24_bmc_stby_lvc3_s~
cl';
NODE_NAME     R2U32 1
 '@BASEBOARD_FAB2_LIB.BASEBOARD_FAB2(SCH_1):PAGE108_I339@MSTR_DISCRETE.RES(CHIPS)':
 'A': CDS_PINID='A';
NODE_NAME     R1T7 2
 '@BASEBOARD_FAB2_LIB.BASEBOARD_FAB2(SCH_1):PAGE160_I50@MSTR_DISCRETE.RES(CHIPS)':
 'B': CDS_PINID='B';
NET_NAME
'SMB_SLOTX24_BMC_STBY_LVC3_SDA'
 '@BASEBOARD_FAB2_LIB.BASEBOARD_FAB2(SCH_1):SMB_SLOTX24_BMC_STBY_LVC3_SDA':
 C_SIGNAL='@baseboard_fab2_lib.baseboard_fab2(sch_1):smb_slotx24_bmc_stby_lvc3_s~
da';
NODE_NAME     R2U31 1
 '@BASEBOARD_FAB2_LIB.BASEBOARD_FAB2(SCH_1):PAGE108_I330@MSTR_DISCRETE.RES(CHIPS)':
 'A': CDS_PINID='A';
NODE_NAME     R1T8 2
 '@BASEBOARD_FAB2_LIB.BASEBOARD_FAB2(SCH_1):PAGE160_I4@MSTR_DISCRETE.RES(CHIPS)':
 'B': CDS_PINID='B';
NET_NAME
'SMB_SLOTX24_PCH_STBY_LVC3_SCL'
 '@BASEBOARD_FAB2_LIB.BASEBOARD_FAB2(SCH_1):SMB_SLOTX24_PCH_STBY_LVC3_SCL':
 C_SIGNAL='@baseboard_fab2_lib.baseboard_fab2(sch_1):smb_slotx24_pch_stby_lvc3_s~
cl';
NODE_NAME     U7C1 BY44
 '@BASEBOARD_FAB2_LIB.BASEBOARD_FAB2(SCH_1):PAGE119_I115@MSTR_U_PROC.LBG_CORE_QAT_EXT_D(CHIPS)':
 'GPP_D13_SML0BCLK_IE': CDS_PINID='GPP_D13_SML0BCLK_IE';
NODE_NAME     R2U36 1
 '@BASEBOARD_FAB2_LIB.BASEBOARD_FAB2(SCH_1):PAGE108_I351@MSTR_DISCRETE.RES(CHIPS)':
 'A': CDS_PINID='A';
NODE_NAME     R24W2 2
 '@BASEBOARD_FAB2_LIB.BASEBOARD_FAB2(SCH_1):PAGE138_I199@MSTR_DISCRETE.RES(CHIPS)':
 'B': CDS_PINID='B';
NET_NAME
'SMB_SLOTX24_PCH_STBY_LVC3_SDA'
 '@BASEBOARD_FAB2_LIB.BASEBOARD_FAB2(SCH_1):SMB_SLOTX24_PCH_STBY_LVC3_SDA':
 C_SIGNAL='@baseboard_fab2_lib.baseboard_fab2(sch_1):smb_slotx24_pch_stby_lvc3_s~
da';
NODE_NAME     U7C1 BL44
 '@BASEBOARD_FAB2_LIB.BASEBOARD_FAB2(SCH_1):PAGE119_I115@MSTR_U_PROC.LBG_CORE_QAT_EXT_D(CHIPS)':
 'GPP_D14_SML0BDATA_IE': CDS_PINID='GPP_D14_SML0BDATA_IE';
NODE_NAME     R2U35 1
 '@BASEBOARD_FAB2_LIB.BASEBOARD_FAB2(SCH_1):PAGE108_I350@MSTR_DISCRETE.RES(CHIPS)':
 'A': CDS_PINID='A';
NODE_NAME     R24W1 2
 '@BASEBOARD_FAB2_LIB.BASEBOARD_FAB2(SCH_1):PAGE138_I198@MSTR_DISCRETE.RES(CHIPS)':
 'B': CDS_PINID='B';
NET_NAME
'SMB_SLOTX24_STBY_LVC3_SCL_R'
 '@BASEBOARD_FAB2_LIB.BASEBOARD_FAB2(SCH_1):SMB_SLOTX24_STBY_LVC3_SCL_R':
 C_SIGNAL='@baseboard_fab2_lib.baseboard_fab2(sch_1):smb_slotx24_stby_lvc3_scl_r~
';
NODE_NAME     R1T2 2
 '@BASEBOARD_FAB2_LIB.BASEBOARD_FAB2(SCH_1):PAGE160_I49@MSTR_DISCRETE.RES(CHIPS)':
 'B': CDS_PINID='B';
NODE_NAME     R1T7 1
 '@BASEBOARD_FAB2_LIB.BASEBOARD_FAB2(SCH_1):PAGE160_I50@MSTR_DISCRETE.RES(CHIPS)':
 'A': CDS_PINID='A';
NODE_NAME     U25W4 M20
 '@BASEBOARD_FAB2_LIB.BASEBOARD_FAB2(SCH_1):PAGE144_I95@W_HDL.AST2520A1-GP-GP(CHIPS)':
 'GPIOY6_SCL2': CDS_PINID='GPIOY6_SCL2';
NET_NAME
'SMB_SLOTX24_STBY_LVC3_SCL_R2'
 '@BASEBOARD_FAB2_LIB.BASEBOARD_FAB2(SCH_1):SMB_SLOTX24_STBY_LVC3_SCL_R2':
 C_SIGNAL='@baseboard_fab2_lib.baseboard_fab2(sch_1):smb_slotx24_stby_lvc3_scl_r~
2';
NODE_NAME     J8G1 17
 '@BASEBOARD_FAB2_LIB.BASEBOARD_FAB2(SCH_1):PAGE108_I258@MSTR_SCONN.SCONN200_H68296001(CHIPS)':
 'IO17': CDS_PINID='IO17';
NODE_NAME     R2U32 2
 '@BASEBOARD_FAB2_LIB.BASEBOARD_FAB2(SCH_1):PAGE108_I339@MSTR_DISCRETE.RES(CHIPS)':
 'B': CDS_PINID='B';
NODE_NAME     R2U36 2
 '@BASEBOARD_FAB2_LIB.BASEBOARD_FAB2(SCH_1):PAGE108_I351@MSTR_DISCRETE.RES(CHIPS)':
 'B': CDS_PINID='B';
NET_NAME
'SMB_SLOTX24_STBY_LVC3_SDA_R'
 '@BASEBOARD_FAB2_LIB.BASEBOARD_FAB2(SCH_1):SMB_SLOTX24_STBY_LVC3_SDA_R':
 C_SIGNAL='@baseboard_fab2_lib.baseboard_fab2(sch_1):smb_slotx24_stby_lvc3_sda_r~
';
NODE_NAME     R1T8 1
 '@BASEBOARD_FAB2_LIB.BASEBOARD_FAB2(SCH_1):PAGE160_I4@MSTR_DISCRETE.RES(CHIPS)':
 'A': CDS_PINID='A';
NODE_NAME     R1T3 2
 '@BASEBOARD_FAB2_LIB.BASEBOARD_FAB2(SCH_1):PAGE160_I46@MSTR_DISCRETE.RES(CHIPS)':
 'B': CDS_PINID='B';
NODE_NAME     U25W4 P20
 '@BASEBOARD_FAB2_LIB.BASEBOARD_FAB2(SCH_1):PAGE144_I95@W_HDL.AST2520A1-GP-GP(CHIPS)':
 'GPIOY7_SDA2': CDS_PINID='GPIOY7_SDA2';
NET_NAME
'SMB_SLOTX24_STBY_LVC3_SDA_R2'
 '@BASEBOARD_FAB2_LIB.BASEBOARD_FAB2(SCH_1):SMB_SLOTX24_STBY_LVC3_SDA_R2':
 C_SIGNAL='@baseboard_fab2_lib.baseboard_fab2(sch_1):smb_slotx24_stby_lvc3_sda_r~
2';
NODE_NAME     J8G1 15
 '@BASEBOARD_FAB2_LIB.BASEBOARD_FAB2(SCH_1):PAGE108_I258@MSTR_SCONN.SCONN200_H68296001(CHIPS)':
 'IO15': CDS_PINID='IO15';
NODE_NAME     R2U31 2
 '@BASEBOARD_FAB2_LIB.BASEBOARD_FAB2(SCH_1):PAGE108_I330@MSTR_DISCRETE.RES(CHIPS)':
 'B': CDS_PINID='B';
NODE_NAME     R2U35 2
 '@BASEBOARD_FAB2_LIB.BASEBOARD_FAB2(SCH_1):PAGE108_I350@MSTR_DISCRETE.RES(CHIPS)':
 'B': CDS_PINID='B';
NET_NAME
'SMB_SMLINK0_STBY_LVC3_SCL'
 '@BASEBOARD_FAB2_LIB.BASEBOARD_FAB2(SCH_1):SMB_SMLINK0_STBY_LVC3_SCL':
 C_SIGNAL='@baseboard_fab2_lib.baseboard_fab2(sch_1):smb_smlink0_stby_lvc3_scl';
NODE_NAME     R2N5 2
 '@BASEBOARD_FAB2_LIB.BASEBOARD_FAB2(SCH_1):PAGE138_I90@MSTR_DISCRETE.RES(CHIPS)':
 'B': CDS_PINID='B';
NODE_NAME     R8C12 2
 '@BASEBOARD_FAB2_LIB.BASEBOARD_FAB2(SCH_1):PAGE138_I170@MSTR_DISCRETE.RES(CHIPS)':
 'B': CDS_PINID='B';
NODE_NAME     J9B2 3
 '@BASEBOARD_FAB2_LIB.BASEBOARD_FAB2(SCH_1):PAGE156_I281@MSTR_CONN.CONN3_C95678002(CHIPS)':
 'IO3': CDS_PINID='IO3';
NODE_NAME     R1U19 1
 '@BASEBOARD_FAB2_LIB.BASEBOARD_FAB2(SCH_1):PAGE159_I226@MSTR_DISCRETE.RES(CHIPS)':
 'A': CDS_PINID='A';
NODE_NAME     R1U9 2
 '@BASEBOARD_FAB2_LIB.BASEBOARD_FAB2(SCH_1):PAGE159_I232@MSTR_DISCRETE.RES(CHIPS)':
 'B': CDS_PINID='B';
NET_NAME
'SMB_SMLINK0_STBY_LVC3_SCL_R'
 '@BASEBOARD_FAB2_LIB.BASEBOARD_FAB2(SCH_1):SMB_SMLINK0_STBY_LVC3_SCL_R':
 C_SIGNAL='@baseboard_fab2_lib.baseboard_fab2(sch_1):smb_smlink0_stby_lvc3_scl_r~
';
NODE_NAME     R1U9 1
 '@BASEBOARD_FAB2_LIB.BASEBOARD_FAB2(SCH_1):PAGE159_I232@MSTR_DISCRETE.RES(CHIPS)':
 'A': CDS_PINID='A';
NODE_NAME     U25W4 L3
 '@BASEBOARD_FAB2_LIB.BASEBOARD_FAB2(SCH_1):PAGE144_I95@W_HDL.AST2520A1-GP-GP(CHIPS)':
 'GPIOK0_SCL5': CDS_PINID='GPIOK0_SCL5';
NET_NAME
'SMB_SMLINK0_STBY_LVC3_SCL_R1'
 '@BASEBOARD_FAB2_LIB.BASEBOARD_FAB2(SCH_1):SMB_SMLINK0_STBY_LVC3_SCL_R1':
 C_SIGNAL='@baseboard_fab2_lib.baseboard_fab2(sch_1):smb_smlink0_stby_lvc3_scl_r~
1';
NODE_NAME     U7C1 BV29
 '@BASEBOARD_FAB2_LIB.BASEBOARD_FAB2(SCH_1):PAGE119_I115@MSTR_U_PROC.LBG_CORE_QAT_EXT_D(CHIPS)':
 'GPP_C3_SML0CLK_IE': CDS_PINID='GPP_C3_SML0CLK_IE';
NODE_NAME     R8C12 1
 '@BASEBOARD_FAB2_LIB.BASEBOARD_FAB2(SCH_1):PAGE138_I170@MSTR_DISCRETE.RES(CHIPS)':
 'A': CDS_PINID='A';
NET_NAME
'SMB_SMLINK0_STBY_LVC3_SDA'
 '@BASEBOARD_FAB2_LIB.BASEBOARD_FAB2(SCH_1):SMB_SMLINK0_STBY_LVC3_SDA':
 C_SIGNAL='@baseboard_fab2_lib.baseboard_fab2(sch_1):smb_smlink0_stby_lvc3_sda';
NODE_NAME     R2N8 2
 '@BASEBOARD_FAB2_LIB.BASEBOARD_FAB2(SCH_1):PAGE138_I89@MSTR_DISCRETE.RES(CHIPS)':
 'B': CDS_PINID='B';
NODE_NAME     R8C11 2
 '@BASEBOARD_FAB2_LIB.BASEBOARD_FAB2(SCH_1):PAGE138_I169@MSTR_DISCRETE.RES(CHIPS)':
 'B': CDS_PINID='B';
NODE_NAME     J9B2 1
 '@BASEBOARD_FAB2_LIB.BASEBOARD_FAB2(SCH_1):PAGE156_I281@MSTR_CONN.CONN3_C95678002(CHIPS)':
 'IO1': CDS_PINID='IO1';
NODE_NAME     R1U20 1
 '@BASEBOARD_FAB2_LIB.BASEBOARD_FAB2(SCH_1):PAGE159_I225@MSTR_DISCRETE.RES(CHIPS)':
 'A': CDS_PINID='A';
NODE_NAME     R1U10 2
 '@BASEBOARD_FAB2_LIB.BASEBOARD_FAB2(SCH_1):PAGE159_I233@MSTR_DISCRETE.RES(CHIPS)':
 'B': CDS_PINID='B';
NET_NAME
'SMB_SMLINK0_STBY_LVC3_SDA_R'
 '@BASEBOARD_FAB2_LIB.BASEBOARD_FAB2(SCH_1):SMB_SMLINK0_STBY_LVC3_SDA_R':
 C_SIGNAL='@baseboard_fab2_lib.baseboard_fab2(sch_1):smb_smlink0_stby_lvc3_sda_r~
';
NODE_NAME     R1U10 1
 '@BASEBOARD_FAB2_LIB.BASEBOARD_FAB2(SCH_1):PAGE159_I233@MSTR_DISCRETE.RES(CHIPS)':
 'A': CDS_PINID='A';
NODE_NAME     U25W4 L4
 '@BASEBOARD_FAB2_LIB.BASEBOARD_FAB2(SCH_1):PAGE144_I95@W_HDL.AST2520A1-GP-GP(CHIPS)':
 'GPIOK1_SDA5': CDS_PINID='GPIOK1_SDA5';
NET_NAME
'SMB_SMLINK0_STBY_LVC3_SDA_R1'
 '@BASEBOARD_FAB2_LIB.BASEBOARD_FAB2(SCH_1):SMB_SMLINK0_STBY_LVC3_SDA_R1':
 C_SIGNAL='@baseboard_fab2_lib.baseboard_fab2(sch_1):smb_smlink0_stby_lvc3_sda_r~
1';
NODE_NAME     U7C1 BW30
 '@BASEBOARD_FAB2_LIB.BASEBOARD_FAB2(SCH_1):PAGE119_I115@MSTR_U_PROC.LBG_CORE_QAT_EXT_D(CHIPS)':
 'GPP_C4_SML0DATA_IE': CDS_PINID='GPP_C4_SML0DATA_IE';
NODE_NAME     R8C11 1
 '@BASEBOARD_FAB2_LIB.BASEBOARD_FAB2(SCH_1):PAGE138_I169@MSTR_DISCRETE.RES(CHIPS)':
 'A': CDS_PINID='A';
NET_NAME
'SMB_SPRINGVILLE_STBY_LVC3_SCL'
 '@BASEBOARD_FAB2_LIB.BASEBOARD_FAB2(SCH_1):SMB_SPRINGVILLE_STBY_LVC3_SCL':
 C_SIGNAL='@baseboard_fab2_lib.baseboard_fab2(sch_1):smb_springville_stby_lvc3_s~
cl';
NODE_NAME     EU9E1 34
 '@BASEBOARD_FAB2_LIB.BASEBOARD_FAB2(SCH_1):PAGE139_I72@MSTR_INTEL.SPRINGVILLE(CHIPS)':
 'SMB_CLK': CDS_PINID='SMB_CLK';
NODE_NAME     R1U19 2
 '@BASEBOARD_FAB2_LIB.BASEBOARD_FAB2(SCH_1):PAGE159_I226@MSTR_DISCRETE.RES(CHIPS)':
 'B': CDS_PINID='B';
NODE_NAME     R9G13 2
 '@BASEBOARD_FAB2_LIB.BASEBOARD_FAB2(SCH_1):PAGE159_I227@MSTR_DISCRETE.RES(CHIPS)':
 'B': CDS_PINID='B';
NET_NAME
'SMB_SPRINGVILLE_STBY_LVC3_SDA'
 '@BASEBOARD_FAB2_LIB.BASEBOARD_FAB2(SCH_1):SMB_SPRINGVILLE_STBY_LVC3_SDA':
 C_SIGNAL='@baseboard_fab2_lib.baseboard_fab2(sch_1):smb_springville_stby_lvc3_s~
da';
NODE_NAME     EU9E1 36
 '@BASEBOARD_FAB2_LIB.BASEBOARD_FAB2(SCH_1):PAGE139_I72@MSTR_INTEL.SPRINGVILLE(CHIPS)':
 'SMB_DATA': CDS_PINID='SMB_DATA';
NODE_NAME     R9G12 2
 '@BASEBOARD_FAB2_LIB.BASEBOARD_FAB2(SCH_1):PAGE159_I224@MSTR_DISCRETE.RES(CHIPS)':
 'B': CDS_PINID='B';
NODE_NAME     R1U20 2
 '@BASEBOARD_FAB2_LIB.BASEBOARD_FAB2(SCH_1):PAGE159_I225@MSTR_DISCRETE.RES(CHIPS)':
 'B': CDS_PINID='B';
NET_NAME
'SMB_VR_STBY_LVC3_SCL'
 '@BASEBOARD_FAB2_LIB.BASEBOARD_FAB2(SCH_1):SMB_VR_STBY_LVC3_SCL':
 C_SIGNAL='@baseboard_fab2_lib.baseboard_fab2(sch_1):smb_vr_stby_lvc3_scl';
NODE_NAME     R8D15 2
 '@BASEBOARD_FAB2_LIB.BASEBOARD_FAB2(SCH_1):PAGE138_I88@MSTR_DISCRETE.RES(CHIPS)':
 'B': CDS_PINID='B';
NODE_NAME     R8D4 2
 '@BASEBOARD_FAB2_LIB.BASEBOARD_FAB2(SCH_1):PAGE138_I164@MSTR_DISCRETE.RES(CHIPS)':
 'B': CDS_PINID='B';
NODE_NAME     R1U11 2
 '@BASEBOARD_FAB2_LIB.BASEBOARD_FAB2(SCH_1):PAGE159_I222@MSTR_DISCRETE.RES(CHIPS)':
 'B': CDS_PINID='B';
NODE_NAME     J4B2 A18
 '@BASEBOARD_FAB2_LIB.BASEBOARD_FAB2(SCH_1):PAGE193_I46@MSTR_SCONN.SCONN120_H61426002(CHIPS)':
 'IOA18': CDS_PINID='IOA18';
NODE_NAME     J6B1 A18
 '@BASEBOARD_FAB2_LIB.BASEBOARD_FAB2(SCH_1):PAGE194_I56@MSTR_SCONN.SCONN120_H61426002(CHIPS)':
 'IOA18': CDS_PINID='IOA18';
NODE_NAME     R6P37 2
 '@BASEBOARD_FAB2_LIB.BASEBOARD_FAB2(SCH_1):PAGE201_I103@MSTR_DISCRETE.RES(CHIPS)':
 'B': CDS_PINID='B';
NODE_NAME     EU4D4 9
 '@BASEBOARD_FAB2_LIB.BASEBOARD_FAB2(SCH_1):PAGE201_I155@MSTR_CONTROLLER.PXE1610B(CHIPS)':
 'SCL': CDS_PINID='SCL';
NODE_NAME     EU1C2 9
 '@BASEBOARD_FAB2_LIB.BASEBOARD_FAB2(SCH_1):PAGE206_I130@MSTR_CONTROLLER.PXE1610B(CHIPS)':
 'SCL': CDS_PINID='SCL';
NODE_NAME     EU3P1 7
 '@BASEBOARD_FAB2_LIB.BASEBOARD_FAB2(SCH_1):PAGE211_I93@MSTR_CONTROLLER.PXE1110B(CHIPS)':
 'SCL': CDS_PINID='SCL';
NODE_NAME     EU4D5 7
 '@BASEBOARD_FAB2_LIB.BASEBOARD_FAB2(SCH_1):PAGE213_I96@MSTR_CONTROLLER.PXE1110B(CHIPS)':
 'SCL': CDS_PINID='SCL';
NODE_NAME     EU8A1 7
 '@BASEBOARD_FAB2_LIB.BASEBOARD_FAB2(SCH_1):PAGE235_I229@MSTR_CONTROLLER.PXE1110B(CHIPS)':
 'SCL': CDS_PINID='SCL';
NODE_NAME     EU7G1 7
 '@BASEBOARD_FAB2_LIB.BASEBOARD_FAB2(SCH_1):PAGE215_I69@MSTR_CONTROLLER.PXM1310B(CHIPS)':
 'SCL': CDS_PINID='SCL';
NODE_NAME     EU7A5 7
 '@BASEBOARD_FAB2_LIB.BASEBOARD_FAB2(SCH_1):PAGE218_I69@MSTR_CONTROLLER.PXM1310B(CHIPS)':
 'SCL': CDS_PINID='SCL';
NODE_NAME     EU1G2 7
 '@BASEBOARD_FAB2_LIB.BASEBOARD_FAB2(SCH_1):PAGE223_I69@MSTR_CONTROLLER.PXM1310B(CHIPS)':
 'SCL': CDS_PINID='SCL';
NODE_NAME     EU1B1 7
 '@BASEBOARD_FAB2_LIB.BASEBOARD_FAB2(SCH_1):PAGE226_I69@MSTR_CONTROLLER.PXM1310B(CHIPS)':
 'SCL': CDS_PINID='SCL';
NODE_NAME     J8D4 3
 '@BASEBOARD_FAB2_LIB.BASEBOARD_FAB2(SCH_1):PAGE201_I191@W_HDL.PIN-CON3-27-GP(CHIPS)':
 '3': CDS_PINID='\3\';
NET_NAME
'SMB_VR_STBY_LVC3_SCL_R'
 '@BASEBOARD_FAB2_LIB.BASEBOARD_FAB2(SCH_1):SMB_VR_STBY_LVC3_SCL_R':
 C_SIGNAL='@baseboard_fab2_lib.baseboard_fab2(sch_1):smb_vr_stby_lvc3_scl_r';
NODE_NAME     R1U11 1
 '@BASEBOARD_FAB2_LIB.BASEBOARD_FAB2(SCH_1):PAGE159_I222@MSTR_DISCRETE.RES(CHIPS)':
 'A': CDS_PINID='A';
NODE_NAME     U25W4 L1
 '@BASEBOARD_FAB2_LIB.BASEBOARD_FAB2(SCH_1):PAGE144_I95@W_HDL.AST2520A1-GP-GP(CHIPS)':
 'GPIOK2_SCL6': CDS_PINID='GPIOK2_SCL6';
NET_NAME
'SMB_VR_STBY_LVC3_SCL_R1'
 '@BASEBOARD_FAB2_LIB.BASEBOARD_FAB2(SCH_1):SMB_VR_STBY_LVC3_SCL_R1':
 C_SIGNAL='@baseboard_fab2_lib.baseboard_fab2(sch_1):smb_vr_stby_lvc3_scl_r1';
NODE_NAME     U7C1 BA4
 '@BASEBOARD_FAB2_LIB.BASEBOARD_FAB2(SCH_1):PAGE120_I147@MSTR_U_PROC.LBG_CORE_QAT_EXT_D(CHIPS)':
 'GPP_H10_SML2CLK_IE': CDS_PINID='GPP_H10_SML2CLK_IE';
NODE_NAME     R8D4 1
 '@BASEBOARD_FAB2_LIB.BASEBOARD_FAB2(SCH_1):PAGE138_I164@MSTR_DISCRETE.RES(CHIPS)':
 'A': CDS_PINID='A';
NODE_NAME     R8W7 2
 '@BASEBOARD_FAB2_LIB.BASEBOARD_FAB2(SCH_1):PAGE138_I202@MSTR_DISCRETE.RES(CHIPS)':
 'B': CDS_PINID='B';
NET_NAME
'SMB_VR_STBY_LVC3_SDA'
 '@BASEBOARD_FAB2_LIB.BASEBOARD_FAB2(SCH_1):SMB_VR_STBY_LVC3_SDA':
 C_SIGNAL='@baseboard_fab2_lib.baseboard_fab2(sch_1):smb_vr_stby_lvc3_sda';
NODE_NAME     R8D17 2
 '@BASEBOARD_FAB2_LIB.BASEBOARD_FAB2(SCH_1):PAGE138_I87@MSTR_DISCRETE.RES(CHIPS)':
 'B': CDS_PINID='B';
NODE_NAME     R8D7 2
 '@BASEBOARD_FAB2_LIB.BASEBOARD_FAB2(SCH_1):PAGE138_I163@MSTR_DISCRETE.RES(CHIPS)':
 'B': CDS_PINID='B';
NODE_NAME     R1U8 2
 '@BASEBOARD_FAB2_LIB.BASEBOARD_FAB2(SCH_1):PAGE159_I223@MSTR_DISCRETE.RES(CHIPS)':
 'B': CDS_PINID='B';
NODE_NAME     J4B2 B18
 '@BASEBOARD_FAB2_LIB.BASEBOARD_FAB2(SCH_1):PAGE193_I46@MSTR_SCONN.SCONN120_H61426002(CHIPS)':
 'IOB18': CDS_PINID='IOB18';
NODE_NAME     J6B1 B18
 '@BASEBOARD_FAB2_LIB.BASEBOARD_FAB2(SCH_1):PAGE194_I56@MSTR_SCONN.SCONN120_H61426002(CHIPS)':
 'IOB18': CDS_PINID='IOB18';
NODE_NAME     R6P32 2
 '@BASEBOARD_FAB2_LIB.BASEBOARD_FAB2(SCH_1):PAGE201_I102@MSTR_DISCRETE.RES(CHIPS)':
 'B': CDS_PINID='B';
NODE_NAME     EU4D4 8
 '@BASEBOARD_FAB2_LIB.BASEBOARD_FAB2(SCH_1):PAGE201_I155@MSTR_CONTROLLER.PXE1610B(CHIPS)':
 'SDA': CDS_PINID='SDA';
NODE_NAME     EU1C2 8
 '@BASEBOARD_FAB2_LIB.BASEBOARD_FAB2(SCH_1):PAGE206_I130@MSTR_CONTROLLER.PXE1610B(CHIPS)':
 'SDA': CDS_PINID='SDA';
NODE_NAME     EU3P1 6
 '@BASEBOARD_FAB2_LIB.BASEBOARD_FAB2(SCH_1):PAGE211_I93@MSTR_CONTROLLER.PXE1110B(CHIPS)':
 'SDA': CDS_PINID='SDA';
NODE_NAME     EU4D5 6
 '@BASEBOARD_FAB2_LIB.BASEBOARD_FAB2(SCH_1):PAGE213_I96@MSTR_CONTROLLER.PXE1110B(CHIPS)':
 'SDA': CDS_PINID='SDA';
NODE_NAME     EU8A1 6
 '@BASEBOARD_FAB2_LIB.BASEBOARD_FAB2(SCH_1):PAGE235_I229@MSTR_CONTROLLER.PXE1110B(CHIPS)':
 'SDA': CDS_PINID='SDA';
NODE_NAME     EU7G1 6
 '@BASEBOARD_FAB2_LIB.BASEBOARD_FAB2(SCH_1):PAGE215_I69@MSTR_CONTROLLER.PXM1310B(CHIPS)':
 'SDA': CDS_PINID='SDA';
NODE_NAME     EU7A5 6
 '@BASEBOARD_FAB2_LIB.BASEBOARD_FAB2(SCH_1):PAGE218_I69@MSTR_CONTROLLER.PXM1310B(CHIPS)':
 'SDA': CDS_PINID='SDA';
NODE_NAME     EU1G2 6
 '@BASEBOARD_FAB2_LIB.BASEBOARD_FAB2(SCH_1):PAGE223_I69@MSTR_CONTROLLER.PXM1310B(CHIPS)':
 'SDA': CDS_PINID='SDA';
NODE_NAME     EU1B1 6
 '@BASEBOARD_FAB2_LIB.BASEBOARD_FAB2(SCH_1):PAGE226_I69@MSTR_CONTROLLER.PXM1310B(CHIPS)':
 'SDA': CDS_PINID='SDA';
NODE_NAME     J8D4 1
 '@BASEBOARD_FAB2_LIB.BASEBOARD_FAB2(SCH_1):PAGE201_I191@W_HDL.PIN-CON3-27-GP(CHIPS)':
 '1': CDS_PINID='\1\';
NET_NAME
'SMB_VR_STBY_LVC3_SDA_R'
 '@BASEBOARD_FAB2_LIB.BASEBOARD_FAB2(SCH_1):SMB_VR_STBY_LVC3_SDA_R':
 C_SIGNAL='@baseboard_fab2_lib.baseboard_fab2(sch_1):smb_vr_stby_lvc3_sda_r';
NODE_NAME     R1U8 1
 '@BASEBOARD_FAB2_LIB.BASEBOARD_FAB2(SCH_1):PAGE159_I223@MSTR_DISCRETE.RES(CHIPS)':
 'A': CDS_PINID='A';
NODE_NAME     U25W4 N2
 '@BASEBOARD_FAB2_LIB.BASEBOARD_FAB2(SCH_1):PAGE144_I95@W_HDL.AST2520A1-GP-GP(CHIPS)':
 'GPIOK3_SDA6': CDS_PINID='GPIOK3_SDA6';
NET_NAME
'SMB_VR_STBY_LVC3_SDA_R1'
 '@BASEBOARD_FAB2_LIB.BASEBOARD_FAB2(SCH_1):SMB_VR_STBY_LVC3_SDA_R1':
 C_SIGNAL='@baseboard_fab2_lib.baseboard_fab2(sch_1):smb_vr_stby_lvc3_sda_r1';
NODE_NAME     U7C1 BD1
 '@BASEBOARD_FAB2_LIB.BASEBOARD_FAB2(SCH_1):PAGE120_I147@MSTR_U_PROC.LBG_CORE_QAT_EXT_D(CHIPS)':
 'GPP_H11_SML2DATA_IE': CDS_PINID='GPP_H11_SML2DATA_IE';
NODE_NAME     R8D7 1
 '@BASEBOARD_FAB2_LIB.BASEBOARD_FAB2(SCH_1):PAGE138_I163@MSTR_DISCRETE.RES(CHIPS)':
 'A': CDS_PINID='A';
NODE_NAME     R8W6 2
 '@BASEBOARD_FAB2_LIB.BASEBOARD_FAB2(SCH_1):PAGE138_I205@MSTR_DISCRETE.RES(CHIPS)':
 'B': CDS_PINID='B';
NET_NAME
'SP1_BMC_HOST_UART_RX'
 '@BASEBOARD_FAB2_LIB.BASEBOARD_FAB2(SCH_1):SP1_BMC_HOST_UART_RX':
 C_SIGNAL='@baseboard_fab2_lib.baseboard_fab2(sch_1):sp1_bmc_host_uart_rx';
NODE_NAME     U9F1 3
 '@BASEBOARD_FAB2_LIB.BASEBOARD_FAB2(SCH_1):PAGE158_I75@MSTR_ANALOG.FSA3357(CHIPS)':
 'B2': CDS_PINID='B2';
NODE_NAME     U8D7 K3
 '@BASEBOARD_FAB2_LIB.BASEBOARD_FAB2(SCH_1):PAGE190_I179@MSTR_MEMORY.LCMXO2_A(CHIPS)':
 'PL10A': CDS_PINID='PL10A';
NODE_NAME     U25W4 W1
 '@BASEBOARD_FAB2_LIB.BASEBOARD_FAB2(SCH_1):PAGE145_I117@W_HDL.AST2520A1-GP-GP(CHIPS)':
 'GPIOL7_RXD1': CDS_PINID='GPIOL7_RXD1';
NODE_NAME     R9W33 2
 '@BASEBOARD_FAB2_LIB.BASEBOARD_FAB2(SCH_1):PAGE158_I153@MSTR_DISCRETE.RES(CHIPS)':
 'B': CDS_PINID='B';
NET_NAME
'SP1_BMC_HOST_UART_TX'
 '@BASEBOARD_FAB2_LIB.BASEBOARD_FAB2(SCH_1):SP1_BMC_HOST_UART_TX':
 C_SIGNAL='@baseboard_fab2_lib.baseboard_fab2(sch_1):sp1_bmc_host_uart_tx';
NODE_NAME     U9F2 3
 '@BASEBOARD_FAB2_LIB.BASEBOARD_FAB2(SCH_1):PAGE158_I74@MSTR_ANALOG.FSA3357(CHIPS)':
 'B2': CDS_PINID='B2';
NODE_NAME     U8D7 K2
 '@BASEBOARD_FAB2_LIB.BASEBOARD_FAB2(SCH_1):PAGE190_I179@MSTR_MEMORY.LCMXO2_A(CHIPS)':
 'PL10B': CDS_PINID='PL10B';
NODE_NAME     U25W4 V1
 '@BASEBOARD_FAB2_LIB.BASEBOARD_FAB2(SCH_1):PAGE145_I117@W_HDL.AST2520A1-GP-GP(CHIPS)':
 'GPIOL6_TXD1': CDS_PINID='GPIOL6_TXD1';
NET_NAME
'SP2_BMC_CM_UART_RX'
 '@BASEBOARD_FAB2_LIB.BASEBOARD_FAB2(SCH_1):SP2_BMC_CM_UART_RX':
 C_SIGNAL='@baseboard_fab2_lib.baseboard_fab2(sch_1):sp2_bmc_cm_uart_rx';
NODE_NAME     R9F24 2
 '@BASEBOARD_FAB2_LIB.BASEBOARD_FAB2(SCH_1):PAGE158_I100@MSTR_DISCRETE.RES(CHIPS)':
 'B': CDS_PINID='B';
NODE_NAME     R9F68 2
 '@BASEBOARD_FAB2_LIB.BASEBOARD_FAB2(SCH_1):PAGE158_I149@MSTR_DISCRETE.RES(CHIPS)':
 'B': CDS_PINID='B';
NODE_NAME     U25W4 T5
 '@BASEBOARD_FAB2_LIB.BASEBOARD_FAB2(SCH_1):PAGE145_I117@W_HDL.AST2520A1-GP-GP(CHIPS)':
 'GPIOM7_RXD2_VPIB9': CDS_PINID='GPIOM7_RXD2_VPIB9';
NET_NAME
'SP2_BMC_CM_UART_RX_R'
 '@BASEBOARD_FAB2_LIB.BASEBOARD_FAB2(SCH_1):SP2_BMC_CM_UART_RX_R':
 C_SIGNAL='@baseboard_fab2_lib.baseboard_fab2(sch_1):sp2_bmc_cm_uart_rx_r';
NODE_NAME     U9F1 1
 '@BASEBOARD_FAB2_LIB.BASEBOARD_FAB2(SCH_1):PAGE158_I75@MSTR_ANALOG.FSA3357(CHIPS)':
 'B0': CDS_PINID='B0';
NODE_NAME     R9F68 1
 '@BASEBOARD_FAB2_LIB.BASEBOARD_FAB2(SCH_1):PAGE158_I149@MSTR_DISCRETE.RES(CHIPS)':
 'A': CDS_PINID='A';
NODE_NAME     R9F69 1
 '@BASEBOARD_FAB2_LIB.BASEBOARD_FAB2(SCH_1):PAGE158_I150@MSTR_DISCRETE.RES(CHIPS)':
 'A': CDS_PINID='A';
NODE_NAME     R9W35 2
 '@BASEBOARD_FAB2_LIB.BASEBOARD_FAB2(SCH_1):PAGE158_I155@MSTR_DISCRETE.RES(CHIPS)':
 'B': CDS_PINID='B';
NET_NAME
'SP2_BMC_CM_UART_RX_R1'
 '@BASEBOARD_FAB2_LIB.BASEBOARD_FAB2(SCH_1):SP2_BMC_CM_UART_RX_R1':
 C_SIGNAL='@baseboard_fab2_lib.baseboard_fab2(sch_1):sp2_bmc_cm_uart_rx_r1';
NODE_NAME     R9F69 2
 '@BASEBOARD_FAB2_LIB.BASEBOARD_FAB2(SCH_1):PAGE158_I150@MSTR_DISCRETE.RES(CHIPS)':
 'B': CDS_PINID='B';
NODE_NAME     R9F67 1
 '@BASEBOARD_FAB2_LIB.BASEBOARD_FAB2(SCH_1):PAGE181_I33@MSTR_DISCRETE.RES(CHIPS)':
 'A': CDS_PINID='A';
NET_NAME
'SP2_BMC_CM_UART_TX'
 '@BASEBOARD_FAB2_LIB.BASEBOARD_FAB2(SCH_1):SP2_BMC_CM_UART_TX':
 C_SIGNAL='@baseboard_fab2_lib.baseboard_fab2(sch_1):sp2_bmc_cm_uart_tx';
NODE_NAME     R9F26 1
 '@BASEBOARD_FAB2_LIB.BASEBOARD_FAB2(SCH_1):PAGE158_I99@MSTR_DISCRETE.RES(CHIPS)':
 'A': CDS_PINID='A';
NODE_NAME     R9F66 1
 '@BASEBOARD_FAB2_LIB.BASEBOARD_FAB2(SCH_1):PAGE158_I152@MSTR_DISCRETE.RES(CHIPS)':
 'A': CDS_PINID='A';
NODE_NAME     U25W4 R5
 '@BASEBOARD_FAB2_LIB.BASEBOARD_FAB2(SCH_1):PAGE145_I117@W_HDL.AST2520A1-GP-GP(CHIPS)':
 'GPIOM6_TXD2_VPIB8': CDS_PINID='GPIOM6_TXD2_VPIB8';
NET_NAME
'SP2_BMC_CM_UART_TX_R'
 '@BASEBOARD_FAB2_LIB.BASEBOARD_FAB2(SCH_1):SP2_BMC_CM_UART_TX_R':
 C_SIGNAL='@baseboard_fab2_lib.baseboard_fab2(sch_1):sp2_bmc_cm_uart_tx_r';
NODE_NAME     U9F2 1
 '@BASEBOARD_FAB2_LIB.BASEBOARD_FAB2(SCH_1):PAGE158_I74@MSTR_ANALOG.FSA3357(CHIPS)':
 'B0': CDS_PINID='B0';
NODE_NAME     R9F65 2
 '@BASEBOARD_FAB2_LIB.BASEBOARD_FAB2(SCH_1):PAGE158_I148@MSTR_DISCRETE.RES(CHIPS)':
 'B': CDS_PINID='B';
NODE_NAME     R9F66 2
 '@BASEBOARD_FAB2_LIB.BASEBOARD_FAB2(SCH_1):PAGE158_I152@MSTR_DISCRETE.RES(CHIPS)':
 'B': CDS_PINID='B';
NET_NAME
'SP2_BMC_CM_UART_TX_R1'
 '@BASEBOARD_FAB2_LIB.BASEBOARD_FAB2(SCH_1):SP2_BMC_CM_UART_TX_R1':
 C_SIGNAL='@baseboard_fab2_lib.baseboard_fab2(sch_1):sp2_bmc_cm_uart_tx_r1';
NODE_NAME     R9F65 1
 '@BASEBOARD_FAB2_LIB.BASEBOARD_FAB2(SCH_1):PAGE158_I148@MSTR_DISCRETE.RES(CHIPS)':
 'A': CDS_PINID='A';
NODE_NAME     R9F64 1
 '@BASEBOARD_FAB2_LIB.BASEBOARD_FAB2(SCH_1):PAGE181_I29@MSTR_DISCRETE.RES(CHIPS)':
 'A': CDS_PINID='A';
NET_NAME
'SPA_5V_SIN_SW'
 '@BASEBOARD_FAB2_LIB.BASEBOARD_FAB2(SCH_1):SPA_5V_SIN_SW':
 C_SIGNAL='@baseboard_fab2_lib.baseboard_fab2(sch_1):spa_5v_sin_sw';
NODE_NAME     J9A2 10
 '@BASEBOARD_FAB2_LIB.BASEBOARD_FAB2(SCH_1):PAGE155_I171@MSTR_CONN.CONN14_H54902001(CHIPS)':
 'IO10': CDS_PINID='IO10';
NODE_NAME     CR9W1 1
 '@BASEBOARD_FAB2_LIB.BASEBOARD_FAB2(SCH_1):PAGE155_I202@MSTR_DISCRETE.DIODE(CHIPS)':
 'C': CDS_PINID='C';
NET_NAME
'SPA_5V_SIN_SW_D'
 '@BASEBOARD_FAB2_LIB.BASEBOARD_FAB2(SCH_1):SPA_5V_SIN_SW_D':
 C_SIGNAL='@baseboard_fab2_lib.baseboard_fab2(sch_1):spa_5v_sin_sw_d';
NODE_NAME     U9A1 2
 '@BASEBOARD_FAB2_LIB.BASEBOARD_FAB2(SCH_1):PAGE155_I178@MSTR_TTL.TTL1G07_A(CHIPS)':
 'A': CDS_PINID='A';
NODE_NAME     R6W19 1
 '@BASEBOARD_FAB2_LIB.BASEBOARD_FAB2(SCH_1):PAGE155_I196@MSTR_DISCRETE.RES(CHIPS)':
 'A': CDS_PINID='A';
NODE_NAME     R6W40 2
 '@BASEBOARD_FAB2_LIB.BASEBOARD_FAB2(SCH_1):PAGE155_I201@MSTR_DISCRETE.RES(CHIPS)':
 'B': CDS_PINID='B';
NODE_NAME     CR9W1 2
 '@BASEBOARD_FAB2_LIB.BASEBOARD_FAB2(SCH_1):PAGE155_I202@MSTR_DISCRETE.DIODE(CHIPS)':
 'A': CDS_PINID='A';
NET_NAME
'SPA_MID_DBG1_RX'
 '@BASEBOARD_FAB2_LIB.BASEBOARD_FAB2(SCH_1):SPA_MID_DBG1_RX':
 C_SIGNAL='@baseboard_fab2_lib.baseboard_fab2(sch_1):spa_mid_dbg1_rx';
NODE_NAME     R9A8 2
 '@BASEBOARD_FAB2_LIB.BASEBOARD_FAB2(SCH_1):PAGE155_I53@MSTR_DISCRETE.RES(CHIPS)':
 'B': CDS_PINID='B';
NODE_NAME     U6W12 3
 '@BASEBOARD_FAB2_LIB.BASEBOARD_FAB2(SCH_1):PAGE176_I182@MSTR_ANALOG.NC7SB3157(CHIPS)':
 'B0': CDS_PINID='B0';
NET_NAME
'SPA_MID_DBG1_TX'
 '@BASEBOARD_FAB2_LIB.BASEBOARD_FAB2(SCH_1):SPA_MID_DBG1_TX':
 C_SIGNAL='@baseboard_fab2_lib.baseboard_fab2(sch_1):spa_mid_dbg1_tx';
NODE_NAME     J9A2 9
 '@BASEBOARD_FAB2_LIB.BASEBOARD_FAB2(SCH_1):PAGE155_I171@MSTR_CONN.CONN14_H54902001(CHIPS)':
 'IO9': CDS_PINID='IO9';
NODE_NAME     R6W36 2
 '@BASEBOARD_FAB2_LIB.BASEBOARD_FAB2(SCH_1):PAGE176_I161@MSTR_DISCRETE.RES(CHIPS)':
 'B': CDS_PINID='B';
NET_NAME
'SPA_MID_DBG1_TX_EN'
 '@BASEBOARD_FAB2_LIB.BASEBOARD_FAB2(SCH_1):SPA_MID_DBG1_TX_EN':
 C_SIGNAL='@baseboard_fab2_lib.baseboard_fab2(sch_1):spa_mid_dbg1_tx_en';
NODE_NAME     U6W6 1
 '@BASEBOARD_FAB2_LIB.BASEBOARD_FAB2(SCH_1):PAGE176_I157@MSTR_TTL.TTL1G126_A(CHIPS)':
 'OE': CDS_PINID='OE';
NODE_NAME     R6W39 1
 '@BASEBOARD_FAB2_LIB.BASEBOARD_FAB2(SCH_1):PAGE176_I158@MSTR_DISCRETE.RES(CHIPS)':
 'A': CDS_PINID='A';
NET_NAME
'SPA_MID_DBG1_TX_R'
 '@BASEBOARD_FAB2_LIB.BASEBOARD_FAB2(SCH_1):SPA_MID_DBG1_TX_R':
 C_SIGNAL='@baseboard_fab2_lib.baseboard_fab2(sch_1):spa_mid_dbg1_tx_r';
NODE_NAME     U6W6 4
 '@BASEBOARD_FAB2_LIB.BASEBOARD_FAB2(SCH_1):PAGE176_I157@MSTR_TTL.TTL1G126_A(CHIPS)':
 'Y': CDS_PINID='Y';
NODE_NAME     R6W36 1
 '@BASEBOARD_FAB2_LIB.BASEBOARD_FAB2(SCH_1):PAGE176_I161@MSTR_DISCRETE.RES(CHIPS)':
 'A': CDS_PINID='A';
NET_NAME
'SPA_MID_DBG2_RX'
 '@BASEBOARD_FAB2_LIB.BASEBOARD_FAB2(SCH_1):SPA_MID_DBG2_RX':
 C_SIGNAL='@baseboard_fab2_lib.baseboard_fab2(sch_1):spa_mid_dbg2_rx';
NODE_NAME     J9B1 9
 '@BASEBOARD_FAB2_LIB.BASEBOARD_FAB2(SCH_1):PAGE176_I69@MSTR_CONN.CONN9_H51826001(CHIPS)':
 'STDA_SSTXP': CDS_PINID='STDA_SSTXP';
NODE_NAME     U6W4 2
 '@BASEBOARD_FAB2_LIB.BASEBOARD_FAB2(SCH_1):PAGE176_I146@MSTR_TTL.TTL1G126_A(CHIPS)':
 'A': CDS_PINID='A';
NODE_NAME     R6W50 2
 '@BASEBOARD_FAB2_LIB.BASEBOARD_FAB2(SCH_1):PAGE176_I178@MSTR_DISCRETE.RES(CHIPS)':
 'B': CDS_PINID='B';
NET_NAME
'SPA_MID_DBG2_RX_BUF'
 '@BASEBOARD_FAB2_LIB.BASEBOARD_FAB2(SCH_1):SPA_MID_DBG2_RX_BUF':
 C_SIGNAL='@baseboard_fab2_lib.baseboard_fab2(sch_1):spa_mid_dbg2_rx_buf';
NODE_NAME     U6W4 4
 '@BASEBOARD_FAB2_LIB.BASEBOARD_FAB2(SCH_1):PAGE176_I146@MSTR_TTL.TTL1G126_A(CHIPS)':
 'Y': CDS_PINID='Y';
NODE_NAME     R6W30 2
 '@BASEBOARD_FAB2_LIB.BASEBOARD_FAB2(SCH_1):PAGE176_I147@MSTR_DISCRETE.RES(CHIPS)':
 'B': CDS_PINID='B';
NODE_NAME     U6W12 1
 '@BASEBOARD_FAB2_LIB.BASEBOARD_FAB2(SCH_1):PAGE176_I182@MSTR_ANALOG.NC7SB3157(CHIPS)':
 'B1': CDS_PINID='B1';
NET_NAME
'SPA_MID_DBG2_TX'
 '@BASEBOARD_FAB2_LIB.BASEBOARD_FAB2(SCH_1):SPA_MID_DBG2_TX':
 C_SIGNAL='@baseboard_fab2_lib.baseboard_fab2(sch_1):spa_mid_dbg2_tx';
NODE_NAME     J9B1 8
 '@BASEBOARD_FAB2_LIB.BASEBOARD_FAB2(SCH_1):PAGE176_I69@MSTR_CONN.CONN9_H51826001(CHIPS)':
 'STDA_SSTXN': CDS_PINID='STDA_SSTXN';
NODE_NAME     R6W37 2
 '@BASEBOARD_FAB2_LIB.BASEBOARD_FAB2(SCH_1):PAGE176_I160@MSTR_DISCRETE.RES(CHIPS)':
 'B': CDS_PINID='B';
NET_NAME
'SPA_MID_DBG2_TX_R'
 '@BASEBOARD_FAB2_LIB.BASEBOARD_FAB2(SCH_1):SPA_MID_DBG2_TX_R':
 C_SIGNAL='@baseboard_fab2_lib.baseboard_fab2(sch_1):spa_mid_dbg2_tx_r';
NODE_NAME     U6W5 4
 '@BASEBOARD_FAB2_LIB.BASEBOARD_FAB2(SCH_1):PAGE176_I148@MSTR_TTL.TTL1G126_A(CHIPS)':
 'Y': CDS_PINID='Y';
NODE_NAME     R6W37 1
 '@BASEBOARD_FAB2_LIB.BASEBOARD_FAB2(SCH_1):PAGE176_I160@MSTR_DISCRETE.RES(CHIPS)':
 'A': CDS_PINID='A';
NET_NAME
'SPA_MID_DBG_RX'
 '@BASEBOARD_FAB2_LIB.BASEBOARD_FAB2(SCH_1):SPA_MID_DBG_RX':
 C_SIGNAL='@baseboard_fab2_lib.baseboard_fab2(sch_1):spa_mid_dbg_rx';
NODE_NAME     R9F25 1
 '@BASEBOARD_FAB2_LIB.BASEBOARD_FAB2(SCH_1):PAGE158_I86@MSTR_DISCRETE.RES(CHIPS)':
 'A': CDS_PINID='A';
NODE_NAME     R9F24 1
 '@BASEBOARD_FAB2_LIB.BASEBOARD_FAB2(SCH_1):PAGE158_I100@MSTR_DISCRETE.RES(CHIPS)':
 'A': CDS_PINID='A';
NODE_NAME     R9F63 1
 '@BASEBOARD_FAB2_LIB.BASEBOARD_FAB2(SCH_1):PAGE181_I28@MSTR_DISCRETE.RES(CHIPS)':
 'A': CDS_PINID='A';
NODE_NAME     U6W12 4
 '@BASEBOARD_FAB2_LIB.BASEBOARD_FAB2(SCH_1):PAGE176_I182@MSTR_ANALOG.NC7SB3157(CHIPS)':
 'A': CDS_PINID='A';
NET_NAME
'SPA_MID_DBG_RX_R'
 '@BASEBOARD_FAB2_LIB.BASEBOARD_FAB2(SCH_1):SPA_MID_DBG_RX_R':
 C_SIGNAL='@baseboard_fab2_lib.baseboard_fab2(sch_1):spa_mid_dbg_rx_r';
NODE_NAME     R9F63 2
 '@BASEBOARD_FAB2_LIB.BASEBOARD_FAB2(SCH_1):PAGE181_I28@MSTR_DISCRETE.RES(CHIPS)':
 'B': CDS_PINID='B';
NODE_NAME     R9F64 2
 '@BASEBOARD_FAB2_LIB.BASEBOARD_FAB2(SCH_1):PAGE181_I29@MSTR_DISCRETE.RES(CHIPS)':
 'B': CDS_PINID='B';
NODE_NAME     J1F1 H3
 '@BASEBOARD_FAB2_LIB.BASEBOARD_FAB2(SCH_1):PAGE181_I134@W_HDL.DM-FCI-CONN76-8R-GP-U-01(CHIPS)':
 'COM_RX': CDS_PINID='COM_RX';
NET_NAME
'SPA_MID_DBG_TX'
 '@BASEBOARD_FAB2_LIB.BASEBOARD_FAB2(SCH_1):SPA_MID_DBG_TX':
 C_SIGNAL='@baseboard_fab2_lib.baseboard_fab2(sch_1):spa_mid_dbg_tx';
NODE_NAME     R9F27 2
 '@BASEBOARD_FAB2_LIB.BASEBOARD_FAB2(SCH_1):PAGE158_I91@MSTR_DISCRETE.RES(CHIPS)':
 'B': CDS_PINID='B';
NODE_NAME     R9F26 2
 '@BASEBOARD_FAB2_LIB.BASEBOARD_FAB2(SCH_1):PAGE158_I99@MSTR_DISCRETE.RES(CHIPS)':
 'B': CDS_PINID='B';
NODE_NAME     R9F70 1
 '@BASEBOARD_FAB2_LIB.BASEBOARD_FAB2(SCH_1):PAGE181_I30@MSTR_DISCRETE.RES(CHIPS)':
 'A': CDS_PINID='A';
NODE_NAME     U6W5 2
 '@BASEBOARD_FAB2_LIB.BASEBOARD_FAB2(SCH_1):PAGE176_I148@MSTR_TTL.TTL1G126_A(CHIPS)':
 'A': CDS_PINID='A';
NODE_NAME     U6W6 2
 '@BASEBOARD_FAB2_LIB.BASEBOARD_FAB2(SCH_1):PAGE176_I157@MSTR_TTL.TTL1G126_A(CHIPS)':
 'A': CDS_PINID='A';
NET_NAME
'SPA_MID_DBG_TX_R'
 '@BASEBOARD_FAB2_LIB.BASEBOARD_FAB2(SCH_1):SPA_MID_DBG_TX_R':
 C_SIGNAL='@baseboard_fab2_lib.baseboard_fab2(sch_1):spa_mid_dbg_tx_r';
NODE_NAME     R9F70 2
 '@BASEBOARD_FAB2_LIB.BASEBOARD_FAB2(SCH_1):PAGE181_I30@MSTR_DISCRETE.RES(CHIPS)':
 'B': CDS_PINID='B';
NODE_NAME     R9F67 2
 '@BASEBOARD_FAB2_LIB.BASEBOARD_FAB2(SCH_1):PAGE181_I33@MSTR_DISCRETE.RES(CHIPS)':
 'B': CDS_PINID='B';
NODE_NAME     J1F1 G3
 '@BASEBOARD_FAB2_LIB.BASEBOARD_FAB2(SCH_1):PAGE181_I134@W_HDL.DM-FCI-CONN76-8R-GP-U-01(CHIPS)':
 'COM_TX': CDS_PINID='COM_TX';
NET_NAME
'SPA_SIN_SW_R'
 '@BASEBOARD_FAB2_LIB.BASEBOARD_FAB2(SCH_1):SPA_SIN_SW_R':
 C_SIGNAL='@baseboard_fab2_lib.baseboard_fab2(sch_1):spa_sin_sw_r';
NODE_NAME     R9A8 1
 '@BASEBOARD_FAB2_LIB.BASEBOARD_FAB2(SCH_1):PAGE155_I53@MSTR_DISCRETE.RES(CHIPS)':
 'A': CDS_PINID='A';
NODE_NAME     R9A7 2
 '@BASEBOARD_FAB2_LIB.BASEBOARD_FAB2(SCH_1):PAGE155_I80@MSTR_DISCRETE.RES(CHIPS)':
 'B': CDS_PINID='B';
NODE_NAME     U9A1 4
 '@BASEBOARD_FAB2_LIB.BASEBOARD_FAB2(SCH_1):PAGE155_I178@MSTR_TTL.TTL1G07_A(CHIPS)':
 'Y': CDS_PINID='Y';
NODE_NAME     R6W19 2
 '@BASEBOARD_FAB2_LIB.BASEBOARD_FAB2(SCH_1):PAGE155_I196@MSTR_DISCRETE.RES(CHIPS)':
 'B': CDS_PINID='B';
NET_NAME
'SPI_BIOS_SOCKET_IO2'
 '@BASEBOARD_FAB2_LIB.BASEBOARD_FAB2(SCH_1):SPI_BIOS_SOCKET_IO2':
 C_SIGNAL='@baseboard_fab2_lib.baseboard_fab2(sch_1):spi_bios_socket_io2';
NODE_NAME     R7F37 1
 '@BASEBOARD_FAB2_LIB.BASEBOARD_FAB2(SCH_1):PAGE153_I108@MSTR_DISCRETE.RES(CHIPS)':
 'A': CDS_PINID='A';
NODE_NAME     R3U1 1
 '@BASEBOARD_FAB2_LIB.BASEBOARD_FAB2(SCH_1):PAGE153_I156@MSTR_DISCRETE.RES(CHIPS)':
 'A': CDS_PINID='A';
NODE_NAME     U2T1 4
 '@BASEBOARD_FAB2_LIB.BASEBOARD_FAB2(SCH_1):PAGE154_I75@MSTR_DIGITAL.PI3B3257A(CHIPS)':
 'YA': CDS_PINID='YA';
NET_NAME
'SPI_BIOS_SOCKET_IO3'
 '@BASEBOARD_FAB2_LIB.BASEBOARD_FAB2(SCH_1):SPI_BIOS_SOCKET_IO3':
 C_SIGNAL='@baseboard_fab2_lib.baseboard_fab2(sch_1):spi_bios_socket_io3';
NODE_NAME     R7F3 1
 '@BASEBOARD_FAB2_LIB.BASEBOARD_FAB2(SCH_1):PAGE153_I109@MSTR_DISCRETE.RES(CHIPS)':
 'A': CDS_PINID='A';
NODE_NAME     R3T1 1
 '@BASEBOARD_FAB2_LIB.BASEBOARD_FAB2(SCH_1):PAGE153_I157@MSTR_DISCRETE.RES(CHIPS)':
 'A': CDS_PINID='A';
NODE_NAME     U2T1 7
 '@BASEBOARD_FAB2_LIB.BASEBOARD_FAB2(SCH_1):PAGE154_I75@MSTR_DIGITAL.PI3B3257A(CHIPS)':
 'YB': CDS_PINID='YB';
NET_NAME
'SPI_BMC_BT_CLK'
 '@BASEBOARD_FAB2_LIB.BASEBOARD_FAB2(SCH_1):SPI_BMC_BT_CLK':
 C_SIGNAL='@baseboard_fab2_lib.baseboard_fab2(sch_1):spi_bmc_bt_clk';
NODE_NAME     U8F2 16
 '@BASEBOARD_FAB2_LIB.BASEBOARD_FAB2(SCH_1):PAGE162_I32@MSTR_MEMORY.W25Q128(CHIPS)':
 'CLK': CDS_PINID='CLK';
NODE_NAME     UN8F2 16
 '@BASEBOARD_FAB2_LIB.BASEBOARD_FAB2(SCH_1):PAGE246_I17@MSTR_MEMORY.W25Q256(CHIPS)':
 'CLK': CDS_PINID='CLK';
NODE_NAME     R25W81 1
 '@BASEBOARD_FAB2_LIB.BASEBOARD_FAB2(SCH_1):PAGE146_I67@MSTR_DISCRETE.RES(CHIPS)':
 'A': CDS_PINID='A';
NODE_NAME     R25W95 2
 '@BASEBOARD_FAB2_LIB.BASEBOARD_FAB2(SCH_1):PAGE150_I144@MSTR_DISCRETE.RES(CHIPS)':
 'B': CDS_PINID='B';
NET_NAME
'SPI_BMC_BT_CLK_R'
 '@BASEBOARD_FAB2_LIB.BASEBOARD_FAB2(SCH_1):SPI_BMC_BT_CLK_R':
 C_SIGNAL='@baseboard_fab2_lib.baseboard_fab2(sch_1):spi_bmc_bt_clk_r';
NODE_NAME     R25W81 2
 '@BASEBOARD_FAB2_LIB.BASEBOARD_FAB2(SCH_1):PAGE146_I67@MSTR_DISCRETE.RES(CHIPS)':
 'B': CDS_PINID='B';
NODE_NAME     U25W4 AA18
 '@BASEBOARD_FAB2_LIB.BASEBOARD_FAB2(SCH_1):PAGE146_I105@W_HDL.AST2520A1-GP-GP(CHIPS)':
 'FWSPICK': CDS_PINID='FWSPICK';
NET_NAME
'SPI_BMC_BT_CS0_N'
 '@BASEBOARD_FAB2_LIB.BASEBOARD_FAB2(SCH_1):SPI_BMC_BT_CS0_N':
 C_SIGNAL='@baseboard_fab2_lib.baseboard_fab2(sch_1):spi_bmc_bt_cs0_n';
NODE_NAME     J9G1 10
 '@BASEBOARD_FAB2_LIB.BASEBOARD_FAB2(SCH_1):PAGE137_I128@MSTR_CONN.CONN12_C73564003(CHIPS)':
 'IO10': CDS_PINID='IO10';
NODE_NAME     UN8F2 7
 '@BASEBOARD_FAB2_LIB.BASEBOARD_FAB2(SCH_1):PAGE246_I17@MSTR_MEMORY.W25Q256(CHIPS)':
 'CS_N': CDS_PINID='CS_N';
NODE_NAME     U25W4 AB19
 '@BASEBOARD_FAB2_LIB.BASEBOARD_FAB2(SCH_1):PAGE146_I105@W_HDL.AST2520A1-GP-GP(CHIPS)':
 'FWSPICS0#': CDS_PINID='\fwspics0#\';
NET_NAME
'SPI_BMC_BT_CS_N'
 '@BASEBOARD_FAB2_LIB.BASEBOARD_FAB2(SCH_1):SPI_BMC_BT_CS_N':
 C_SIGNAL='@baseboard_fab2_lib.baseboard_fab2(sch_1):spi_bmc_bt_cs_n';
NODE_NAME     U8F2 7
 '@BASEBOARD_FAB2_LIB.BASEBOARD_FAB2(SCH_1):PAGE162_I32@MSTR_MEMORY.W25Q128(CHIPS)':
 'CS_N': CDS_PINID='CS_N';
NODE_NAME     R25W78 2
 '@BASEBOARD_FAB2_LIB.BASEBOARD_FAB2(SCH_1):PAGE146_I123@MSTR_DISCRETE.RES(CHIPS)':
 'B': CDS_PINID='B';
NODE_NAME     R8F13 2
 '@BASEBOARD_FAB2_LIB.BASEBOARD_FAB2(SCH_1):PAGE162_I35@MSTR_DISCRETE.RES(CHIPS)':
 'B': CDS_PINID='B';
NET_NAME
'SPI_BMC_BT_CS_R_N'
 '@BASEBOARD_FAB2_LIB.BASEBOARD_FAB2(SCH_1):SPI_BMC_BT_CS_R_N':
 C_SIGNAL='@baseboard_fab2_lib.baseboard_fab2(sch_1):spi_bmc_bt_cs_r_n';
NODE_NAME     U25W4 AA19
 '@BASEBOARD_FAB2_LIB.BASEBOARD_FAB2(SCH_1):PAGE146_I105@W_HDL.AST2520A1-GP-GP(CHIPS)':
 'GPIOR0_FWSPICS1#': CDS_PINID='\gpior0_fwspics1#\';
NODE_NAME     R25W78 1
 '@BASEBOARD_FAB2_LIB.BASEBOARD_FAB2(SCH_1):PAGE146_I123@MSTR_DISCRETE.RES(CHIPS)':
 'A': CDS_PINID='A';
NET_NAME
'SPI_BMC_BT_DI'
 '@BASEBOARD_FAB2_LIB.BASEBOARD_FAB2(SCH_1):SPI_BMC_BT_DI':
 C_SIGNAL='@baseboard_fab2_lib.baseboard_fab2(sch_1):spi_bmc_bt_di';
NODE_NAME     R8F12 1
 '@BASEBOARD_FAB2_LIB.BASEBOARD_FAB2(SCH_1):PAGE162_I13@MSTR_DISCRETE.RES(CHIPS)':
 'A': CDS_PINID='A';
NODE_NAME     RN8F5 1
 '@BASEBOARD_FAB2_LIB.BASEBOARD_FAB2(SCH_1):PAGE246_I9@MSTR_DISCRETE.RES(CHIPS)':
 'A': CDS_PINID='A';
NODE_NAME     U25W4 T18
 '@BASEBOARD_FAB2_LIB.BASEBOARD_FAB2(SCH_1):PAGE146_I105@W_HDL.AST2520A1-GP-GP(CHIPS)':
 'FWSPIMISO': CDS_PINID='FWSPIMISO';
NODE_NAME     R25W97 2
 '@BASEBOARD_FAB2_LIB.BASEBOARD_FAB2(SCH_1):PAGE150_I146@MSTR_DISCRETE.RES(CHIPS)':
 'B': CDS_PINID='B';
NET_NAME
'SPI_BMC_BT_DI_R'
 '@BASEBOARD_FAB2_LIB.BASEBOARD_FAB2(SCH_1):SPI_BMC_BT_DI_R':
 C_SIGNAL='@baseboard_fab2_lib.baseboard_fab2(sch_1):spi_bmc_bt_di_r';
NODE_NAME     R8F12 2
 '@BASEBOARD_FAB2_LIB.BASEBOARD_FAB2(SCH_1):PAGE162_I13@MSTR_DISCRETE.RES(CHIPS)':
 'B': CDS_PINID='B';
NODE_NAME     U8F2 8
 '@BASEBOARD_FAB2_LIB.BASEBOARD_FAB2(SCH_1):PAGE162_I32@MSTR_MEMORY.W25Q128(CHIPS)':
 'DO_IO'<1>: CDS_PINID='DO_IO(1)';
NET_NAME
'SPI_BMC_BT_DO'
 '@BASEBOARD_FAB2_LIB.BASEBOARD_FAB2(SCH_1):SPI_BMC_BT_DO':
 C_SIGNAL='@baseboard_fab2_lib.baseboard_fab2(sch_1):spi_bmc_bt_do';
NODE_NAME     U8F2 15
 '@BASEBOARD_FAB2_LIB.BASEBOARD_FAB2(SCH_1):PAGE162_I32@MSTR_MEMORY.W25Q128(CHIPS)':
 'DI_IO'<0>: CDS_PINID='DI_IO(0)';
NODE_NAME     UN8F2 15
 '@BASEBOARD_FAB2_LIB.BASEBOARD_FAB2(SCH_1):PAGE246_I17@MSTR_MEMORY.W25Q256(CHIPS)':
 'DI_IO'<0>: CDS_PINID='DI_IO(0)';
NODE_NAME     R25W82 1
 '@BASEBOARD_FAB2_LIB.BASEBOARD_FAB2(SCH_1):PAGE146_I68@MSTR_DISCRETE.RES(CHIPS)':
 'A': CDS_PINID='A';
NODE_NAME     R25W96 2
 '@BASEBOARD_FAB2_LIB.BASEBOARD_FAB2(SCH_1):PAGE150_I145@MSTR_DISCRETE.RES(CHIPS)':
 'B': CDS_PINID='B';
NET_NAME
'SPI_BMC_BT_DO_R'
 '@BASEBOARD_FAB2_LIB.BASEBOARD_FAB2(SCH_1):SPI_BMC_BT_DO_R':
 C_SIGNAL='@baseboard_fab2_lib.baseboard_fab2(sch_1):spi_bmc_bt_do_r';
NODE_NAME     R25W82 2
 '@BASEBOARD_FAB2_LIB.BASEBOARD_FAB2(SCH_1):PAGE146_I68@MSTR_DISCRETE.RES(CHIPS)':
 'B': CDS_PINID='B';
NODE_NAME     U25W4 U17
 '@BASEBOARD_FAB2_LIB.BASEBOARD_FAB2(SCH_1):PAGE146_I105@W_HDL.AST2520A1-GP-GP(CHIPS)':
 'FWSPIMOSI': CDS_PINID='FWSPIMOSI';
NET_NAME
'SPI_BMC_BT_WP0_N'
 '@BASEBOARD_FAB2_LIB.BASEBOARD_FAB2(SCH_1):SPI_BMC_BT_WP0_N':
 C_SIGNAL='@baseboard_fab2_lib.baseboard_fab2(sch_1):spi_bmc_bt_wp0_n';
NODE_NAME     U25W4 J18
 '@BASEBOARD_FAB2_LIB.BASEBOARD_FAB2(SCH_1):PAGE145_I117@W_HDL.AST2520A1-GP-GP(CHIPS)':
 'GPIOF1_NDCD4_LHAD1': CDS_PINID='GPIOF1_NDCD4_LHAD1';
NODE_NAME     R25W154 1
 '@BASEBOARD_FAB2_LIB.BASEBOARD_FAB2(SCH_1):PAGE137_I133@MSTR_DISCRETE.RES(CHIPS)':
 'A': CDS_PINID='A';
NET_NAME
'SPI_BMC_CLK'
 '@BASEBOARD_FAB2_LIB.BASEBOARD_FAB2(SCH_1):SPI_BMC_CLK':
 C_SIGNAL='@baseboard_fab2_lib.baseboard_fab2(sch_1):spi_bmc_clk';
NODE_NAME     U8F1 3
 '@BASEBOARD_FAB2_LIB.BASEBOARD_FAB2(SCH_1):PAGE154_I74@MSTR_DIGITAL.PI3B3257A(CHIPS)':
 'IA1': CDS_PINID='IA1';
NODE_NAME     U25W4 C15
 '@BASEBOARD_FAB2_LIB.BASEBOARD_FAB2(SCH_1):PAGE144_I95@W_HDL.AST2520A1-GP-GP(CHIPS)':
 'GPIOI5_SPI1CK_VBCK': CDS_PINID='GPIOI5_SPI1CK_VBCK';
NET_NAME
'SPI_BMC_CS0_N'
 '@BASEBOARD_FAB2_LIB.BASEBOARD_FAB2(SCH_1):SPI_BMC_CS0_N':
 C_SIGNAL='@baseboard_fab2_lib.baseboard_fab2(sch_1):spi_bmc_cs0_n';
NODE_NAME     U8F1 10
 '@BASEBOARD_FAB2_LIB.BASEBOARD_FAB2(SCH_1):PAGE154_I74@MSTR_DIGITAL.PI3B3257A(CHIPS)':
 'IC1': CDS_PINID='IC1';
NODE_NAME     U25W4 B15
 '@BASEBOARD_FAB2_LIB.BASEBOARD_FAB2(SCH_1):PAGE144_I95@W_HDL.AST2520A1-GP-GP(CHIPS)':
 'GPIOI4_SPI1CS0#_VBCS#': CDS_PINID='\gpioi4_spi1cs0#_vbcs#\';
NET_NAME
'SPI_BMC_DI'
 '@BASEBOARD_FAB2_LIB.BASEBOARD_FAB2(SCH_1):SPI_BMC_DI':
 C_SIGNAL='@baseboard_fab2_lib.baseboard_fab2(sch_1):spi_bmc_di';
NODE_NAME     U8F1 13
 '@BASEBOARD_FAB2_LIB.BASEBOARD_FAB2(SCH_1):PAGE154_I74@MSTR_DIGITAL.PI3B3257A(CHIPS)':
 'ID1': CDS_PINID='ID1';
NODE_NAME     U25W4 A15
 '@BASEBOARD_FAB2_LIB.BASEBOARD_FAB2(SCH_1):PAGE144_I95@W_HDL.AST2520A1-GP-GP(CHIPS)':
 'GPIOI7_SPI1MISO_VBMISO': CDS_PINID='GPIOI7_SPI1MISO_VBMISO';
NET_NAME
'SPI_BMC_DO'
 '@BASEBOARD_FAB2_LIB.BASEBOARD_FAB2(SCH_1):SPI_BMC_DO':
 C_SIGNAL='@baseboard_fab2_lib.baseboard_fab2(sch_1):spi_bmc_do';
NODE_NAME     U8F1 6
 '@BASEBOARD_FAB2_LIB.BASEBOARD_FAB2(SCH_1):PAGE154_I74@MSTR_DIGITAL.PI3B3257A(CHIPS)':
 'IB1': CDS_PINID='IB1';
NODE_NAME     U25W4 A14
 '@BASEBOARD_FAB2_LIB.BASEBOARD_FAB2(SCH_1):PAGE144_I95@W_HDL.AST2520A1-GP-GP(CHIPS)':
 'GPIOI6_SPI1MOSI_VBMOSI': CDS_PINID='GPIOI6_SPI1MOSI_VBMOSI';
NET_NAME
'SPI_CLK_R0'
 '@BASEBOARD_FAB2_LIB.BASEBOARD_FAB2(SCH_1):SPI_CLK_R0':
 C_SIGNAL='@baseboard_fab2_lib.baseboard_fab2(sch_1):spi_clk_r0';
NODE_NAME     U7F1 16
 '@BASEBOARD_FAB2_LIB.BASEBOARD_FAB2(SCH_1):PAGE153_I146@MSTR_MEMORY.W25Q256(CHIPS)':
 'CLK': CDS_PINID='CLK';
NODE_NAME     R8F8 2
 '@BASEBOARD_FAB2_LIB.BASEBOARD_FAB2(SCH_1):PAGE153_I166@MSTR_DISCRETE.RES(CHIPS)':
 'B': CDS_PINID='B';
NET_NAME
'SPI_CLK_R1'
 '@BASEBOARD_FAB2_LIB.BASEBOARD_FAB2(SCH_1):SPI_CLK_R1':
 C_SIGNAL='@baseboard_fab2_lib.baseboard_fab2(sch_1):spi_clk_r1';
NODE_NAME     R8F7 2
 '@BASEBOARD_FAB2_LIB.BASEBOARD_FAB2(SCH_1):PAGE153_I167@MSTR_DISCRETE.RES(CHIPS)':
 'B': CDS_PINID='B';
NODE_NAME     U3T1 16
 '@BASEBOARD_FAB2_LIB.BASEBOARD_FAB2(SCH_1):PAGE153_I185@W_HDL.W25Q256FVFIG-GP(CHIPS)':
 'CLK': CDS_PINID='CLK';
NET_NAME
'SPI_CS0_PRIMARY_N'
 '@BASEBOARD_FAB2_LIB.BASEBOARD_FAB2(SCH_1):SPI_CS0_PRIMARY_N':
 C_SIGNAL='@baseboard_fab2_lib.baseboard_fab2(sch_1):spi_cs0_primary_n';
NODE_NAME     U2T3 4
 '@BASEBOARD_FAB2_LIB.BASEBOARD_FAB2(SCH_1):PAGE154_I99@MSTR_TTL.TTL1G32_A(CHIPS)':
 'Y': CDS_PINID='Y';
NODE_NAME     R2T13 1
 '@BASEBOARD_FAB2_LIB.BASEBOARD_FAB2(SCH_1):PAGE154_I101@MSTR_DISCRETE.RES(CHIPS)':
 'A': CDS_PINID='A';
NET_NAME
'SPI_CS0_PRIMARY_R_N'
 '@BASEBOARD_FAB2_LIB.BASEBOARD_FAB2(SCH_1):SPI_CS0_PRIMARY_R_N':
 C_SIGNAL='@baseboard_fab2_lib.baseboard_fab2(sch_1):spi_cs0_primary_r_n';
NODE_NAME     R7F5 2
 '@BASEBOARD_FAB2_LIB.BASEBOARD_FAB2(SCH_1):PAGE153_I94@MSTR_DISCRETE.RES(CHIPS)':
 'B': CDS_PINID='B';
NODE_NAME     U7F1 7
 '@BASEBOARD_FAB2_LIB.BASEBOARD_FAB2(SCH_1):PAGE153_I146@MSTR_MEMORY.W25Q256(CHIPS)':
 'CS_N': CDS_PINID='CS_N';
NODE_NAME     R2T13 2
 '@BASEBOARD_FAB2_LIB.BASEBOARD_FAB2(SCH_1):PAGE154_I101@MSTR_DISCRETE.RES(CHIPS)':
 'B': CDS_PINID='B';
NODE_NAME     R7W5 2
 '@BASEBOARD_FAB2_LIB.BASEBOARD_FAB2(SCH_1):PAGE153_I187@MSTR_DISCRETE.RES(CHIPS)':
 'B': CDS_PINID='B';
NET_NAME
'SPI_CS0_SECONDARY_N'
 '@BASEBOARD_FAB2_LIB.BASEBOARD_FAB2(SCH_1):SPI_CS0_SECONDARY_N':
 C_SIGNAL='@baseboard_fab2_lib.baseboard_fab2(sch_1):spi_cs0_secondary_n';
NODE_NAME     R2T9 1
 '@BASEBOARD_FAB2_LIB.BASEBOARD_FAB2(SCH_1):PAGE154_I62@MSTR_DISCRETE.RES(CHIPS)':
 'A': CDS_PINID='A';
NODE_NAME     U2T2 4
 '@BASEBOARD_FAB2_LIB.BASEBOARD_FAB2(SCH_1):PAGE154_I100@MSTR_TTL.TTL1G32_A(CHIPS)':
 'Y': CDS_PINID='Y';
NET_NAME
'SPI_CS0_SECONDARY_R_N'
 '@BASEBOARD_FAB2_LIB.BASEBOARD_FAB2(SCH_1):SPI_CS0_SECONDARY_R_N':
 C_SIGNAL='@baseboard_fab2_lib.baseboard_fab2(sch_1):spi_cs0_secondary_r_n';
NODE_NAME     R3T5 2
 '@BASEBOARD_FAB2_LIB.BASEBOARD_FAB2(SCH_1):PAGE153_I152@MSTR_DISCRETE.RES(CHIPS)':
 'B': CDS_PINID='B';
NODE_NAME     R2T9 2
 '@BASEBOARD_FAB2_LIB.BASEBOARD_FAB2(SCH_1):PAGE154_I62@MSTR_DISCRETE.RES(CHIPS)':
 'B': CDS_PINID='B';
NODE_NAME     U3T1 7
 '@BASEBOARD_FAB2_LIB.BASEBOARD_FAB2(SCH_1):PAGE153_I185@W_HDL.W25Q256FVFIG-GP(CHIPS)':
 'CS#': CDS_PINID='\cs#\';
NET_NAME
'SPI_MISO_R0'
 '@BASEBOARD_FAB2_LIB.BASEBOARD_FAB2(SCH_1):SPI_MISO_R0':
 C_SIGNAL='@baseboard_fab2_lib.baseboard_fab2(sch_1):spi_miso_r0';
NODE_NAME     R7F4 2
 '@BASEBOARD_FAB2_LIB.BASEBOARD_FAB2(SCH_1):PAGE153_I98@MSTR_DISCRETE.RES(CHIPS)':
 'B': CDS_PINID='B';
NODE_NAME     U7F1 8
 '@BASEBOARD_FAB2_LIB.BASEBOARD_FAB2(SCH_1):PAGE153_I146@MSTR_MEMORY.W25Q256(CHIPS)':
 'DO_IO'<1>: CDS_PINID='DO_IO(1)';
NET_NAME
'SPI_MISO_R1'
 '@BASEBOARD_FAB2_LIB.BASEBOARD_FAB2(SCH_1):SPI_MISO_R1':
 C_SIGNAL='@baseboard_fab2_lib.baseboard_fab2(sch_1):spi_miso_r1';
NODE_NAME     R3T2 2
 '@BASEBOARD_FAB2_LIB.BASEBOARD_FAB2(SCH_1):PAGE153_I155@MSTR_DISCRETE.RES(CHIPS)':
 'B': CDS_PINID='B';
NODE_NAME     U3T1 8
 '@BASEBOARD_FAB2_LIB.BASEBOARD_FAB2(SCH_1):PAGE153_I185@W_HDL.W25Q256FVFIG-GP(CHIPS)':
 'DO/IO1': CDS_PINID='\do/io1\';
NET_NAME
'SPI_NIC_CS_N'
 '@BASEBOARD_FAB2_LIB.BASEBOARD_FAB2(SCH_1):SPI_NIC_CS_N':
 C_SIGNAL='@baseboard_fab2_lib.baseboard_fab2(sch_1):spi_nic_cs_n';
NODE_NAME     R9E5 2
 '@BASEBOARD_FAB2_LIB.BASEBOARD_FAB2(SCH_1):PAGE139_I129@MSTR_DISCRETE.RES(CHIPS)':
 'B': CDS_PINID='B';
NODE_NAME     U9E1 1
 '@BASEBOARD_FAB2_LIB.BASEBOARD_FAB2(SCH_1):PAGE140_I1@MSTR_MEMORY.M25PE16(CHIPS)':
 'S_N': CDS_PINID='S_N';
NET_NAME
'SPI_NIC_CS_R_N'
 '@BASEBOARD_FAB2_LIB.BASEBOARD_FAB2(SCH_1):SPI_NIC_CS_R_N':
 C_SIGNAL='@baseboard_fab2_lib.baseboard_fab2(sch_1):spi_nic_cs_r_n';
NODE_NAME     EU9E1 15
 '@BASEBOARD_FAB2_LIB.BASEBOARD_FAB2(SCH_1):PAGE139_I72@MSTR_INTEL.SPRINGVILLE(CHIPS)':
 'NVM_CS_N': CDS_PINID='NVM_CS_N';
NODE_NAME     R9E5 1
 '@BASEBOARD_FAB2_LIB.BASEBOARD_FAB2(SCH_1):PAGE139_I129@MSTR_DISCRETE.RES(CHIPS)':
 'A': CDS_PINID='A';
NET_NAME
'SPI_NIC_MISO'
 '@BASEBOARD_FAB2_LIB.BASEBOARD_FAB2(SCH_1):SPI_NIC_MISO':
 C_SIGNAL='@baseboard_fab2_lib.baseboard_fab2(sch_1):spi_nic_miso';
NODE_NAME     EU9E1 14
 '@BASEBOARD_FAB2_LIB.BASEBOARD_FAB2(SCH_1):PAGE139_I72@MSTR_INTEL.SPRINGVILLE(CHIPS)':
 'NVM_SO': CDS_PINID='NVM_SO';
NODE_NAME     R9E6 2
 '@BASEBOARD_FAB2_LIB.BASEBOARD_FAB2(SCH_1):PAGE140_I17@MSTR_DISCRETE.RES(CHIPS)':
 'B': CDS_PINID='B';
NET_NAME
'SPI_NIC_MISO_R'
 '@BASEBOARD_FAB2_LIB.BASEBOARD_FAB2(SCH_1):SPI_NIC_MISO_R':
 C_SIGNAL='@baseboard_fab2_lib.baseboard_fab2(sch_1):spi_nic_miso_r';
NODE_NAME     U9E1 2
 '@BASEBOARD_FAB2_LIB.BASEBOARD_FAB2(SCH_1):PAGE140_I1@MSTR_MEMORY.M25PE16(CHIPS)':
 'DQ1': CDS_PINID='DQ1';
NODE_NAME     R9E6 1
 '@BASEBOARD_FAB2_LIB.BASEBOARD_FAB2(SCH_1):PAGE140_I17@MSTR_DISCRETE.RES(CHIPS)':
 'A': CDS_PINID='A';
NET_NAME
'SPI_NIC_MOSI'
 '@BASEBOARD_FAB2_LIB.BASEBOARD_FAB2(SCH_1):SPI_NIC_MOSI':
 C_SIGNAL='@baseboard_fab2_lib.baseboard_fab2(sch_1):spi_nic_mosi';
NODE_NAME     R9E9 2
 '@BASEBOARD_FAB2_LIB.BASEBOARD_FAB2(SCH_1):PAGE139_I128@MSTR_DISCRETE.RES(CHIPS)':
 'B': CDS_PINID='B';
NODE_NAME     U9E1 5
 '@BASEBOARD_FAB2_LIB.BASEBOARD_FAB2(SCH_1):PAGE140_I1@MSTR_MEMORY.M25PE16(CHIPS)':
 'DQ0': CDS_PINID='DQ0';
NODE_NAME     R1R7 2
 '@BASEBOARD_FAB2_LIB.BASEBOARD_FAB2(SCH_1):PAGE140_I12@MSTR_DISCRETE.RES(CHIPS)':
 'B': CDS_PINID='B';
NODE_NAME     R1R6 1
 '@BASEBOARD_FAB2_LIB.BASEBOARD_FAB2(SCH_1):PAGE140_I14@MSTR_DISCRETE.RES(CHIPS)':
 'A': CDS_PINID='A';
NET_NAME
'SPI_NIC_MOSI_R'
 '@BASEBOARD_FAB2_LIB.BASEBOARD_FAB2(SCH_1):SPI_NIC_MOSI_R':
 C_SIGNAL='@baseboard_fab2_lib.baseboard_fab2(sch_1):spi_nic_mosi_r';
NODE_NAME     EU9E1 12
 '@BASEBOARD_FAB2_LIB.BASEBOARD_FAB2(SCH_1):PAGE139_I72@MSTR_INTEL.SPRINGVILLE(CHIPS)':
 'NVM_SI': CDS_PINID='NVM_SI';
NODE_NAME     R9E9 1
 '@BASEBOARD_FAB2_LIB.BASEBOARD_FAB2(SCH_1):PAGE139_I128@MSTR_DISCRETE.RES(CHIPS)':
 'A': CDS_PINID='A';
NET_NAME
'SPI_NIC_SCLK'
 '@BASEBOARD_FAB2_LIB.BASEBOARD_FAB2(SCH_1):SPI_NIC_SCLK':
 C_SIGNAL='@baseboard_fab2_lib.baseboard_fab2(sch_1):spi_nic_sclk';
NODE_NAME     R9E8 2
 '@BASEBOARD_FAB2_LIB.BASEBOARD_FAB2(SCH_1):PAGE139_I130@MSTR_DISCRETE.RES(CHIPS)':
 'B': CDS_PINID='B';
NODE_NAME     U9E1 6
 '@BASEBOARD_FAB2_LIB.BASEBOARD_FAB2(SCH_1):PAGE140_I1@MSTR_MEMORY.M25PE16(CHIPS)':
 'C': CDS_PINID='C';
NET_NAME
'SPI_NIC_SCLK_R'
 '@BASEBOARD_FAB2_LIB.BASEBOARD_FAB2(SCH_1):SPI_NIC_SCLK_R':
 C_SIGNAL='@baseboard_fab2_lib.baseboard_fab2(sch_1):spi_nic_sclk_r';
NODE_NAME     EU9E1 13
 '@BASEBOARD_FAB2_LIB.BASEBOARD_FAB2(SCH_1):PAGE139_I72@MSTR_INTEL.SPRINGVILLE(CHIPS)':
 'NVM_SK': CDS_PINID='NVM_SK';
NODE_NAME     R9E8 1
 '@BASEBOARD_FAB2_LIB.BASEBOARD_FAB2(SCH_1):PAGE139_I130@MSTR_DISCRETE.RES(CHIPS)':
 'A': CDS_PINID='A';
NET_NAME
'SPI_PCH_CLK'
 '@BASEBOARD_FAB2_LIB.BASEBOARD_FAB2(SCH_1):SPI_PCH_CLK':
 C_SIGNAL='@baseboard_fab2_lib.baseboard_fab2(sch_1):spi_pch_clk';
NODE_NAME     U7C1 K2
 '@BASEBOARD_FAB2_LIB.BASEBOARD_FAB2(SCH_1):PAGE121_I34@MSTR_U_PROC.LBG_CORE_QAT_EXT_D(CHIPS)':
 'SPI0_CLK': CDS_PINID='SPI0_CLK';
NODE_NAME     U8F1 2
 '@BASEBOARD_FAB2_LIB.BASEBOARD_FAB2(SCH_1):PAGE154_I74@MSTR_DIGITAL.PI3B3257A(CHIPS)':
 'IA0': CDS_PINID='IA0';
NODE_NAME     R8E9 1
 '@BASEBOARD_FAB2_LIB.BASEBOARD_FAB2(SCH_1):PAGE184_I88@MSTR_DISCRETE.RES(CHIPS)':
 'A': CDS_PINID='A';
NET_NAME
'SPI_PCH_CS0_N'
 '@BASEBOARD_FAB2_LIB.BASEBOARD_FAB2(SCH_1):SPI_PCH_CS0_N':
 C_SIGNAL='@baseboard_fab2_lib.baseboard_fab2(sch_1):spi_pch_cs0_n';
NODE_NAME     R7C16 2
 '@BASEBOARD_FAB2_LIB.BASEBOARD_FAB2(SCH_1):PAGE121_I33@MSTR_DISCRETE.RES(CHIPS)':
 'B': CDS_PINID='B';
NODE_NAME     U8F1 11
 '@BASEBOARD_FAB2_LIB.BASEBOARD_FAB2(SCH_1):PAGE154_I74@MSTR_DIGITAL.PI3B3257A(CHIPS)':
 'IC0': CDS_PINID='IC0';
NET_NAME
'SPI_PCH_CS0_R_N'
 '@BASEBOARD_FAB2_LIB.BASEBOARD_FAB2(SCH_1):SPI_PCH_CS0_R_N':
 C_SIGNAL='@baseboard_fab2_lib.baseboard_fab2(sch_1):spi_pch_cs0_r_n';
NODE_NAME     R7C16 1
 '@BASEBOARD_FAB2_LIB.BASEBOARD_FAB2(SCH_1):PAGE121_I33@MSTR_DISCRETE.RES(CHIPS)':
 'A': CDS_PINID='A';
NODE_NAME     U7C1 J3
 '@BASEBOARD_FAB2_LIB.BASEBOARD_FAB2(SCH_1):PAGE121_I34@MSTR_U_PROC.LBG_CORE_QAT_EXT_D(CHIPS)':
 'SPI0_FLASH_CS0_N': CDS_PINID='SPI0_FLASH_CS0_N';
NET_NAME
'SPI_PCH_IO2'
 '@BASEBOARD_FAB2_LIB.BASEBOARD_FAB2(SCH_1):SPI_PCH_IO2':
 C_SIGNAL='@baseboard_fab2_lib.baseboard_fab2(sch_1):spi_pch_io2';
NODE_NAME     R2P2 1
 '@BASEBOARD_FAB2_LIB.BASEBOARD_FAB2(SCH_1):PAGE111_I37@MSTR_DISCRETE.RES(CHIPS)':
 'A': CDS_PINID='A';
NODE_NAME     U7C1 F5
 '@BASEBOARD_FAB2_LIB.BASEBOARD_FAB2(SCH_1):PAGE121_I34@MSTR_U_PROC.LBG_CORE_QAT_EXT_D(CHIPS)':
 'SPI0_IO2': CDS_PINID='SPI0_IO2';
NODE_NAME     R2R11 1
 '@BASEBOARD_FAB2_LIB.BASEBOARD_FAB2(SCH_1):PAGE125_I11@MSTR_DISCRETE.RES(CHIPS)':
 'A': CDS_PINID='A';
NODE_NAME     R2R12 1
 '@BASEBOARD_FAB2_LIB.BASEBOARD_FAB2(SCH_1):PAGE154_I93@MSTR_DISCRETE.RES(CHIPS)':
 'A': CDS_PINID='A';
NET_NAME
'SPI_PCH_IO2_R1'
 '@BASEBOARD_FAB2_LIB.BASEBOARD_FAB2(SCH_1):SPI_PCH_IO2_R1':
 C_SIGNAL='@baseboard_fab2_lib.baseboard_fab2(sch_1):spi_pch_io2_r1';
NODE_NAME     U2T1 2
 '@BASEBOARD_FAB2_LIB.BASEBOARD_FAB2(SCH_1):PAGE154_I75@MSTR_DIGITAL.PI3B3257A(CHIPS)':
 'IA0': CDS_PINID='IA0';
NODE_NAME     R2R12 2
 '@BASEBOARD_FAB2_LIB.BASEBOARD_FAB2(SCH_1):PAGE154_I93@MSTR_DISCRETE.RES(CHIPS)':
 'B': CDS_PINID='B';
NET_NAME
'SPI_PCH_IO3'
 '@BASEBOARD_FAB2_LIB.BASEBOARD_FAB2(SCH_1):SPI_PCH_IO3':
 C_SIGNAL='@baseboard_fab2_lib.baseboard_fab2(sch_1):spi_pch_io3';
NODE_NAME     U7C1 L1
 '@BASEBOARD_FAB2_LIB.BASEBOARD_FAB2(SCH_1):PAGE121_I34@MSTR_U_PROC.LBG_CORE_QAT_EXT_D(CHIPS)':
 'SPI0_IO3': CDS_PINID='SPI0_IO3';
NODE_NAME     R3N17 2
 '@BASEBOARD_FAB2_LIB.BASEBOARD_FAB2(SCH_1):PAGE125_I78@MSTR_DISCRETE.RES(CHIPS)':
 'B': CDS_PINID='B';
NODE_NAME     R2T2 1
 '@BASEBOARD_FAB2_LIB.BASEBOARD_FAB2(SCH_1):PAGE154_I92@MSTR_DISCRETE.RES(CHIPS)':
 'A': CDS_PINID='A';
NODE_NAME     R2T1 1
 '@BASEBOARD_FAB2_LIB.BASEBOARD_FAB2(SCH_1):PAGE125_I89@MSTR_DISCRETE.RES(CHIPS)':
 'A': CDS_PINID='A';
NET_NAME
'SPI_PCH_IO3_R1'
 '@BASEBOARD_FAB2_LIB.BASEBOARD_FAB2(SCH_1):SPI_PCH_IO3_R1':
 C_SIGNAL='@baseboard_fab2_lib.baseboard_fab2(sch_1):spi_pch_io3_r1';
NODE_NAME     U2T1 5
 '@BASEBOARD_FAB2_LIB.BASEBOARD_FAB2(SCH_1):PAGE154_I75@MSTR_DIGITAL.PI3B3257A(CHIPS)':
 'IB0': CDS_PINID='IB0';
NODE_NAME     R2T2 2
 '@BASEBOARD_FAB2_LIB.BASEBOARD_FAB2(SCH_1):PAGE154_I92@MSTR_DISCRETE.RES(CHIPS)':
 'B': CDS_PINID='B';
NET_NAME
'SPI_PCH_MISO'
 '@BASEBOARD_FAB2_LIB.BASEBOARD_FAB2(SCH_1):SPI_PCH_MISO':
 C_SIGNAL='@baseboard_fab2_lib.baseboard_fab2(sch_1):spi_pch_miso';
NODE_NAME     U7C1 L3
 '@BASEBOARD_FAB2_LIB.BASEBOARD_FAB2(SCH_1):PAGE121_I34@MSTR_U_PROC.LBG_CORE_QAT_EXT_D(CHIPS)':
 'SPI0_MISO_IO1': CDS_PINID='SPI0_MISO_IO1';
NODE_NAME     R8F6 1
 '@BASEBOARD_FAB2_LIB.BASEBOARD_FAB2(SCH_1):PAGE154_I119@MSTR_DISCRETE.RES(CHIPS)':
 'A': CDS_PINID='A';
NODE_NAME     R8E13 1
 '@BASEBOARD_FAB2_LIB.BASEBOARD_FAB2(SCH_1):PAGE184_I93@MSTR_DISCRETE.RES(CHIPS)':
 'A': CDS_PINID='A';
NET_NAME
'SPI_PCH_MISO_R'
 '@BASEBOARD_FAB2_LIB.BASEBOARD_FAB2(SCH_1):SPI_PCH_MISO_R':
 C_SIGNAL='@baseboard_fab2_lib.baseboard_fab2(sch_1):spi_pch_miso_r';
NODE_NAME     U8F1 14
 '@BASEBOARD_FAB2_LIB.BASEBOARD_FAB2(SCH_1):PAGE154_I74@MSTR_DIGITAL.PI3B3257A(CHIPS)':
 'ID0': CDS_PINID='ID0';
NODE_NAME     R8F6 2
 '@BASEBOARD_FAB2_LIB.BASEBOARD_FAB2(SCH_1):PAGE154_I119@MSTR_DISCRETE.RES(CHIPS)':
 'B': CDS_PINID='B';
NET_NAME
'SPI_PCH_MOSI'
 '@BASEBOARD_FAB2_LIB.BASEBOARD_FAB2(SCH_1):SPI_PCH_MOSI':
 C_SIGNAL='@baseboard_fab2_lib.baseboard_fab2(sch_1):spi_pch_mosi';
NODE_NAME     R8E2 2
 '@BASEBOARD_FAB2_LIB.BASEBOARD_FAB2(SCH_1):PAGE111_I89@MSTR_DISCRETE.RES(CHIPS)':
 'B': CDS_PINID='B';
NODE_NAME     R7C15 2
 '@BASEBOARD_FAB2_LIB.BASEBOARD_FAB2(SCH_1):PAGE121_I31@MSTR_DISCRETE.RES(CHIPS)':
 'B': CDS_PINID='B';
NODE_NAME     R8E6 2
 '@BASEBOARD_FAB2_LIB.BASEBOARD_FAB2(SCH_1):PAGE125_I21@MSTR_DISCRETE.RES(CHIPS)':
 'B': CDS_PINID='B';
NODE_NAME     R8E4 1
 '@BASEBOARD_FAB2_LIB.BASEBOARD_FAB2(SCH_1):PAGE125_I24@MSTR_DISCRETE.RES(CHIPS)':
 'A': CDS_PINID='A';
NODE_NAME     U8F1 5
 '@BASEBOARD_FAB2_LIB.BASEBOARD_FAB2(SCH_1):PAGE154_I74@MSTR_DIGITAL.PI3B3257A(CHIPS)':
 'IB0': CDS_PINID='IB0';
NODE_NAME     R8E10 1
 '@BASEBOARD_FAB2_LIB.BASEBOARD_FAB2(SCH_1):PAGE184_I95@MSTR_DISCRETE.RES(CHIPS)':
 'A': CDS_PINID='A';
NET_NAME
'SPI_PCH_MOSI_R'
 '@BASEBOARD_FAB2_LIB.BASEBOARD_FAB2(SCH_1):SPI_PCH_MOSI_R':
 C_SIGNAL='@baseboard_fab2_lib.baseboard_fab2(sch_1):spi_pch_mosi_r';
NODE_NAME     R7C15 1
 '@BASEBOARD_FAB2_LIB.BASEBOARD_FAB2(SCH_1):PAGE121_I31@MSTR_DISCRETE.RES(CHIPS)':
 'A': CDS_PINID='A';
NODE_NAME     U7C1 H4
 '@BASEBOARD_FAB2_LIB.BASEBOARD_FAB2(SCH_1):PAGE121_I34@MSTR_U_PROC.LBG_CORE_QAT_EXT_D(CHIPS)':
 'SPI0_MOSI_IO0': CDS_PINID='SPI0_MOSI_IO0';
NET_NAME
'SPI_PCH_TPM_CLK_R'
 '@BASEBOARD_FAB2_LIB.BASEBOARD_FAB2(SCH_1):SPI_PCH_TPM_CLK_R':
 C_SIGNAL='@baseboard_fab2_lib.baseboard_fab2(sch_1):spi_pch_tpm_clk_r';
NODE_NAME     J8E1 1
 '@BASEBOARD_FAB2_LIB.BASEBOARD_FAB2(SCH_1):PAGE184_I87@MSTR_SCONN.SCONN11_H67026001(CHIPS)':
 'IO1': CDS_PINID='IO1';
NODE_NAME     R8E9 2
 '@BASEBOARD_FAB2_LIB.BASEBOARD_FAB2(SCH_1):PAGE184_I88@MSTR_DISCRETE.RES(CHIPS)':
 'B': CDS_PINID='B';
NET_NAME
'SPI_PCH_TPM_CS_N'
 '@BASEBOARD_FAB2_LIB.BASEBOARD_FAB2(SCH_1):SPI_PCH_TPM_CS_N':
 C_SIGNAL='@baseboard_fab2_lib.baseboard_fab2(sch_1):spi_pch_tpm_cs_n';
NODE_NAME     U7C1 K4
 '@BASEBOARD_FAB2_LIB.BASEBOARD_FAB2(SCH_1):PAGE121_I34@MSTR_U_PROC.LBG_CORE_QAT_EXT_D(CHIPS)':
 'SPI0_TPM_CS_N': CDS_PINID='SPI0_TPM_CS_N';
NODE_NAME     R8D35 1
 '@BASEBOARD_FAB2_LIB.BASEBOARD_FAB2(SCH_1):PAGE184_I92@MSTR_DISCRETE.RES(CHIPS)':
 'A': CDS_PINID='A';
NET_NAME
'SPI_PCH_TPM_CS_R_N'
 '@BASEBOARD_FAB2_LIB.BASEBOARD_FAB2(SCH_1):SPI_PCH_TPM_CS_R_N':
 C_SIGNAL='@baseboard_fab2_lib.baseboard_fab2(sch_1):spi_pch_tpm_cs_r_n';
NODE_NAME     J8E1 5
 '@BASEBOARD_FAB2_LIB.BASEBOARD_FAB2(SCH_1):PAGE184_I87@MSTR_SCONN.SCONN11_H67026001(CHIPS)':
 'IO5': CDS_PINID='IO5';
NODE_NAME     R8D35 2
 '@BASEBOARD_FAB2_LIB.BASEBOARD_FAB2(SCH_1):PAGE184_I92@MSTR_DISCRETE.RES(CHIPS)':
 'B': CDS_PINID='B';
NET_NAME
'SPI_PCH_TPM_MISO_R'
 '@BASEBOARD_FAB2_LIB.BASEBOARD_FAB2(SCH_1):SPI_PCH_TPM_MISO_R':
 C_SIGNAL='@baseboard_fab2_lib.baseboard_fab2(sch_1):spi_pch_tpm_miso_r';
NODE_NAME     J8E1 4
 '@BASEBOARD_FAB2_LIB.BASEBOARD_FAB2(SCH_1):PAGE184_I87@MSTR_SCONN.SCONN11_H67026001(CHIPS)':
 'IO4': CDS_PINID='IO4';
NODE_NAME     R8E13 2
 '@BASEBOARD_FAB2_LIB.BASEBOARD_FAB2(SCH_1):PAGE184_I93@MSTR_DISCRETE.RES(CHIPS)':
 'B': CDS_PINID='B';
NET_NAME
'SPI_PCH_TPM_MOSI_R'
 '@BASEBOARD_FAB2_LIB.BASEBOARD_FAB2(SCH_1):SPI_PCH_TPM_MOSI_R':
 C_SIGNAL='@baseboard_fab2_lib.baseboard_fab2(sch_1):spi_pch_tpm_mosi_r';
NODE_NAME     J8E1 3
 '@BASEBOARD_FAB2_LIB.BASEBOARD_FAB2(SCH_1):PAGE184_I87@MSTR_SCONN.SCONN11_H67026001(CHIPS)':
 'IO3': CDS_PINID='IO3';
NODE_NAME     R8E10 2
 '@BASEBOARD_FAB2_LIB.BASEBOARD_FAB2(SCH_1):PAGE184_I95@MSTR_DISCRETE.RES(CHIPS)':
 'B': CDS_PINID='B';
NET_NAME
'SPI_SWITCH_CLK'
 '@BASEBOARD_FAB2_LIB.BASEBOARD_FAB2(SCH_1):SPI_SWITCH_CLK':
 C_SIGNAL='@baseboard_fab2_lib.baseboard_fab2(sch_1):spi_switch_clk';
NODE_NAME     R8F8 1
 '@BASEBOARD_FAB2_LIB.BASEBOARD_FAB2(SCH_1):PAGE153_I166@MSTR_DISCRETE.RES(CHIPS)':
 'A': CDS_PINID='A';
NODE_NAME     R8F7 1
 '@BASEBOARD_FAB2_LIB.BASEBOARD_FAB2(SCH_1):PAGE153_I167@MSTR_DISCRETE.RES(CHIPS)':
 'A': CDS_PINID='A';
NODE_NAME     U8F1 4
 '@BASEBOARD_FAB2_LIB.BASEBOARD_FAB2(SCH_1):PAGE154_I74@MSTR_DIGITAL.PI3B3257A(CHIPS)':
 'YA': CDS_PINID='YA';
NET_NAME
'SPI_SWITCH_CS0_N'
 '@BASEBOARD_FAB2_LIB.BASEBOARD_FAB2(SCH_1):SPI_SWITCH_CS0_N':
 C_SIGNAL='@baseboard_fab2_lib.baseboard_fab2(sch_1):spi_switch_cs0_n';
NODE_NAME     U8F1 9
 '@BASEBOARD_FAB2_LIB.BASEBOARD_FAB2(SCH_1):PAGE154_I74@MSTR_DIGITAL.PI3B3257A(CHIPS)':
 'YC': CDS_PINID='YC';
NODE_NAME     U2T3 2
 '@BASEBOARD_FAB2_LIB.BASEBOARD_FAB2(SCH_1):PAGE154_I99@MSTR_TTL.TTL1G32_A(CHIPS)':
 'B': CDS_PINID='B';
NODE_NAME     U2T2 2
 '@BASEBOARD_FAB2_LIB.BASEBOARD_FAB2(SCH_1):PAGE154_I100@MSTR_TTL.TTL1G32_A(CHIPS)':
 'B': CDS_PINID='B';
NODE_NAME     R2T8 2
 '@BASEBOARD_FAB2_LIB.BASEBOARD_FAB2(SCH_1):PAGE154_I106@MSTR_DISCRETE.RES(CHIPS)':
 'B': CDS_PINID='B';
NODE_NAME     R7W5 1
 '@BASEBOARD_FAB2_LIB.BASEBOARD_FAB2(SCH_1):PAGE153_I187@MSTR_DISCRETE.RES(CHIPS)':
 'A': CDS_PINID='A';
NET_NAME
'SPI_SWITCH_MISO'
 '@BASEBOARD_FAB2_LIB.BASEBOARD_FAB2(SCH_1):SPI_SWITCH_MISO':
 C_SIGNAL='@baseboard_fab2_lib.baseboard_fab2(sch_1):spi_switch_miso';
NODE_NAME     R7F4 1
 '@BASEBOARD_FAB2_LIB.BASEBOARD_FAB2(SCH_1):PAGE153_I98@MSTR_DISCRETE.RES(CHIPS)':
 'A': CDS_PINID='A';
NODE_NAME     R3T2 1
 '@BASEBOARD_FAB2_LIB.BASEBOARD_FAB2(SCH_1):PAGE153_I155@MSTR_DISCRETE.RES(CHIPS)':
 'A': CDS_PINID='A';
NODE_NAME     U8F1 12
 '@BASEBOARD_FAB2_LIB.BASEBOARD_FAB2(SCH_1):PAGE154_I74@MSTR_DIGITAL.PI3B3257A(CHIPS)':
 'YD': CDS_PINID='YD';
NET_NAME
'SPI_SWITCH_MOSI'
 '@BASEBOARD_FAB2_LIB.BASEBOARD_FAB2(SCH_1):SPI_SWITCH_MOSI':
 C_SIGNAL='@baseboard_fab2_lib.baseboard_fab2(sch_1):spi_switch_mosi';
NODE_NAME     R7F29 1
 '@BASEBOARD_FAB2_LIB.BASEBOARD_FAB2(SCH_1):PAGE153_I181@MSTR_DISCRETE.RES(CHIPS)':
 'A': CDS_PINID='A';
NODE_NAME     R3T10 1
 '@BASEBOARD_FAB2_LIB.BASEBOARD_FAB2(SCH_1):PAGE153_I184@MSTR_DISCRETE.RES(CHIPS)':
 'A': CDS_PINID='A';
NODE_NAME     U8F1 7
 '@BASEBOARD_FAB2_LIB.BASEBOARD_FAB2(SCH_1):PAGE154_I74@MSTR_DIGITAL.PI3B3257A(CHIPS)':
 'YB': CDS_PINID='YB';
NET_NAME
'SPI_SWITCH_MOSI_R0'
 '@BASEBOARD_FAB2_LIB.BASEBOARD_FAB2(SCH_1):SPI_SWITCH_MOSI_R0':
 C_SIGNAL='@baseboard_fab2_lib.baseboard_fab2(sch_1):spi_switch_mosi_r0';
NODE_NAME     U7F1 15
 '@BASEBOARD_FAB2_LIB.BASEBOARD_FAB2(SCH_1):PAGE153_I146@MSTR_MEMORY.W25Q256(CHIPS)':
 'DI_IO'<0>: CDS_PINID='DI_IO(0)';
NODE_NAME     R7F29 2
 '@BASEBOARD_FAB2_LIB.BASEBOARD_FAB2(SCH_1):PAGE153_I181@MSTR_DISCRETE.RES(CHIPS)':
 'B': CDS_PINID='B';
NET_NAME
'SPI_SWITCH_MOSI_R1'
 '@BASEBOARD_FAB2_LIB.BASEBOARD_FAB2(SCH_1):SPI_SWITCH_MOSI_R1':
 C_SIGNAL='@baseboard_fab2_lib.baseboard_fab2(sch_1):spi_switch_mosi_r1';
NODE_NAME     R3T10 2
 '@BASEBOARD_FAB2_LIB.BASEBOARD_FAB2(SCH_1):PAGE153_I184@MSTR_DISCRETE.RES(CHIPS)':
 'B': CDS_PINID='B';
NODE_NAME     U3T1 15
 '@BASEBOARD_FAB2_LIB.BASEBOARD_FAB2(SCH_1):PAGE153_I185@W_HDL.W25Q256FVFIG-GP(CHIPS)':
 'DI/IO0': CDS_PINID='\di/io0\';
NET_NAME
'SPI_TPM_BMC_DI_R'
 '@BASEBOARD_FAB2_LIB.BASEBOARD_FAB2(SCH_1):SPI_TPM_BMC_DI_R':
 C_SIGNAL='@baseboard_fab2_lib.baseboard_fab2(sch_1):spi_tpm_bmc_di_r';
NODE_NAME     RN8F5 2
 '@BASEBOARD_FAB2_LIB.BASEBOARD_FAB2(SCH_1):PAGE246_I9@MSTR_DISCRETE.RES(CHIPS)':
 'B': CDS_PINID='B';
NODE_NAME     UN8F2 8
 '@BASEBOARD_FAB2_LIB.BASEBOARD_FAB2(SCH_1):PAGE246_I17@MSTR_MEMORY.W25Q256(CHIPS)':
 'DO_IO'<1>: CDS_PINID='DO_IO(1)';
NET_NAME
'SVID_ALERT0_CPU0_N'
 '@BASEBOARD_FAB2_LIB.BASEBOARD_FAB2(SCH_1):SVID_ALERT0_CPU0_N':
 C_SIGNAL='@baseboard_fab2_lib.baseboard_fab2(sch_1):svid_alert0_cpu0_n';
NODE_NAME     R6N10 1
 '@BASEBOARD_FAB2_LIB.BASEBOARD_FAB2(SCH_1):PAGE21_I149@MSTR_DISCRETE.RES(CHIPS)':
 'A': CDS_PINID='A';
NODE_NAME     U5D1 DE44
 '@BASEBOARD_FAB2_LIB.BASEBOARD_FAB2(SCH_1):PAGE21_I259@CHPSET_LIB.SKX_EXT_B(CHIPS)':
 'SVIDALERT_N'<0>: CDS_PINID='SVIDALERT_N(0)';
NET_NAME
'SVID_ALERT0_CPU0_R_N'
 '@BASEBOARD_FAB2_LIB.BASEBOARD_FAB2(SCH_1):SVID_ALERT0_CPU0_R_N':
 C_SIGNAL='@baseboard_fab2_lib.baseboard_fab2(sch_1):svid_alert0_cpu0_r_n';
NODE_NAME     R6N10 2
 '@BASEBOARD_FAB2_LIB.BASEBOARD_FAB2(SCH_1):PAGE21_I149@MSTR_DISCRETE.RES(CHIPS)':
 'B': CDS_PINID='B';
NODE_NAME     R6N1 1
 '@BASEBOARD_FAB2_LIB.BASEBOARD_FAB2(SCH_1):PAGE21_I164@MSTR_DISCRETE.RES(CHIPS)':
 'A': CDS_PINID='A';
NODE_NAME     J6B1 A19
 '@BASEBOARD_FAB2_LIB.BASEBOARD_FAB2(SCH_1):PAGE194_I56@MSTR_SCONN.SCONN120_H61426002(CHIPS)':
 'IOA19': CDS_PINID='IOA19';
NODE_NAME     R4D67 2
 '@BASEBOARD_FAB2_LIB.BASEBOARD_FAB2(SCH_1):PAGE201_I26@MSTR_DISCRETE.RES(CHIPS)':
 'B': CDS_PINID='B';
NODE_NAME     R3P1 2
 '@BASEBOARD_FAB2_LIB.BASEBOARD_FAB2(SCH_1):PAGE211_I61@MSTR_DISCRETE.RES(CHIPS)':
 'B': CDS_PINID='B';
NET_NAME
'SVID_ALERT0_CPU1_N'
 '@BASEBOARD_FAB2_LIB.BASEBOARD_FAB2(SCH_1):SVID_ALERT0_CPU1_N':
 C_SIGNAL='@baseboard_fab2_lib.baseboard_fab2(sch_1):svid_alert0_cpu1_n';
NODE_NAME     R3B1 1
 '@BASEBOARD_FAB2_LIB.BASEBOARD_FAB2(SCH_1):PAGE55_I27@MSTR_DISCRETE.RES(CHIPS)':
 'A': CDS_PINID='A';
NODE_NAME     U2D1 DE44
 '@BASEBOARD_FAB2_LIB.BASEBOARD_FAB2(SCH_1):PAGE55_I172@CHPSET_LIB.SKX_EXT_B(CHIPS)':
 'SVIDALERT_N'<0>: CDS_PINID='SVIDALERT_N(0)';
NET_NAME
'SVID_ALERT0_CPU1_R_N'
 '@BASEBOARD_FAB2_LIB.BASEBOARD_FAB2(SCH_1):SVID_ALERT0_CPU1_R_N':
 C_SIGNAL='@baseboard_fab2_lib.baseboard_fab2(sch_1):svid_alert0_cpu1_r_n';
NODE_NAME     R3B2 1
 '@BASEBOARD_FAB2_LIB.BASEBOARD_FAB2(SCH_1):PAGE55_I19@MSTR_DISCRETE.RES(CHIPS)':
 'A': CDS_PINID='A';
NODE_NAME     R3B1 2
 '@BASEBOARD_FAB2_LIB.BASEBOARD_FAB2(SCH_1):PAGE55_I27@MSTR_DISCRETE.RES(CHIPS)':
 'B': CDS_PINID='B';
NODE_NAME     J4B2 A19
 '@BASEBOARD_FAB2_LIB.BASEBOARD_FAB2(SCH_1):PAGE193_I46@MSTR_SCONN.SCONN120_H61426002(CHIPS)':
 'IOA19': CDS_PINID='IOA19';
NODE_NAME     R1D3 2
 '@BASEBOARD_FAB2_LIB.BASEBOARD_FAB2(SCH_1):PAGE206_I37@MSTR_DISCRETE.RES(CHIPS)':
 'B': CDS_PINID='B';
NODE_NAME     R4D56 2
 '@BASEBOARD_FAB2_LIB.BASEBOARD_FAB2(SCH_1):PAGE213_I16@MSTR_DISCRETE.RES(CHIPS)':
 'B': CDS_PINID='B';
NET_NAME
'SVID_ALERT1_CPU0_N'
 '@BASEBOARD_FAB2_LIB.BASEBOARD_FAB2(SCH_1):SVID_ALERT1_CPU0_N':
 C_SIGNAL='@baseboard_fab2_lib.baseboard_fab2(sch_1):svid_alert1_cpu0_n';
NODE_NAME     R6B3 1
 '@BASEBOARD_FAB2_LIB.BASEBOARD_FAB2(SCH_1):PAGE21_I152@MSTR_DISCRETE.RES(CHIPS)':
 'A': CDS_PINID='A';
NODE_NAME     U5D1 DL44
 '@BASEBOARD_FAB2_LIB.BASEBOARD_FAB2(SCH_1):PAGE21_I259@CHPSET_LIB.SKX_EXT_B(CHIPS)':
 'SVIDALERT_N'<1>: CDS_PINID='SVIDALERT_N(1)';
NET_NAME
'SVID_ALERT1_CPU0_R_N'
 '@BASEBOARD_FAB2_LIB.BASEBOARD_FAB2(SCH_1):SVID_ALERT1_CPU0_R_N':
 C_SIGNAL='@baseboard_fab2_lib.baseboard_fab2(sch_1):svid_alert1_cpu0_r_n';
NODE_NAME     R6B3 2
 '@BASEBOARD_FAB2_LIB.BASEBOARD_FAB2(SCH_1):PAGE21_I152@MSTR_DISCRETE.RES(CHIPS)':
 'B': CDS_PINID='B';
NODE_NAME     R6B1 2
 '@BASEBOARD_FAB2_LIB.BASEBOARD_FAB2(SCH_1):PAGE21_I161@MSTR_DISCRETE.RES(CHIPS)':
 'B': CDS_PINID='B';
NODE_NAME     J6B1 B19
 '@BASEBOARD_FAB2_LIB.BASEBOARD_FAB2(SCH_1):PAGE194_I56@MSTR_SCONN.SCONN120_H61426002(CHIPS)':
 'IOB19': CDS_PINID='IOB19';
NODE_NAME     R7G4 2
 '@BASEBOARD_FAB2_LIB.BASEBOARD_FAB2(SCH_1):PAGE215_I49@MSTR_DISCRETE.RES(CHIPS)':
 'B': CDS_PINID='B';
NODE_NAME     R7A11 2
 '@BASEBOARD_FAB2_LIB.BASEBOARD_FAB2(SCH_1):PAGE218_I56@MSTR_DISCRETE.RES(CHIPS)':
 'B': CDS_PINID='B';
NET_NAME
'SVID_ALERT1_CPU1_N'
 '@BASEBOARD_FAB2_LIB.BASEBOARD_FAB2(SCH_1):SVID_ALERT1_CPU1_N':
 C_SIGNAL='@baseboard_fab2_lib.baseboard_fab2(sch_1):svid_alert1_cpu1_n';
NODE_NAME     R1C1 1
 '@BASEBOARD_FAB2_LIB.BASEBOARD_FAB2(SCH_1):PAGE55_I26@MSTR_DISCRETE.RES(CHIPS)':
 'A': CDS_PINID='A';
NODE_NAME     U2D1 DL44
 '@BASEBOARD_FAB2_LIB.BASEBOARD_FAB2(SCH_1):PAGE55_I172@CHPSET_LIB.SKX_EXT_B(CHIPS)':
 'SVIDALERT_N'<1>: CDS_PINID='SVIDALERT_N(1)';
NET_NAME
'SVID_ALERT1_CPU1_R_N'
 '@BASEBOARD_FAB2_LIB.BASEBOARD_FAB2(SCH_1):SVID_ALERT1_CPU1_R_N':
 C_SIGNAL='@baseboard_fab2_lib.baseboard_fab2(sch_1):svid_alert1_cpu1_r_n';
NODE_NAME     R9N1 2
 '@BASEBOARD_FAB2_LIB.BASEBOARD_FAB2(SCH_1):PAGE55_I4@MSTR_DISCRETE.RES(CHIPS)':
 'B': CDS_PINID='B';
NODE_NAME     R1C1 2
 '@BASEBOARD_FAB2_LIB.BASEBOARD_FAB2(SCH_1):PAGE55_I26@MSTR_DISCRETE.RES(CHIPS)':
 'B': CDS_PINID='B';
NODE_NAME     J4B2 B19
 '@BASEBOARD_FAB2_LIB.BASEBOARD_FAB2(SCH_1):PAGE193_I46@MSTR_SCONN.SCONN120_H61426002(CHIPS)':
 'IOB19': CDS_PINID='IOB19';
NODE_NAME     R1G9 2
 '@BASEBOARD_FAB2_LIB.BASEBOARD_FAB2(SCH_1):PAGE223_I50@MSTR_DISCRETE.RES(CHIPS)':
 'B': CDS_PINID='B';
NODE_NAME     R1B11 2
 '@BASEBOARD_FAB2_LIB.BASEBOARD_FAB2(SCH_1):PAGE226_I48@MSTR_DISCRETE.RES(CHIPS)':
 'B': CDS_PINID='B';
NET_NAME
'SVID_ALERT_PVCCIO_CPU0'
 '@BASEBOARD_FAB2_LIB.BASEBOARD_FAB2(SCH_1):SVID_ALERT_PVCCIO_CPU0':
 C_SIGNAL='@baseboard_fab2_lib.baseboard_fab2(sch_1):svid_alert_pvccio_cpu0';
NODE_NAME     R3P1 1
 '@BASEBOARD_FAB2_LIB.BASEBOARD_FAB2(SCH_1):PAGE211_I61@MSTR_DISCRETE.RES(CHIPS)':
 'A': CDS_PINID='A';
NODE_NAME     EU3P1 17
 '@BASEBOARD_FAB2_LIB.BASEBOARD_FAB2(SCH_1):PAGE211_I93@MSTR_CONTROLLER.PXE1110B(CHIPS)':
 'VALRT_N': CDS_PINID='VALRT_N';
NET_NAME
'SVID_ALERT_PVCCIO_CPU1'
 '@BASEBOARD_FAB2_LIB.BASEBOARD_FAB2(SCH_1):SVID_ALERT_PVCCIO_CPU1':
 C_SIGNAL='@baseboard_fab2_lib.baseboard_fab2(sch_1):svid_alert_pvccio_cpu1';
NODE_NAME     R4D56 1
 '@BASEBOARD_FAB2_LIB.BASEBOARD_FAB2(SCH_1):PAGE213_I16@MSTR_DISCRETE.RES(CHIPS)':
 'A': CDS_PINID='A';
NODE_NAME     EU4D5 17
 '@BASEBOARD_FAB2_LIB.BASEBOARD_FAB2(SCH_1):PAGE213_I96@MSTR_CONTROLLER.PXE1110B(CHIPS)':
 'VALRT_N': CDS_PINID='VALRT_N';
NET_NAME
'SVID_ALERT_PVDDQ_ABC'
 '@BASEBOARD_FAB2_LIB.BASEBOARD_FAB2(SCH_1):SVID_ALERT_PVDDQ_ABC':
 C_SIGNAL='@baseboard_fab2_lib.baseboard_fab2(sch_1):svid_alert_pvddq_abc';
NODE_NAME     R7G4 1
 '@BASEBOARD_FAB2_LIB.BASEBOARD_FAB2(SCH_1):PAGE215_I49@MSTR_DISCRETE.RES(CHIPS)':
 'A': CDS_PINID='A';
NODE_NAME     EU7G1 17
 '@BASEBOARD_FAB2_LIB.BASEBOARD_FAB2(SCH_1):PAGE215_I69@MSTR_CONTROLLER.PXM1310B(CHIPS)':
 'VALRT_N': CDS_PINID='VALRT_N';
NET_NAME
'SVID_ALERT_PVDDQ_DEF'
 '@BASEBOARD_FAB2_LIB.BASEBOARD_FAB2(SCH_1):SVID_ALERT_PVDDQ_DEF':
 C_SIGNAL='@baseboard_fab2_lib.baseboard_fab2(sch_1):svid_alert_pvddq_def';
NODE_NAME     R7A11 1
 '@BASEBOARD_FAB2_LIB.BASEBOARD_FAB2(SCH_1):PAGE218_I56@MSTR_DISCRETE.RES(CHIPS)':
 'A': CDS_PINID='A';
NODE_NAME     EU7A5 17
 '@BASEBOARD_FAB2_LIB.BASEBOARD_FAB2(SCH_1):PAGE218_I69@MSTR_CONTROLLER.PXM1310B(CHIPS)':
 'VALRT_N': CDS_PINID='VALRT_N';
NET_NAME
'SVID_ALERT_PVDDQ_GHJ'
 '@BASEBOARD_FAB2_LIB.BASEBOARD_FAB2(SCH_1):SVID_ALERT_PVDDQ_GHJ':
 C_SIGNAL='@baseboard_fab2_lib.baseboard_fab2(sch_1):svid_alert_pvddq_ghj';
NODE_NAME     EU1G2 17
 '@BASEBOARD_FAB2_LIB.BASEBOARD_FAB2(SCH_1):PAGE223_I69@MSTR_CONTROLLER.PXM1310B(CHIPS)':
 'VALRT_N': CDS_PINID='VALRT_N';
NODE_NAME     R1G9 1
 '@BASEBOARD_FAB2_LIB.BASEBOARD_FAB2(SCH_1):PAGE223_I50@MSTR_DISCRETE.RES(CHIPS)':
 'A': CDS_PINID='A';
NET_NAME
'SVID_ALERT_PVDDQ_KLM'
 '@BASEBOARD_FAB2_LIB.BASEBOARD_FAB2(SCH_1):SVID_ALERT_PVDDQ_KLM':
 C_SIGNAL='@baseboard_fab2_lib.baseboard_fab2(sch_1):svid_alert_pvddq_klm';
NODE_NAME     R1B11 1
 '@BASEBOARD_FAB2_LIB.BASEBOARD_FAB2(SCH_1):PAGE226_I48@MSTR_DISCRETE.RES(CHIPS)':
 'A': CDS_PINID='A';
NODE_NAME     EU1B1 17
 '@BASEBOARD_FAB2_LIB.BASEBOARD_FAB2(SCH_1):PAGE226_I69@MSTR_CONTROLLER.PXM1310B(CHIPS)':
 'VALRT_N': CDS_PINID='VALRT_N';
NET_NAME
'SVID_CLK0_CPU0'
 '@BASEBOARD_FAB2_LIB.BASEBOARD_FAB2(SCH_1):SVID_CLK0_CPU0':
 C_SIGNAL='@baseboard_fab2_lib.baseboard_fab2(sch_1):svid_clk0_cpu0';
NODE_NAME     R6N12 1
 '@BASEBOARD_FAB2_LIB.BASEBOARD_FAB2(SCH_1):PAGE21_I150@MSTR_DISCRETE.RES(CHIPS)':
 'A': CDS_PINID='A';
NODE_NAME     U5D1 DC44
 '@BASEBOARD_FAB2_LIB.BASEBOARD_FAB2(SCH_1):PAGE21_I259@CHPSET_LIB.SKX_EXT_B(CHIPS)':
 'SVIDCLK'<0>: CDS_PINID='SVIDCLK(0)';
NET_NAME
'SVID_CLK0_CPU0_R'
 '@BASEBOARD_FAB2_LIB.BASEBOARD_FAB2(SCH_1):SVID_CLK0_CPU0_R':
 C_SIGNAL='@baseboard_fab2_lib.baseboard_fab2(sch_1):svid_clk0_cpu0_r';
NODE_NAME     R6N12 2
 '@BASEBOARD_FAB2_LIB.BASEBOARD_FAB2(SCH_1):PAGE21_I150@MSTR_DISCRETE.RES(CHIPS)':
 'B': CDS_PINID='B';
NODE_NAME     J6B1 A20
 '@BASEBOARD_FAB2_LIB.BASEBOARD_FAB2(SCH_1):PAGE194_I56@MSTR_SCONN.SCONN120_H61426002(CHIPS)':
 'IOA20': CDS_PINID='IOA20';
NODE_NAME     R4E6 1
 '@BASEBOARD_FAB2_LIB.BASEBOARD_FAB2(SCH_1):PAGE201_I56@MSTR_DISCRETE.RES(CHIPS)':
 'A': CDS_PINID='A';
NODE_NAME     R3P15 1
 '@BASEBOARD_FAB2_LIB.BASEBOARD_FAB2(SCH_1):PAGE211_I29@MSTR_DISCRETE.RES(CHIPS)':
 'A': CDS_PINID='A';
NODE_NAME     R4E9 2
 '@BASEBOARD_FAB2_LIB.BASEBOARD_FAB2(SCH_1):PAGE201_I189@MSTR_DISCRETE.RES(CHIPS)':
 'B': CDS_PINID='B';
NODE_NAME     R3P17 2
 '@BASEBOARD_FAB2_LIB.BASEBOARD_FAB2(SCH_1):PAGE211_I99@MSTR_DISCRETE.RES(CHIPS)':
 'B': CDS_PINID='B';
NET_NAME
'SVID_CLK0_CPU1'
 '@BASEBOARD_FAB2_LIB.BASEBOARD_FAB2(SCH_1):SVID_CLK0_CPU1':
 C_SIGNAL='@baseboard_fab2_lib.baseboard_fab2(sch_1):svid_clk0_cpu1';
NODE_NAME     R3B5 1
 '@BASEBOARD_FAB2_LIB.BASEBOARD_FAB2(SCH_1):PAGE55_I28@MSTR_DISCRETE.RES(CHIPS)':
 'A': CDS_PINID='A';
NODE_NAME     U2D1 DC44
 '@BASEBOARD_FAB2_LIB.BASEBOARD_FAB2(SCH_1):PAGE55_I172@CHPSET_LIB.SKX_EXT_B(CHIPS)':
 'SVIDCLK'<0>: CDS_PINID='SVIDCLK(0)';
NET_NAME
'SVID_CLK0_CPU1_R'
 '@BASEBOARD_FAB2_LIB.BASEBOARD_FAB2(SCH_1):SVID_CLK0_CPU1_R':
 C_SIGNAL='@baseboard_fab2_lib.baseboard_fab2(sch_1):svid_clk0_cpu1_r';
NODE_NAME     R3B5 2
 '@BASEBOARD_FAB2_LIB.BASEBOARD_FAB2(SCH_1):PAGE55_I28@MSTR_DISCRETE.RES(CHIPS)':
 'B': CDS_PINID='B';
NODE_NAME     J4B2 A20
 '@BASEBOARD_FAB2_LIB.BASEBOARD_FAB2(SCH_1):PAGE193_I46@MSTR_SCONN.SCONN120_H61426002(CHIPS)':
 'IOA20': CDS_PINID='IOA20';
NODE_NAME     R9P2 2
 '@BASEBOARD_FAB2_LIB.BASEBOARD_FAB2(SCH_1):PAGE206_I53@MSTR_DISCRETE.RES(CHIPS)':
 'B': CDS_PINID='B';
NODE_NAME     R1D9 1
 '@BASEBOARD_FAB2_LIB.BASEBOARD_FAB2(SCH_1):PAGE206_I54@MSTR_DISCRETE.RES(CHIPS)':
 'A': CDS_PINID='A';
NODE_NAME     R6P33 2
 '@BASEBOARD_FAB2_LIB.BASEBOARD_FAB2(SCH_1):PAGE213_I30@MSTR_DISCRETE.RES(CHIPS)':
 'B': CDS_PINID='B';
NODE_NAME     R4D51 1
 '@BASEBOARD_FAB2_LIB.BASEBOARD_FAB2(SCH_1):PAGE213_I46@MSTR_DISCRETE.RES(CHIPS)':
 'A': CDS_PINID='A';
NET_NAME
'SVID_CLK1_CPU0'
 '@BASEBOARD_FAB2_LIB.BASEBOARD_FAB2(SCH_1):SVID_CLK1_CPU0':
 C_SIGNAL='@baseboard_fab2_lib.baseboard_fab2(sch_1):svid_clk1_cpu0';
NODE_NAME     R6B5 1
 '@BASEBOARD_FAB2_LIB.BASEBOARD_FAB2(SCH_1):PAGE21_I153@MSTR_DISCRETE.RES(CHIPS)':
 'A': CDS_PINID='A';
NODE_NAME     U5D1 DG44
 '@BASEBOARD_FAB2_LIB.BASEBOARD_FAB2(SCH_1):PAGE21_I259@CHPSET_LIB.SKX_EXT_B(CHIPS)':
 'SVIDCLK'<1>: CDS_PINID='SVIDCLK(1)';
NET_NAME
'SVID_CLK1_CPU0_R'
 '@BASEBOARD_FAB2_LIB.BASEBOARD_FAB2(SCH_1):SVID_CLK1_CPU0_R':
 C_SIGNAL='@baseboard_fab2_lib.baseboard_fab2(sch_1):svid_clk1_cpu0_r';
NODE_NAME     R6B5 2
 '@BASEBOARD_FAB2_LIB.BASEBOARD_FAB2(SCH_1):PAGE21_I153@MSTR_DISCRETE.RES(CHIPS)':
 'B': CDS_PINID='B';
NODE_NAME     J6B1 E20
 '@BASEBOARD_FAB2_LIB.BASEBOARD_FAB2(SCH_1):PAGE194_I56@MSTR_SCONN.SCONN120_H61426002(CHIPS)':
 'IOE20': CDS_PINID='IOE20';
NODE_NAME     R7A17 1
 '@BASEBOARD_FAB2_LIB.BASEBOARD_FAB2(SCH_1):PAGE218_I21@MSTR_DISCRETE.RES(CHIPS)':
 'A': CDS_PINID='A';
NODE_NAME     R7G24 1
 '@BASEBOARD_FAB2_LIB.BASEBOARD_FAB2(SCH_1):PAGE215_I28@MSTR_DISCRETE.RES(CHIPS)':
 'A': CDS_PINID='A';
NODE_NAME     R3T11 2
 '@BASEBOARD_FAB2_LIB.BASEBOARD_FAB2(SCH_1):PAGE215_I70@MSTR_DISCRETE.RES(CHIPS)':
 'B': CDS_PINID='B';
NODE_NAME     R3L13 2
 '@BASEBOARD_FAB2_LIB.BASEBOARD_FAB2(SCH_1):PAGE218_I70@MSTR_DISCRETE.RES(CHIPS)':
 'B': CDS_PINID='B';
NET_NAME
'SVID_CLK1_CPU1'
 '@BASEBOARD_FAB2_LIB.BASEBOARD_FAB2(SCH_1):SVID_CLK1_CPU1':
 C_SIGNAL='@baseboard_fab2_lib.baseboard_fab2(sch_1):svid_clk1_cpu1';
NODE_NAME     R1C3 1
 '@BASEBOARD_FAB2_LIB.BASEBOARD_FAB2(SCH_1):PAGE55_I25@MSTR_DISCRETE.RES(CHIPS)':
 'A': CDS_PINID='A';
NODE_NAME     U2D1 DG44
 '@BASEBOARD_FAB2_LIB.BASEBOARD_FAB2(SCH_1):PAGE55_I172@CHPSET_LIB.SKX_EXT_B(CHIPS)':
 'SVIDCLK'<1>: CDS_PINID='SVIDCLK(1)';
NET_NAME
'SVID_CLK1_CPU1_R'
 '@BASEBOARD_FAB2_LIB.BASEBOARD_FAB2(SCH_1):SVID_CLK1_CPU1_R':
 C_SIGNAL='@baseboard_fab2_lib.baseboard_fab2(sch_1):svid_clk1_cpu1_r';
NODE_NAME     R1C3 2
 '@BASEBOARD_FAB2_LIB.BASEBOARD_FAB2(SCH_1):PAGE55_I25@MSTR_DISCRETE.RES(CHIPS)':
 'B': CDS_PINID='B';
NODE_NAME     J4B2 E20
 '@BASEBOARD_FAB2_LIB.BASEBOARD_FAB2(SCH_1):PAGE193_I46@MSTR_SCONN.SCONN120_H61426002(CHIPS)':
 'IOE20': CDS_PINID='IOE20';
NODE_NAME     R1G7 1
 '@BASEBOARD_FAB2_LIB.BASEBOARD_FAB2(SCH_1):PAGE223_I18@MSTR_DISCRETE.RES(CHIPS)':
 'A': CDS_PINID='A';
NODE_NAME     R1B8 1
 '@BASEBOARD_FAB2_LIB.BASEBOARD_FAB2(SCH_1):PAGE226_I19@MSTR_DISCRETE.RES(CHIPS)':
 'A': CDS_PINID='A';
NODE_NAME     R9M6 2
 '@BASEBOARD_FAB2_LIB.BASEBOARD_FAB2(SCH_1):PAGE226_I70@MSTR_DISCRETE.RES(CHIPS)':
 'B': CDS_PINID='B';
NODE_NAME     R9U4 2
 '@BASEBOARD_FAB2_LIB.BASEBOARD_FAB2(SCH_1):PAGE223_I70@MSTR_DISCRETE.RES(CHIPS)':
 'B': CDS_PINID='B';
NET_NAME
'SVID_CLK_PVCCIO_CPU0'
 '@BASEBOARD_FAB2_LIB.BASEBOARD_FAB2(SCH_1):SVID_CLK_PVCCIO_CPU0':
 C_SIGNAL='@baseboard_fab2_lib.baseboard_fab2(sch_1):svid_clk_pvccio_cpu0';
NODE_NAME     R3P15 2
 '@BASEBOARD_FAB2_LIB.BASEBOARD_FAB2(SCH_1):PAGE211_I29@MSTR_DISCRETE.RES(CHIPS)':
 'B': CDS_PINID='B';
NODE_NAME     EU3P1 15
 '@BASEBOARD_FAB2_LIB.BASEBOARD_FAB2(SCH_1):PAGE211_I93@MSTR_CONTROLLER.PXE1110B(CHIPS)':
 'VCLK': CDS_PINID='VCLK';
NET_NAME
'SVID_CLK_PVCCIO_CPU1'
 '@BASEBOARD_FAB2_LIB.BASEBOARD_FAB2(SCH_1):SVID_CLK_PVCCIO_CPU1':
 C_SIGNAL='@baseboard_fab2_lib.baseboard_fab2(sch_1):svid_clk_pvccio_cpu1';
NODE_NAME     R4D51 2
 '@BASEBOARD_FAB2_LIB.BASEBOARD_FAB2(SCH_1):PAGE213_I46@MSTR_DISCRETE.RES(CHIPS)':
 'B': CDS_PINID='B';
NODE_NAME     EU4D5 15
 '@BASEBOARD_FAB2_LIB.BASEBOARD_FAB2(SCH_1):PAGE213_I96@MSTR_CONTROLLER.PXE1110B(CHIPS)':
 'VCLK': CDS_PINID='VCLK';
NET_NAME
'SVID_CLK_PVDDQ_ABC'
 '@BASEBOARD_FAB2_LIB.BASEBOARD_FAB2(SCH_1):SVID_CLK_PVDDQ_ABC':
 C_SIGNAL='@baseboard_fab2_lib.baseboard_fab2(sch_1):svid_clk_pvddq_abc';
NODE_NAME     R7G24 2
 '@BASEBOARD_FAB2_LIB.BASEBOARD_FAB2(SCH_1):PAGE215_I28@MSTR_DISCRETE.RES(CHIPS)':
 'B': CDS_PINID='B';
NODE_NAME     EU7G1 15
 '@BASEBOARD_FAB2_LIB.BASEBOARD_FAB2(SCH_1):PAGE215_I69@MSTR_CONTROLLER.PXM1310B(CHIPS)':
 'VCLK': CDS_PINID='VCLK';
NET_NAME
'SVID_CLK_PVDDQ_DEF'
 '@BASEBOARD_FAB2_LIB.BASEBOARD_FAB2(SCH_1):SVID_CLK_PVDDQ_DEF':
 C_SIGNAL='@baseboard_fab2_lib.baseboard_fab2(sch_1):svid_clk_pvddq_def';
NODE_NAME     R7A17 2
 '@BASEBOARD_FAB2_LIB.BASEBOARD_FAB2(SCH_1):PAGE218_I21@MSTR_DISCRETE.RES(CHIPS)':
 'B': CDS_PINID='B';
NODE_NAME     EU7A5 15
 '@BASEBOARD_FAB2_LIB.BASEBOARD_FAB2(SCH_1):PAGE218_I69@MSTR_CONTROLLER.PXM1310B(CHIPS)':
 'VCLK': CDS_PINID='VCLK';
NET_NAME
'SVID_CLK_PVDDQ_GHJ'
 '@BASEBOARD_FAB2_LIB.BASEBOARD_FAB2(SCH_1):SVID_CLK_PVDDQ_GHJ':
 C_SIGNAL='@baseboard_fab2_lib.baseboard_fab2(sch_1):svid_clk_pvddq_ghj';
NODE_NAME     R1G7 2
 '@BASEBOARD_FAB2_LIB.BASEBOARD_FAB2(SCH_1):PAGE223_I18@MSTR_DISCRETE.RES(CHIPS)':
 'B': CDS_PINID='B';
NODE_NAME     EU1G2 15
 '@BASEBOARD_FAB2_LIB.BASEBOARD_FAB2(SCH_1):PAGE223_I69@MSTR_CONTROLLER.PXM1310B(CHIPS)':
 'VCLK': CDS_PINID='VCLK';
NET_NAME
'SVID_CLK_PVDDQ_KLM'
 '@BASEBOARD_FAB2_LIB.BASEBOARD_FAB2(SCH_1):SVID_CLK_PVDDQ_KLM':
 C_SIGNAL='@baseboard_fab2_lib.baseboard_fab2(sch_1):svid_clk_pvddq_klm';
NODE_NAME     R1B8 2
 '@BASEBOARD_FAB2_LIB.BASEBOARD_FAB2(SCH_1):PAGE226_I19@MSTR_DISCRETE.RES(CHIPS)':
 'B': CDS_PINID='B';
NODE_NAME     EU1B1 15
 '@BASEBOARD_FAB2_LIB.BASEBOARD_FAB2(SCH_1):PAGE226_I69@MSTR_CONTROLLER.PXM1310B(CHIPS)':
 'VCLK': CDS_PINID='VCLK';
NET_NAME
'SVID_DIO0_CPU0'
 '@BASEBOARD_FAB2_LIB.BASEBOARD_FAB2(SCH_1):SVID_DIO0_CPU0':
 C_SIGNAL='@baseboard_fab2_lib.baseboard_fab2(sch_1):svid_dio0_cpu0';
NODE_NAME     R6N11 1
 '@BASEBOARD_FAB2_LIB.BASEBOARD_FAB2(SCH_1):PAGE21_I151@MSTR_DISCRETE.RES(CHIPS)':
 'A': CDS_PINID='A';
NODE_NAME     U5D1 DB45
 '@BASEBOARD_FAB2_LIB.BASEBOARD_FAB2(SCH_1):PAGE21_I259@CHPSET_LIB.SKX_EXT_B(CHIPS)':
 'SVIDDATA'<0>: CDS_PINID='SVIDDATA(0)';
NET_NAME
'SVID_DIO0_CPU0_R'
 '@BASEBOARD_FAB2_LIB.BASEBOARD_FAB2(SCH_1):SVID_DIO0_CPU0_R':
 C_SIGNAL='@baseboard_fab2_lib.baseboard_fab2(sch_1):svid_dio0_cpu0_r';
NODE_NAME     R6N11 2
 '@BASEBOARD_FAB2_LIB.BASEBOARD_FAB2(SCH_1):PAGE21_I151@MSTR_DISCRETE.RES(CHIPS)':
 'B': CDS_PINID='B';
NODE_NAME     R6N2 1
 '@BASEBOARD_FAB2_LIB.BASEBOARD_FAB2(SCH_1):PAGE21_I163@MSTR_DISCRETE.RES(CHIPS)':
 'A': CDS_PINID='A';
NODE_NAME     J6B1 B20
 '@BASEBOARD_FAB2_LIB.BASEBOARD_FAB2(SCH_1):PAGE194_I56@MSTR_SCONN.SCONN120_H61426002(CHIPS)':
 'IOB20': CDS_PINID='IOB20';
NODE_NAME     R4D66 2
 '@BASEBOARD_FAB2_LIB.BASEBOARD_FAB2(SCH_1):PAGE201_I98@MSTR_DISCRETE.RES(CHIPS)':
 'B': CDS_PINID='B';
NODE_NAME     R3P11 1
 '@BASEBOARD_FAB2_LIB.BASEBOARD_FAB2(SCH_1):PAGE211_I16@MSTR_DISCRETE.RES(CHIPS)':
 'A': CDS_PINID='A';
NODE_NAME     R4E10 2
 '@BASEBOARD_FAB2_LIB.BASEBOARD_FAB2(SCH_1):PAGE201_I190@MSTR_DISCRETE.RES(CHIPS)':
 'B': CDS_PINID='B';
NODE_NAME     R3P13 2
 '@BASEBOARD_FAB2_LIB.BASEBOARD_FAB2(SCH_1):PAGE211_I100@MSTR_DISCRETE.RES(CHIPS)':
 'B': CDS_PINID='B';
NET_NAME
'SVID_DIO0_CPU1'
 '@BASEBOARD_FAB2_LIB.BASEBOARD_FAB2(SCH_1):SVID_DIO0_CPU1':
 C_SIGNAL='@baseboard_fab2_lib.baseboard_fab2(sch_1):svid_dio0_cpu1';
NODE_NAME     R3B3 1
 '@BASEBOARD_FAB2_LIB.BASEBOARD_FAB2(SCH_1):PAGE55_I29@MSTR_DISCRETE.RES(CHIPS)':
 'A': CDS_PINID='A';
NODE_NAME     U2D1 DB45
 '@BASEBOARD_FAB2_LIB.BASEBOARD_FAB2(SCH_1):PAGE55_I172@CHPSET_LIB.SKX_EXT_B(CHIPS)':
 'SVIDDATA'<0>: CDS_PINID='SVIDDATA(0)';
NET_NAME
'SVID_DIO0_CPU1_R'
 '@BASEBOARD_FAB2_LIB.BASEBOARD_FAB2(SCH_1):SVID_DIO0_CPU1_R':
 C_SIGNAL='@baseboard_fab2_lib.baseboard_fab2(sch_1):svid_dio0_cpu1_r';
NODE_NAME     R3B4 1
 '@BASEBOARD_FAB2_LIB.BASEBOARD_FAB2(SCH_1):PAGE55_I21@MSTR_DISCRETE.RES(CHIPS)':
 'A': CDS_PINID='A';
NODE_NAME     R3B3 2
 '@BASEBOARD_FAB2_LIB.BASEBOARD_FAB2(SCH_1):PAGE55_I29@MSTR_DISCRETE.RES(CHIPS)':
 'B': CDS_PINID='B';
NODE_NAME     J4B2 B20
 '@BASEBOARD_FAB2_LIB.BASEBOARD_FAB2(SCH_1):PAGE193_I46@MSTR_SCONN.SCONN120_H61426002(CHIPS)':
 'IOB20': CDS_PINID='IOB20';
NODE_NAME     R9P1 2
 '@BASEBOARD_FAB2_LIB.BASEBOARD_FAB2(SCH_1):PAGE206_I4@MSTR_DISCRETE.RES(CHIPS)':
 'B': CDS_PINID='B';
NODE_NAME     R1D2 2
 '@BASEBOARD_FAB2_LIB.BASEBOARD_FAB2(SCH_1):PAGE206_I38@MSTR_DISCRETE.RES(CHIPS)':
 'B': CDS_PINID='B';
NODE_NAME     R6P35 2
 '@BASEBOARD_FAB2_LIB.BASEBOARD_FAB2(SCH_1):PAGE213_I27@MSTR_DISCRETE.RES(CHIPS)':
 'B': CDS_PINID='B';
NODE_NAME     R4D54 1
 '@BASEBOARD_FAB2_LIB.BASEBOARD_FAB2(SCH_1):PAGE213_I37@MSTR_DISCRETE.RES(CHIPS)':
 'A': CDS_PINID='A';
NET_NAME
'SVID_DIO1_CPU0'
 '@BASEBOARD_FAB2_LIB.BASEBOARD_FAB2(SCH_1):SVID_DIO1_CPU0':
 C_SIGNAL='@baseboard_fab2_lib.baseboard_fab2(sch_1):svid_dio1_cpu0';
NODE_NAME     R6B4 1
 '@BASEBOARD_FAB2_LIB.BASEBOARD_FAB2(SCH_1):PAGE21_I154@MSTR_DISCRETE.RES(CHIPS)':
 'A': CDS_PINID='A';
NODE_NAME     U5D1 DJ44
 '@BASEBOARD_FAB2_LIB.BASEBOARD_FAB2(SCH_1):PAGE21_I259@CHPSET_LIB.SKX_EXT_B(CHIPS)':
 'SVIDDATA'<1>: CDS_PINID='SVIDDATA(1)';
NET_NAME
'SVID_DIO1_CPU0_R'
 '@BASEBOARD_FAB2_LIB.BASEBOARD_FAB2(SCH_1):SVID_DIO1_CPU0_R':
 C_SIGNAL='@baseboard_fab2_lib.baseboard_fab2(sch_1):svid_dio1_cpu0_r';
NODE_NAME     R6B4 2
 '@BASEBOARD_FAB2_LIB.BASEBOARD_FAB2(SCH_1):PAGE21_I154@MSTR_DISCRETE.RES(CHIPS)':
 'B': CDS_PINID='B';
NODE_NAME     R6B2 2
 '@BASEBOARD_FAB2_LIB.BASEBOARD_FAB2(SCH_1):PAGE21_I159@MSTR_DISCRETE.RES(CHIPS)':
 'B': CDS_PINID='B';
NODE_NAME     J6B1 F20
 '@BASEBOARD_FAB2_LIB.BASEBOARD_FAB2(SCH_1):PAGE194_I56@MSTR_SCONN.SCONN120_H61426002(CHIPS)':
 'IOF20': CDS_PINID='IOF20';
NODE_NAME     R7G2 2
 '@BASEBOARD_FAB2_LIB.BASEBOARD_FAB2(SCH_1):PAGE215_I41@MSTR_DISCRETE.RES(CHIPS)':
 'B': CDS_PINID='B';
NODE_NAME     R3U2 2
 '@BASEBOARD_FAB2_LIB.BASEBOARD_FAB2(SCH_1):PAGE215_I58@MSTR_DISCRETE.RES(CHIPS)':
 'B': CDS_PINID='B';
NODE_NAME     R7A12 2
 '@BASEBOARD_FAB2_LIB.BASEBOARD_FAB2(SCH_1):PAGE218_I45@MSTR_DISCRETE.RES(CHIPS)':
 'B': CDS_PINID='B';
NODE_NAME     R3L11 2
 '@BASEBOARD_FAB2_LIB.BASEBOARD_FAB2(SCH_1):PAGE218_I67@MSTR_DISCRETE.RES(CHIPS)':
 'B': CDS_PINID='B';
NET_NAME
'SVID_DIO1_CPU1'
 '@BASEBOARD_FAB2_LIB.BASEBOARD_FAB2(SCH_1):SVID_DIO1_CPU1':
 C_SIGNAL='@baseboard_fab2_lib.baseboard_fab2(sch_1):svid_dio1_cpu1';
NODE_NAME     R1C2 1
 '@BASEBOARD_FAB2_LIB.BASEBOARD_FAB2(SCH_1):PAGE55_I24@MSTR_DISCRETE.RES(CHIPS)':
 'A': CDS_PINID='A';
NODE_NAME     U2D1 DJ44
 '@BASEBOARD_FAB2_LIB.BASEBOARD_FAB2(SCH_1):PAGE55_I172@CHPSET_LIB.SKX_EXT_B(CHIPS)':
 'SVIDDATA'<1>: CDS_PINID='SVIDDATA(1)';
NET_NAME
'SVID_DIO1_CPU1_R'
 '@BASEBOARD_FAB2_LIB.BASEBOARD_FAB2(SCH_1):SVID_DIO1_CPU1_R':
 C_SIGNAL='@baseboard_fab2_lib.baseboard_fab2(sch_1):svid_dio1_cpu1_r';
NODE_NAME     R9N2 2
 '@BASEBOARD_FAB2_LIB.BASEBOARD_FAB2(SCH_1):PAGE55_I7@MSTR_DISCRETE.RES(CHIPS)':
 'B': CDS_PINID='B';
NODE_NAME     R1C2 2
 '@BASEBOARD_FAB2_LIB.BASEBOARD_FAB2(SCH_1):PAGE55_I24@MSTR_DISCRETE.RES(CHIPS)':
 'B': CDS_PINID='B';
NODE_NAME     J4B2 F20
 '@BASEBOARD_FAB2_LIB.BASEBOARD_FAB2(SCH_1):PAGE193_I46@MSTR_SCONN.SCONN120_H61426002(CHIPS)':
 'IOF20': CDS_PINID='IOF20';
NODE_NAME     R9U3 2
 '@BASEBOARD_FAB2_LIB.BASEBOARD_FAB2(SCH_1):PAGE223_I57@MSTR_DISCRETE.RES(CHIPS)':
 'B': CDS_PINID='B';
NODE_NAME     R1G10 2
 '@BASEBOARD_FAB2_LIB.BASEBOARD_FAB2(SCH_1):PAGE223_I41@MSTR_DISCRETE.RES(CHIPS)':
 'B': CDS_PINID='B';
NODE_NAME     R9M7 2
 '@BASEBOARD_FAB2_LIB.BASEBOARD_FAB2(SCH_1):PAGE226_I57@MSTR_DISCRETE.RES(CHIPS)':
 'B': CDS_PINID='B';
NODE_NAME     R1B10 2
 '@BASEBOARD_FAB2_LIB.BASEBOARD_FAB2(SCH_1):PAGE226_I41@MSTR_DISCRETE.RES(CHIPS)':
 'B': CDS_PINID='B';
NET_NAME
'SVID_VALERT_VCCIN_CPU0'
 '@BASEBOARD_FAB2_LIB.BASEBOARD_FAB2(SCH_1):SVID_VALERT_VCCIN_CPU0':
 C_SIGNAL='@baseboard_fab2_lib.baseboard_fab2(sch_1):svid_valert_vccin_cpu0';
NODE_NAME     R4D67 1
 '@BASEBOARD_FAB2_LIB.BASEBOARD_FAB2(SCH_1):PAGE201_I26@MSTR_DISCRETE.RES(CHIPS)':
 'A': CDS_PINID='A';
NODE_NAME     EU4D4 19
 '@BASEBOARD_FAB2_LIB.BASEBOARD_FAB2(SCH_1):PAGE201_I155@MSTR_CONTROLLER.PXE1610B(CHIPS)':
 'VALRT_N': CDS_PINID='VALRT_N';
NET_NAME
'SVID_VALERT_VCCIN_CPU1'
 '@BASEBOARD_FAB2_LIB.BASEBOARD_FAB2(SCH_1):SVID_VALERT_VCCIN_CPU1':
 C_SIGNAL='@baseboard_fab2_lib.baseboard_fab2(sch_1):svid_valert_vccin_cpu1';
NODE_NAME     R1D3 1
 '@BASEBOARD_FAB2_LIB.BASEBOARD_FAB2(SCH_1):PAGE206_I37@MSTR_DISCRETE.RES(CHIPS)':
 'A': CDS_PINID='A';
NODE_NAME     EU1C2 19
 '@BASEBOARD_FAB2_LIB.BASEBOARD_FAB2(SCH_1):PAGE206_I130@MSTR_CONTROLLER.PXE1610B(CHIPS)':
 'VALRT_N': CDS_PINID='VALRT_N';
NET_NAME
'SVID_VCLK_PVCCIN_CPU0'
 '@BASEBOARD_FAB2_LIB.BASEBOARD_FAB2(SCH_1):SVID_VCLK_PVCCIN_CPU0':
 C_SIGNAL='@baseboard_fab2_lib.baseboard_fab2(sch_1):svid_vclk_pvccin_cpu0';
NODE_NAME     R4E6 2
 '@BASEBOARD_FAB2_LIB.BASEBOARD_FAB2(SCH_1):PAGE201_I56@MSTR_DISCRETE.RES(CHIPS)':
 'B': CDS_PINID='B';
NODE_NAME     EU4D4 17
 '@BASEBOARD_FAB2_LIB.BASEBOARD_FAB2(SCH_1):PAGE201_I155@MSTR_CONTROLLER.PXE1610B(CHIPS)':
 'VCLK': CDS_PINID='VCLK';
NET_NAME
'SVID_VCLK_PVCCIN_CPU1'
 '@BASEBOARD_FAB2_LIB.BASEBOARD_FAB2(SCH_1):SVID_VCLK_PVCCIN_CPU1':
 C_SIGNAL='@baseboard_fab2_lib.baseboard_fab2(sch_1):svid_vclk_pvccin_cpu1';
NODE_NAME     R1D9 2
 '@BASEBOARD_FAB2_LIB.BASEBOARD_FAB2(SCH_1):PAGE206_I54@MSTR_DISCRETE.RES(CHIPS)':
 'B': CDS_PINID='B';
NODE_NAME     EU1C2 17
 '@BASEBOARD_FAB2_LIB.BASEBOARD_FAB2(SCH_1):PAGE206_I130@MSTR_CONTROLLER.PXE1610B(CHIPS)':
 'VCLK': CDS_PINID='VCLK';
NET_NAME
'SVID_VDIO_PVCCIN_CPU0'
 '@BASEBOARD_FAB2_LIB.BASEBOARD_FAB2(SCH_1):SVID_VDIO_PVCCIN_CPU0':
 C_SIGNAL='@baseboard_fab2_lib.baseboard_fab2(sch_1):svid_vdio_pvccin_cpu0';
NODE_NAME     R4D66 1
 '@BASEBOARD_FAB2_LIB.BASEBOARD_FAB2(SCH_1):PAGE201_I98@MSTR_DISCRETE.RES(CHIPS)':
 'A': CDS_PINID='A';
NODE_NAME     EU4D4 18
 '@BASEBOARD_FAB2_LIB.BASEBOARD_FAB2(SCH_1):PAGE201_I155@MSTR_CONTROLLER.PXE1610B(CHIPS)':
 'VDIO': CDS_PINID='VDIO';
NET_NAME
'SVID_VDIO_PVCCIN_CPU1'
 '@BASEBOARD_FAB2_LIB.BASEBOARD_FAB2(SCH_1):SVID_VDIO_PVCCIN_CPU1':
 C_SIGNAL='@baseboard_fab2_lib.baseboard_fab2(sch_1):svid_vdio_pvccin_cpu1';
NODE_NAME     R1D2 1
 '@BASEBOARD_FAB2_LIB.BASEBOARD_FAB2(SCH_1):PAGE206_I38@MSTR_DISCRETE.RES(CHIPS)':
 'A': CDS_PINID='A';
NODE_NAME     EU1C2 18
 '@BASEBOARD_FAB2_LIB.BASEBOARD_FAB2(SCH_1):PAGE206_I130@MSTR_CONTROLLER.PXE1610B(CHIPS)':
 'VDIO': CDS_PINID='VDIO';
NET_NAME
'SVID_VDIO_PVCCIO_CPU0'
 '@BASEBOARD_FAB2_LIB.BASEBOARD_FAB2(SCH_1):SVID_VDIO_PVCCIO_CPU0':
 C_SIGNAL='@baseboard_fab2_lib.baseboard_fab2(sch_1):svid_vdio_pvccio_cpu0';
NODE_NAME     R3P11 2
 '@BASEBOARD_FAB2_LIB.BASEBOARD_FAB2(SCH_1):PAGE211_I16@MSTR_DISCRETE.RES(CHIPS)':
 'B': CDS_PINID='B';
NODE_NAME     EU3P1 16
 '@BASEBOARD_FAB2_LIB.BASEBOARD_FAB2(SCH_1):PAGE211_I93@MSTR_CONTROLLER.PXE1110B(CHIPS)':
 'VDIO': CDS_PINID='VDIO';
NET_NAME
'SVID_VDIO_PVCCIO_CPU1'
 '@BASEBOARD_FAB2_LIB.BASEBOARD_FAB2(SCH_1):SVID_VDIO_PVCCIO_CPU1':
 C_SIGNAL='@baseboard_fab2_lib.baseboard_fab2(sch_1):svid_vdio_pvccio_cpu1';
NODE_NAME     R4D54 2
 '@BASEBOARD_FAB2_LIB.BASEBOARD_FAB2(SCH_1):PAGE213_I37@MSTR_DISCRETE.RES(CHIPS)':
 'B': CDS_PINID='B';
NODE_NAME     EU4D5 16
 '@BASEBOARD_FAB2_LIB.BASEBOARD_FAB2(SCH_1):PAGE213_I96@MSTR_CONTROLLER.PXE1110B(CHIPS)':
 'VDIO': CDS_PINID='VDIO';
NET_NAME
'SVID_VDIO_PVDDQ_ABC'
 '@BASEBOARD_FAB2_LIB.BASEBOARD_FAB2(SCH_1):SVID_VDIO_PVDDQ_ABC':
 C_SIGNAL='@baseboard_fab2_lib.baseboard_fab2(sch_1):svid_vdio_pvddq_abc';
NODE_NAME     R7G2 1
 '@BASEBOARD_FAB2_LIB.BASEBOARD_FAB2(SCH_1):PAGE215_I41@MSTR_DISCRETE.RES(CHIPS)':
 'A': CDS_PINID='A';
NODE_NAME     EU7G1 16
 '@BASEBOARD_FAB2_LIB.BASEBOARD_FAB2(SCH_1):PAGE215_I69@MSTR_CONTROLLER.PXM1310B(CHIPS)':
 'VDIO': CDS_PINID='VDIO';
NET_NAME
'SVID_VDIO_PVDDQ_DEF'
 '@BASEBOARD_FAB2_LIB.BASEBOARD_FAB2(SCH_1):SVID_VDIO_PVDDQ_DEF':
 C_SIGNAL='@baseboard_fab2_lib.baseboard_fab2(sch_1):svid_vdio_pvddq_def';
NODE_NAME     R7A12 1
 '@BASEBOARD_FAB2_LIB.BASEBOARD_FAB2(SCH_1):PAGE218_I45@MSTR_DISCRETE.RES(CHIPS)':
 'A': CDS_PINID='A';
NODE_NAME     EU7A5 16
 '@BASEBOARD_FAB2_LIB.BASEBOARD_FAB2(SCH_1):PAGE218_I69@MSTR_CONTROLLER.PXM1310B(CHIPS)':
 'VDIO': CDS_PINID='VDIO';
NET_NAME
'SVID_VDIO_PVDDQ_GHJ'
 '@BASEBOARD_FAB2_LIB.BASEBOARD_FAB2(SCH_1):SVID_VDIO_PVDDQ_GHJ':
 C_SIGNAL='@baseboard_fab2_lib.baseboard_fab2(sch_1):svid_vdio_pvddq_ghj';
NODE_NAME     EU1G2 16
 '@BASEBOARD_FAB2_LIB.BASEBOARD_FAB2(SCH_1):PAGE223_I69@MSTR_CONTROLLER.PXM1310B(CHIPS)':
 'VDIO': CDS_PINID='VDIO';
NODE_NAME     R1G10 1
 '@BASEBOARD_FAB2_LIB.BASEBOARD_FAB2(SCH_1):PAGE223_I41@MSTR_DISCRETE.RES(CHIPS)':
 'A': CDS_PINID='A';
NET_NAME
'SVID_VDIO_PVDDQ_KLM'
 '@BASEBOARD_FAB2_LIB.BASEBOARD_FAB2(SCH_1):SVID_VDIO_PVDDQ_KLM':
 C_SIGNAL='@baseboard_fab2_lib.baseboard_fab2(sch_1):svid_vdio_pvddq_klm';
NODE_NAME     EU1B1 16
 '@BASEBOARD_FAB2_LIB.BASEBOARD_FAB2(SCH_1):PAGE226_I69@MSTR_CONTROLLER.PXM1310B(CHIPS)':
 'VDIO': CDS_PINID='VDIO';
NODE_NAME     R1B10 1
 '@BASEBOARD_FAB2_LIB.BASEBOARD_FAB2(SCH_1):PAGE226_I41@MSTR_DISCRETE.RES(CHIPS)':
 'A': CDS_PINID='A';
NET_NAME
'TEMP_SENSOR_B'
 '@BASEBOARD_FAB2_LIB.BASEBOARD_FAB2(SCH_1):TEMP_SENSOR_B':
 C_SIGNAL='@baseboard_fab2_lib.baseboard_fab2(sch_1):temp_sensor_b';
NODE_NAME     Q1D3 1
 '@BASEBOARD_FAB2_LIB.BASEBOARD_FAB2(SCH_1):PAGE199_I58@MSTR_DISCRETE.NPN(CHIPS)':
 'B': CDS_PINID='B';
NODE_NAME     Q1D3 3
 '@BASEBOARD_FAB2_LIB.BASEBOARD_FAB2(SCH_1):PAGE199_I58@MSTR_DISCRETE.NPN(CHIPS)':
 'C': CDS_PINID='C';
NODE_NAME     R1W20 2
 '@BASEBOARD_FAB2_LIB.BASEBOARD_FAB2(SCH_1):PAGE199_I134@MSTR_DISCRETE.RES(CHIPS)':
 'B': CDS_PINID='B';
NET_NAME
'TEMP_SENSOR_E'
 '@BASEBOARD_FAB2_LIB.BASEBOARD_FAB2(SCH_1):TEMP_SENSOR_E':
 C_SIGNAL='@baseboard_fab2_lib.baseboard_fab2(sch_1):temp_sensor_e';
NODE_NAME     Q1D3 2
 '@BASEBOARD_FAB2_LIB.BASEBOARD_FAB2(SCH_1):PAGE199_I58@MSTR_DISCRETE.NPN(CHIPS)':
 'E': CDS_PINID='E';
NODE_NAME     R1W21 2
 '@BASEBOARD_FAB2_LIB.BASEBOARD_FAB2(SCH_1):PAGE199_I135@MSTR_DISCRETE.RES(CHIPS)':
 'B': CDS_PINID='B';
NET_NAME
'TPM_SPI_BMC_WP_N'
 '@BASEBOARD_FAB2_LIB.BASEBOARD_FAB2(SCH_1):TPM_SPI_BMC_WP_N':
 C_SIGNAL='@baseboard_fab2_lib.baseboard_fab2(sch_1):tpm_spi_bmc_wp_n';
NODE_NAME     UN8F2 9
 '@BASEBOARD_FAB2_LIB.BASEBOARD_FAB2(SCH_1):PAGE246_I17@MSTR_MEMORY.W25Q256(CHIPS)':
 'WP_N_IO'<2>: CDS_PINID='WP_N_IO(2)';
NODE_NAME     RN8F6 1
 '@BASEBOARD_FAB2_LIB.BASEBOARD_FAB2(SCH_1):PAGE246_I19@W_HDL.82KR2F-1-GP(CHIPS)':
 '1': CDS_PINID='\1\';
NODE_NAME     RN8F2 2
 '@BASEBOARD_FAB2_LIB.BASEBOARD_FAB2(SCH_1):PAGE246_I20@MSTR_DISCRETE.RES(CHIPS)':
 'B': CDS_PINID='B';
NODE_NAME     R25W154 2
 '@BASEBOARD_FAB2_LIB.BASEBOARD_FAB2(SCH_1):PAGE137_I133@MSTR_DISCRETE.RES(CHIPS)':
 'B': CDS_PINID='B';
NET_NAME
'TP_10GBE_KR0_MON_DN'
 '@BASEBOARD_FAB2_LIB.BASEBOARD_FAB2(SCH_1):TP_10GBE_KR0_MON_DN':
 C_SIGNAL='@baseboard_fab2_lib.baseboard_fab2(sch_1):tp_10gbe_kr0_mon_dn';
NODE_NAME     U7C1 BL26
 '@BASEBOARD_FAB2_LIB.BASEBOARD_FAB2(SCH_1):PAGE118_I73@MSTR_U_PROC.LBG_CORE_QAT_EXT_D(CHIPS)':
 'RSVD'<39>: CDS_PINID='RSVD(39)';
NET_NAME
'TP_10GBE_KR0_MON_DP'
 '@BASEBOARD_FAB2_LIB.BASEBOARD_FAB2(SCH_1):TP_10GBE_KR0_MON_DP':
 C_SIGNAL='@baseboard_fab2_lib.baseboard_fab2(sch_1):tp_10gbe_kr0_mon_dp';
NODE_NAME     U7C1 BN26
 '@BASEBOARD_FAB2_LIB.BASEBOARD_FAB2(SCH_1):PAGE118_I73@MSTR_U_PROC.LBG_CORE_QAT_EXT_D(CHIPS)':
 'RSVD'<40>: CDS_PINID='RSVD(40)';
NET_NAME
'TP_10GBE_KR1_MON_DN'
 '@BASEBOARD_FAB2_LIB.BASEBOARD_FAB2(SCH_1):TP_10GBE_KR1_MON_DN':
 C_SIGNAL='@baseboard_fab2_lib.baseboard_fab2(sch_1):tp_10gbe_kr1_mon_dn';
NODE_NAME     U7C1 BL33
 '@BASEBOARD_FAB2_LIB.BASEBOARD_FAB2(SCH_1):PAGE118_I73@MSTR_U_PROC.LBG_CORE_QAT_EXT_D(CHIPS)':
 'RSVD'<43>: CDS_PINID='RSVD(43)';
NET_NAME
'TP_10GBE_KR1_MON_DP'
 '@BASEBOARD_FAB2_LIB.BASEBOARD_FAB2(SCH_1):TP_10GBE_KR1_MON_DP':
 C_SIGNAL='@baseboard_fab2_lib.baseboard_fab2(sch_1):tp_10gbe_kr1_mon_dp';
NODE_NAME     U7C1 BN33
 '@BASEBOARD_FAB2_LIB.BASEBOARD_FAB2(SCH_1):PAGE118_I73@MSTR_U_PROC.LBG_CORE_QAT_EXT_D(CHIPS)':
 'RSVD'<44>: CDS_PINID='RSVD(44)';
NET_NAME
'TP_BIOS_RECOVER_BOOT'
 '@BASEBOARD_FAB2_LIB.BASEBOARD_FAB2(SCH_1):TP_BIOS_RECOVER_BOOT':
 C_SIGNAL='@baseboard_fab2_lib.baseboard_fab2(sch_1):tp_bios_recover_boot';
NODE_NAME     J7G3 8
 '@BASEBOARD_FAB2_LIB.BASEBOARD_FAB2(SCH_1):PAGE136_I174@MSTR_CONN.CONN12_C73564003(CHIPS)':
 'IO8': CDS_PINID='IO8';
NET_NAME
'TP_BIOS_USB_RECOVERY'
 '@BASEBOARD_FAB2_LIB.BASEBOARD_FAB2(SCH_1):TP_BIOS_USB_RECOVERY':
 C_SIGNAL='@baseboard_fab2_lib.baseboard_fab2(sch_1):tp_bios_usb_recovery';
NODE_NAME     J7G3 2
 '@BASEBOARD_FAB2_LIB.BASEBOARD_FAB2(SCH_1):PAGE136_I174@MSTR_CONN.CONN12_C73564003(CHIPS)':
 'IO2': CDS_PINID='IO2';
NET_NAME
'TP_BMC_GPIOA2'
 '@BASEBOARD_FAB2_LIB.BASEBOARD_FAB2(SCH_1):TP_BMC_GPIOA2':
 C_SIGNAL='@baseboard_fab2_lib.baseboard_fab2(sch_1):tp_bmc_gpioa2';
NODE_NAME     U25W4 D13
 '@BASEBOARD_FAB2_LIB.BASEBOARD_FAB2(SCH_1):PAGE145_I117@W_HDL.AST2520A1-GP-GP(CHIPS)':
 'GPIOA2_TIMER3_SPI1CS1#': CDS_PINID='\gpioa2_timer3_spi1cs1#\';
NET_NAME
'TP_BMC_M_A15'
 '@BASEBOARD_FAB2_LIB.BASEBOARD_FAB2(SCH_1):TP_BMC_M_A15':
 C_SIGNAL='@baseboard_fab2_lib.baseboard_fab2(sch_1):tp_bmc_m_a15';
NODE_NAME     U25W4 U15
 '@BASEBOARD_FAB2_LIB.BASEBOARD_FAB2(SCH_1):PAGE143_I63@W_HDL.AST2520A1-GP-GP(CHIPS)':
 'MA15': CDS_PINID='MA15';
NET_NAME
'TP_CD_HFI1_CPU1_I2CDAT'
 '@BASEBOARD_FAB2_LIB.BASEBOARD_FAB2(SCH_1):TP_CD_HFI1_CPU1_I2CDAT':
 C_SIGNAL='@baseboard_fab2_lib.baseboard_fab2(sch_1):tp_cd_hfi1_cpu1_i2cdat';
NODE_NAME     U2D1 BH23
 '@BASEBOARD_FAB2_LIB.BASEBOARD_FAB2(SCH_1):PAGE63_I23@CHPSET_LIB.SKX_EXT_B(CHIPS)':
 'CD_HFI1_I2CDAT': CDS_PINID='CD_HFI1_I2CDAT';
NET_NAME
'TP_CD_HFI1_CPU1_I2CLK'
 '@BASEBOARD_FAB2_LIB.BASEBOARD_FAB2(SCH_1):TP_CD_HFI1_CPU1_I2CLK':
 C_SIGNAL='@baseboard_fab2_lib.baseboard_fab2(sch_1):tp_cd_hfi1_cpu1_i2clk';
NODE_NAME     U2D1 BJ22
 '@BASEBOARD_FAB2_LIB.BASEBOARD_FAB2(SCH_1):PAGE63_I23@CHPSET_LIB.SKX_EXT_B(CHIPS)':
 'CD_HFI1_I2CCLK': CDS_PINID='CD_HFI1_I2CCLK';
NET_NAME
'TP_CD_HFI1_CPU1_INT_N'
 '@BASEBOARD_FAB2_LIB.BASEBOARD_FAB2(SCH_1):TP_CD_HFI1_CPU1_INT_N':
 C_SIGNAL='@baseboard_fab2_lib.baseboard_fab2(sch_1):tp_cd_hfi1_cpu1_int_n';
NODE_NAME     U2D1 BM21
 '@BASEBOARD_FAB2_LIB.BASEBOARD_FAB2(SCH_1):PAGE63_I23@CHPSET_LIB.SKX_EXT_B(CHIPS)':
 'CD_HFI1_INT_N': CDS_PINID='CD_HFI1_INT_N';
NET_NAME
'TP_CD_HFI1_CPU1_LED_N'
 '@BASEBOARD_FAB2_LIB.BASEBOARD_FAB2(SCH_1):TP_CD_HFI1_CPU1_LED_N':
 C_SIGNAL='@baseboard_fab2_lib.baseboard_fab2(sch_1):tp_cd_hfi1_cpu1_led_n';
NODE_NAME     U2D1 BM23
 '@BASEBOARD_FAB2_LIB.BASEBOARD_FAB2(SCH_1):PAGE63_I23@CHPSET_LIB.SKX_EXT_B(CHIPS)':
 'CD_HFI1_LED_N': CDS_PINID='CD_HFI1_LED_N';
NET_NAME
'TP_CD_HFI1_CPU1_MODPRST_N'
 '@BASEBOARD_FAB2_LIB.BASEBOARD_FAB2(SCH_1):TP_CD_HFI1_CPU1_MODPRST_N':
 C_SIGNAL='@baseboard_fab2_lib.baseboard_fab2(sch_1):tp_cd_hfi1_cpu1_modprst_n';
NODE_NAME     U2D1 BT19
 '@BASEBOARD_FAB2_LIB.BASEBOARD_FAB2(SCH_1):PAGE63_I23@CHPSET_LIB.SKX_EXT_B(CHIPS)':
 'CD_HFI1_MODPRST_N': CDS_PINID='CD_HFI1_MODPRST_N';
NET_NAME
'TP_CD_HFI1_CPU1_RESET_N'
 '@BASEBOARD_FAB2_LIB.BASEBOARD_FAB2(SCH_1):TP_CD_HFI1_CPU1_RESET_N':
 C_SIGNAL='@baseboard_fab2_lib.baseboard_fab2(sch_1):tp_cd_hfi1_cpu1_reset_n';
NODE_NAME     U2D1 BK23
 '@BASEBOARD_FAB2_LIB.BASEBOARD_FAB2(SCH_1):PAGE63_I23@CHPSET_LIB.SKX_EXT_B(CHIPS)':
 'CD_HFI1_RESET_N': CDS_PINID='CD_HFI1_RESET_N';
NET_NAME
'TP_CH_A_DIMM_A0_RFU_0'
 '@BASEBOARD_FAB2_LIB.BASEBOARD_FAB2(SCH_1):TP_CH_A_DIMM_A0_RFU_0':
 C_SIGNAL='@baseboard_fab2_lib.baseboard_fab2(sch_1):tp_ch_a_dimm_a0_rfu_0';
NODE_NAME     J4G1 205
 '@BASEBOARD_FAB2_LIB.BASEBOARD_FAB2(SCH_1):PAGE43_I1@MSTR_SCONN.SCONN288_H44441004(CHIPS)':
 'RFU'<0>: CDS_PINID='RFU(0)';
NET_NAME
'TP_CH_A_DIMM_A0_RFU_1'
 '@BASEBOARD_FAB2_LIB.BASEBOARD_FAB2(SCH_1):TP_CH_A_DIMM_A0_RFU_1':
 C_SIGNAL='@baseboard_fab2_lib.baseboard_fab2(sch_1):tp_ch_a_dimm_a0_rfu_1';
NODE_NAME     J4G1 227
 '@BASEBOARD_FAB2_LIB.BASEBOARD_FAB2(SCH_1):PAGE43_I1@MSTR_SCONN.SCONN288_H44441004(CHIPS)':
 'RFU'<1>: CDS_PINID='RFU(1)';
NET_NAME
'TP_CH_A_DIMM_A0_RFU_2'
 '@BASEBOARD_FAB2_LIB.BASEBOARD_FAB2(SCH_1):TP_CH_A_DIMM_A0_RFU_2':
 C_SIGNAL='@baseboard_fab2_lib.baseboard_fab2(sch_1):tp_ch_a_dimm_a0_rfu_2';
NODE_NAME     J4G1 144
 '@BASEBOARD_FAB2_LIB.BASEBOARD_FAB2(SCH_1):PAGE43_I1@MSTR_SCONN.SCONN288_H44441004(CHIPS)':
 'RFU'<2>: CDS_PINID='RFU(2)';
NET_NAME
'TP_CH_A_DIMM_A1_RFU_0'
 '@BASEBOARD_FAB2_LIB.BASEBOARD_FAB2(SCH_1):TP_CH_A_DIMM_A1_RFU_0':
 C_SIGNAL='@baseboard_fab2_lib.baseboard_fab2(sch_1):tp_ch_a_dimm_a1_rfu_0';
NODE_NAME     J6T1 205
 '@BASEBOARD_FAB2_LIB.BASEBOARD_FAB2(SCH_1):PAGE44_I13@MSTR_SCONN.SCONN288_H44441003(CHIPS)':
 'RFU'<0>: CDS_PINID='RFU(0)';
NET_NAME
'TP_CH_A_DIMM_A1_RFU_1'
 '@BASEBOARD_FAB2_LIB.BASEBOARD_FAB2(SCH_1):TP_CH_A_DIMM_A1_RFU_1':
 C_SIGNAL='@baseboard_fab2_lib.baseboard_fab2(sch_1):tp_ch_a_dimm_a1_rfu_1';
NODE_NAME     J6T1 227
 '@BASEBOARD_FAB2_LIB.BASEBOARD_FAB2(SCH_1):PAGE44_I13@MSTR_SCONN.SCONN288_H44441003(CHIPS)':
 'RFU'<1>: CDS_PINID='RFU(1)';
NET_NAME
'TP_CH_A_DIMM_A1_RFU_2'
 '@BASEBOARD_FAB2_LIB.BASEBOARD_FAB2(SCH_1):TP_CH_A_DIMM_A1_RFU_2':
 C_SIGNAL='@baseboard_fab2_lib.baseboard_fab2(sch_1):tp_ch_a_dimm_a1_rfu_2';
NODE_NAME     J6T1 144
 '@BASEBOARD_FAB2_LIB.BASEBOARD_FAB2(SCH_1):PAGE44_I13@MSTR_SCONN.SCONN288_H44441003(CHIPS)':
 'RFU'<2>: CDS_PINID='RFU(2)';
NET_NAME
'TP_CH_B_DIMM_B0_RFU_0'
 '@BASEBOARD_FAB2_LIB.BASEBOARD_FAB2(SCH_1):TP_CH_B_DIMM_B0_RFU_0':
 C_SIGNAL='@baseboard_fab2_lib.baseboard_fab2(sch_1):tp_ch_b_dimm_b0_rfu_0';
NODE_NAME     J4G2 205
 '@BASEBOARD_FAB2_LIB.BASEBOARD_FAB2(SCH_1):PAGE45_I111@MSTR_SCONN.SCONN288_H44441004(CHIPS)':
 'RFU'<0>: CDS_PINID='RFU(0)';
NET_NAME
'TP_CH_B_DIMM_B0_RFU_1'
 '@BASEBOARD_FAB2_LIB.BASEBOARD_FAB2(SCH_1):TP_CH_B_DIMM_B0_RFU_1':
 C_SIGNAL='@baseboard_fab2_lib.baseboard_fab2(sch_1):tp_ch_b_dimm_b0_rfu_1';
NODE_NAME     J4G2 227
 '@BASEBOARD_FAB2_LIB.BASEBOARD_FAB2(SCH_1):PAGE45_I111@MSTR_SCONN.SCONN288_H44441004(CHIPS)':
 'RFU'<1>: CDS_PINID='RFU(1)';
NET_NAME
'TP_CH_B_DIMM_B0_RFU_2'
 '@BASEBOARD_FAB2_LIB.BASEBOARD_FAB2(SCH_1):TP_CH_B_DIMM_B0_RFU_2':
 C_SIGNAL='@baseboard_fab2_lib.baseboard_fab2(sch_1):tp_ch_b_dimm_b0_rfu_2';
NODE_NAME     J4G2 144
 '@BASEBOARD_FAB2_LIB.BASEBOARD_FAB2(SCH_1):PAGE45_I111@MSTR_SCONN.SCONN288_H44441004(CHIPS)':
 'RFU'<2>: CDS_PINID='RFU(2)';
NET_NAME
'TP_CH_B_DIMM_B1_RFU_0'
 '@BASEBOARD_FAB2_LIB.BASEBOARD_FAB2(SCH_1):TP_CH_B_DIMM_B1_RFU_0':
 C_SIGNAL='@baseboard_fab2_lib.baseboard_fab2(sch_1):tp_ch_b_dimm_b1_rfu_0';
NODE_NAME     J6U1 205
 '@BASEBOARD_FAB2_LIB.BASEBOARD_FAB2(SCH_1):PAGE46_I14@MSTR_SCONN.SCONN288_H44441003(CHIPS)':
 'RFU'<0>: CDS_PINID='RFU(0)';
NET_NAME
'TP_CH_B_DIMM_B1_RFU_1'
 '@BASEBOARD_FAB2_LIB.BASEBOARD_FAB2(SCH_1):TP_CH_B_DIMM_B1_RFU_1':
 C_SIGNAL='@baseboard_fab2_lib.baseboard_fab2(sch_1):tp_ch_b_dimm_b1_rfu_1';
NODE_NAME     J6U1 227
 '@BASEBOARD_FAB2_LIB.BASEBOARD_FAB2(SCH_1):PAGE46_I14@MSTR_SCONN.SCONN288_H44441003(CHIPS)':
 'RFU'<1>: CDS_PINID='RFU(1)';
NET_NAME
'TP_CH_B_DIMM_B1_RFU_2'
 '@BASEBOARD_FAB2_LIB.BASEBOARD_FAB2(SCH_1):TP_CH_B_DIMM_B1_RFU_2':
 C_SIGNAL='@baseboard_fab2_lib.baseboard_fab2(sch_1):tp_ch_b_dimm_b1_rfu_2';
NODE_NAME     J6U1 144
 '@BASEBOARD_FAB2_LIB.BASEBOARD_FAB2(SCH_1):PAGE46_I14@MSTR_SCONN.SCONN288_H44441003(CHIPS)':
 'RFU'<2>: CDS_PINID='RFU(2)';
NET_NAME
'TP_CH_C_DIMM_C0_RFU_0'
 '@BASEBOARD_FAB2_LIB.BASEBOARD_FAB2(SCH_1):TP_CH_C_DIMM_C0_RFU_0':
 C_SIGNAL='@baseboard_fab2_lib.baseboard_fab2(sch_1):tp_ch_c_dimm_c0_rfu_0';
NODE_NAME     J4G3 205
 '@BASEBOARD_FAB2_LIB.BASEBOARD_FAB2(SCH_1):PAGE47_I111@MSTR_SCONN.SCONN288_H44441004(CHIPS)':
 'RFU'<0>: CDS_PINID='RFU(0)';
NET_NAME
'TP_CH_C_DIMM_C0_RFU_1'
 '@BASEBOARD_FAB2_LIB.BASEBOARD_FAB2(SCH_1):TP_CH_C_DIMM_C0_RFU_1':
 C_SIGNAL='@baseboard_fab2_lib.baseboard_fab2(sch_1):tp_ch_c_dimm_c0_rfu_1';
NODE_NAME     J4G3 227
 '@BASEBOARD_FAB2_LIB.BASEBOARD_FAB2(SCH_1):PAGE47_I111@MSTR_SCONN.SCONN288_H44441004(CHIPS)':
 'RFU'<1>: CDS_PINID='RFU(1)';
NET_NAME
'TP_CH_C_DIMM_C0_RFU_2'
 '@BASEBOARD_FAB2_LIB.BASEBOARD_FAB2(SCH_1):TP_CH_C_DIMM_C0_RFU_2':
 C_SIGNAL='@baseboard_fab2_lib.baseboard_fab2(sch_1):tp_ch_c_dimm_c0_rfu_2';
NODE_NAME     J4G3 144
 '@BASEBOARD_FAB2_LIB.BASEBOARD_FAB2(SCH_1):PAGE47_I111@MSTR_SCONN.SCONN288_H44441004(CHIPS)':
 'RFU'<2>: CDS_PINID='RFU(2)';
NET_NAME
'TP_CH_C_DIMM_C1_RFU_0'
 '@BASEBOARD_FAB2_LIB.BASEBOARD_FAB2(SCH_1):TP_CH_C_DIMM_C1_RFU_0':
 C_SIGNAL='@baseboard_fab2_lib.baseboard_fab2(sch_1):tp_ch_c_dimm_c1_rfu_0';
NODE_NAME     J6U2 205
 '@BASEBOARD_FAB2_LIB.BASEBOARD_FAB2(SCH_1):PAGE48_I111@MSTR_SCONN.SCONN288_H44441003(CHIPS)':
 'RFU'<0>: CDS_PINID='RFU(0)';
NET_NAME
'TP_CH_C_DIMM_C1_RFU_1'
 '@BASEBOARD_FAB2_LIB.BASEBOARD_FAB2(SCH_1):TP_CH_C_DIMM_C1_RFU_1':
 C_SIGNAL='@baseboard_fab2_lib.baseboard_fab2(sch_1):tp_ch_c_dimm_c1_rfu_1';
NODE_NAME     J6U2 227
 '@BASEBOARD_FAB2_LIB.BASEBOARD_FAB2(SCH_1):PAGE48_I111@MSTR_SCONN.SCONN288_H44441003(CHIPS)':
 'RFU'<1>: CDS_PINID='RFU(1)';
NET_NAME
'TP_CH_C_DIMM_C1_RFU_2'
 '@BASEBOARD_FAB2_LIB.BASEBOARD_FAB2(SCH_1):TP_CH_C_DIMM_C1_RFU_2':
 C_SIGNAL='@baseboard_fab2_lib.baseboard_fab2(sch_1):tp_ch_c_dimm_c1_rfu_2';
NODE_NAME     J6U2 144
 '@BASEBOARD_FAB2_LIB.BASEBOARD_FAB2(SCH_1):PAGE48_I111@MSTR_SCONN.SCONN288_H44441003(CHIPS)':
 'RFU'<2>: CDS_PINID='RFU(2)';
NET_NAME
'TP_CH_D_DIMM_D0_RFU_0'
 '@BASEBOARD_FAB2_LIB.BASEBOARD_FAB2(SCH_1):TP_CH_D_DIMM_D0_RFU_0':
 C_SIGNAL='@baseboard_fab2_lib.baseboard_fab2(sch_1):tp_ch_d_dimm_d0_rfu_0';
NODE_NAME     J4B1 205
 '@BASEBOARD_FAB2_LIB.BASEBOARD_FAB2(SCH_1):PAGE49_I111@MSTR_SCONN.SCONN288_H44441004(CHIPS)':
 'RFU'<0>: CDS_PINID='RFU(0)';
NET_NAME
'TP_CH_D_DIMM_D0_RFU_1'
 '@BASEBOARD_FAB2_LIB.BASEBOARD_FAB2(SCH_1):TP_CH_D_DIMM_D0_RFU_1':
 C_SIGNAL='@baseboard_fab2_lib.baseboard_fab2(sch_1):tp_ch_d_dimm_d0_rfu_1';
NODE_NAME     J4B1 227
 '@BASEBOARD_FAB2_LIB.BASEBOARD_FAB2(SCH_1):PAGE49_I111@MSTR_SCONN.SCONN288_H44441004(CHIPS)':
 'RFU'<1>: CDS_PINID='RFU(1)';
NET_NAME
'TP_CH_D_DIMM_D0_RFU_2'
 '@BASEBOARD_FAB2_LIB.BASEBOARD_FAB2(SCH_1):TP_CH_D_DIMM_D0_RFU_2':
 C_SIGNAL='@baseboard_fab2_lib.baseboard_fab2(sch_1):tp_ch_d_dimm_d0_rfu_2';
NODE_NAME     J4B1 144
 '@BASEBOARD_FAB2_LIB.BASEBOARD_FAB2(SCH_1):PAGE49_I111@MSTR_SCONN.SCONN288_H44441004(CHIPS)':
 'RFU'<2>: CDS_PINID='RFU(2)';
NET_NAME
'TP_CH_D_DIMM_D1_RFU_0'
 '@BASEBOARD_FAB2_LIB.BASEBOARD_FAB2(SCH_1):TP_CH_D_DIMM_D1_RFU_0':
 C_SIGNAL='@baseboard_fab2_lib.baseboard_fab2(sch_1):tp_ch_d_dimm_d1_rfu_0';
NODE_NAME     J6M1 205
 '@BASEBOARD_FAB2_LIB.BASEBOARD_FAB2(SCH_1):PAGE50_I158@MSTR_SCONN.SCONN288_H44441003(CHIPS)':
 'RFU'<0>: CDS_PINID='RFU(0)';
NET_NAME
'TP_CH_D_DIMM_D1_RFU_1'
 '@BASEBOARD_FAB2_LIB.BASEBOARD_FAB2(SCH_1):TP_CH_D_DIMM_D1_RFU_1':
 C_SIGNAL='@baseboard_fab2_lib.baseboard_fab2(sch_1):tp_ch_d_dimm_d1_rfu_1';
NODE_NAME     J6M1 227
 '@BASEBOARD_FAB2_LIB.BASEBOARD_FAB2(SCH_1):PAGE50_I158@MSTR_SCONN.SCONN288_H44441003(CHIPS)':
 'RFU'<1>: CDS_PINID='RFU(1)';
NET_NAME
'TP_CH_D_DIMM_D1_RFU_2'
 '@BASEBOARD_FAB2_LIB.BASEBOARD_FAB2(SCH_1):TP_CH_D_DIMM_D1_RFU_2':
 C_SIGNAL='@baseboard_fab2_lib.baseboard_fab2(sch_1):tp_ch_d_dimm_d1_rfu_2';
NODE_NAME     J6M1 144
 '@BASEBOARD_FAB2_LIB.BASEBOARD_FAB2(SCH_1):PAGE50_I158@MSTR_SCONN.SCONN288_H44441003(CHIPS)':
 'RFU'<2>: CDS_PINID='RFU(2)';
NET_NAME
'TP_CH_E_DIMM_E0_RFU_0'
 '@BASEBOARD_FAB2_LIB.BASEBOARD_FAB2(SCH_1):TP_CH_E_DIMM_E0_RFU_0':
 C_SIGNAL='@baseboard_fab2_lib.baseboard_fab2(sch_1):tp_ch_e_dimm_e0_rfu_0';
NODE_NAME     J4A2 205
 '@BASEBOARD_FAB2_LIB.BASEBOARD_FAB2(SCH_1):PAGE51_I111@MSTR_SCONN.SCONN288_H44441004(CHIPS)':
 'RFU'<0>: CDS_PINID='RFU(0)';
NET_NAME
'TP_CH_E_DIMM_E0_RFU_1'
 '@BASEBOARD_FAB2_LIB.BASEBOARD_FAB2(SCH_1):TP_CH_E_DIMM_E0_RFU_1':
 C_SIGNAL='@baseboard_fab2_lib.baseboard_fab2(sch_1):tp_ch_e_dimm_e0_rfu_1';
NODE_NAME     J4A2 227
 '@BASEBOARD_FAB2_LIB.BASEBOARD_FAB2(SCH_1):PAGE51_I111@MSTR_SCONN.SCONN288_H44441004(CHIPS)':
 'RFU'<1>: CDS_PINID='RFU(1)';
NET_NAME
'TP_CH_E_DIMM_E0_RFU_2'
 '@BASEBOARD_FAB2_LIB.BASEBOARD_FAB2(SCH_1):TP_CH_E_DIMM_E0_RFU_2':
 C_SIGNAL='@baseboard_fab2_lib.baseboard_fab2(sch_1):tp_ch_e_dimm_e0_rfu_2';
NODE_NAME     J4A2 144
 '@BASEBOARD_FAB2_LIB.BASEBOARD_FAB2(SCH_1):PAGE51_I111@MSTR_SCONN.SCONN288_H44441004(CHIPS)':
 'RFU'<2>: CDS_PINID='RFU(2)';
NET_NAME
'TP_CH_E_DIMM_E1_RFU_0'
 '@BASEBOARD_FAB2_LIB.BASEBOARD_FAB2(SCH_1):TP_CH_E_DIMM_E1_RFU_0':
 C_SIGNAL='@baseboard_fab2_lib.baseboard_fab2(sch_1):tp_ch_e_dimm_e1_rfu_0';
NODE_NAME     J6L2 205
 '@BASEBOARD_FAB2_LIB.BASEBOARD_FAB2(SCH_1):PAGE52_I12@MSTR_SCONN.SCONN288_H44441003(CHIPS)':
 'RFU'<0>: CDS_PINID='RFU(0)';
NET_NAME
'TP_CH_E_DIMM_E1_RFU_1'
 '@BASEBOARD_FAB2_LIB.BASEBOARD_FAB2(SCH_1):TP_CH_E_DIMM_E1_RFU_1':
 C_SIGNAL='@baseboard_fab2_lib.baseboard_fab2(sch_1):tp_ch_e_dimm_e1_rfu_1';
NODE_NAME     J6L2 227
 '@BASEBOARD_FAB2_LIB.BASEBOARD_FAB2(SCH_1):PAGE52_I12@MSTR_SCONN.SCONN288_H44441003(CHIPS)':
 'RFU'<1>: CDS_PINID='RFU(1)';
NET_NAME
'TP_CH_E_DIMM_E1_RFU_2'
 '@BASEBOARD_FAB2_LIB.BASEBOARD_FAB2(SCH_1):TP_CH_E_DIMM_E1_RFU_2':
 C_SIGNAL='@baseboard_fab2_lib.baseboard_fab2(sch_1):tp_ch_e_dimm_e1_rfu_2';
NODE_NAME     J6L2 144
 '@BASEBOARD_FAB2_LIB.BASEBOARD_FAB2(SCH_1):PAGE52_I12@MSTR_SCONN.SCONN288_H44441003(CHIPS)':
 'RFU'<2>: CDS_PINID='RFU(2)';
NET_NAME
'TP_CH_F_DIMM_F0_RFU_0'
 '@BASEBOARD_FAB2_LIB.BASEBOARD_FAB2(SCH_1):TP_CH_F_DIMM_F0_RFU_0':
 C_SIGNAL='@baseboard_fab2_lib.baseboard_fab2(sch_1):tp_ch_f_dimm_f0_rfu_0';
NODE_NAME     J4A1 205
 '@BASEBOARD_FAB2_LIB.BASEBOARD_FAB2(SCH_1):PAGE53_I111@MSTR_SCONN.SCONN288_H44441004(CHIPS)':
 'RFU'<0>: CDS_PINID='RFU(0)';
NET_NAME
'TP_CH_F_DIMM_F0_RFU_1'
 '@BASEBOARD_FAB2_LIB.BASEBOARD_FAB2(SCH_1):TP_CH_F_DIMM_F0_RFU_1':
 C_SIGNAL='@baseboard_fab2_lib.baseboard_fab2(sch_1):tp_ch_f_dimm_f0_rfu_1';
NODE_NAME     J4A1 227
 '@BASEBOARD_FAB2_LIB.BASEBOARD_FAB2(SCH_1):PAGE53_I111@MSTR_SCONN.SCONN288_H44441004(CHIPS)':
 'RFU'<1>: CDS_PINID='RFU(1)';
NET_NAME
'TP_CH_F_DIMM_F0_RFU_2'
 '@BASEBOARD_FAB2_LIB.BASEBOARD_FAB2(SCH_1):TP_CH_F_DIMM_F0_RFU_2':
 C_SIGNAL='@baseboard_fab2_lib.baseboard_fab2(sch_1):tp_ch_f_dimm_f0_rfu_2';
NODE_NAME     J4A1 144
 '@BASEBOARD_FAB2_LIB.BASEBOARD_FAB2(SCH_1):PAGE53_I111@MSTR_SCONN.SCONN288_H44441004(CHIPS)':
 'RFU'<2>: CDS_PINID='RFU(2)';
NET_NAME
'TP_CH_F_DIMM_F1_RFU_0'
 '@BASEBOARD_FAB2_LIB.BASEBOARD_FAB2(SCH_1):TP_CH_F_DIMM_F1_RFU_0':
 C_SIGNAL='@baseboard_fab2_lib.baseboard_fab2(sch_1):tp_ch_f_dimm_f1_rfu_0';
NODE_NAME     J6L1 205
 '@BASEBOARD_FAB2_LIB.BASEBOARD_FAB2(SCH_1):PAGE54_I111@MSTR_SCONN.SCONN288_H44441003(CHIPS)':
 'RFU'<0>: CDS_PINID='RFU(0)';
NET_NAME
'TP_CH_F_DIMM_F1_RFU_1'
 '@BASEBOARD_FAB2_LIB.BASEBOARD_FAB2(SCH_1):TP_CH_F_DIMM_F1_RFU_1':
 C_SIGNAL='@baseboard_fab2_lib.baseboard_fab2(sch_1):tp_ch_f_dimm_f1_rfu_1';
NODE_NAME     J6L1 227
 '@BASEBOARD_FAB2_LIB.BASEBOARD_FAB2(SCH_1):PAGE54_I111@MSTR_SCONN.SCONN288_H44441003(CHIPS)':
 'RFU'<1>: CDS_PINID='RFU(1)';
NET_NAME
'TP_CH_F_DIMM_F1_RFU_2'
 '@BASEBOARD_FAB2_LIB.BASEBOARD_FAB2(SCH_1):TP_CH_F_DIMM_F1_RFU_2':
 C_SIGNAL='@baseboard_fab2_lib.baseboard_fab2(sch_1):tp_ch_f_dimm_f1_rfu_2';
NODE_NAME     J6L1 144
 '@BASEBOARD_FAB2_LIB.BASEBOARD_FAB2(SCH_1):PAGE54_I111@MSTR_SCONN.SCONN288_H44441003(CHIPS)':
 'RFU'<2>: CDS_PINID='RFU(2)';
NET_NAME
'TP_CH_G_DIMM0_RFU_0'
 '@BASEBOARD_FAB2_LIB.BASEBOARD_FAB2(SCH_1):TP_CH_G_DIMM0_RFU_0':
 C_SIGNAL='@baseboard_fab2_lib.baseboard_fab2(sch_1):tp_ch_g_dimm0_rfu_0';
NODE_NAME     J9T1 205
 '@BASEBOARD_FAB2_LIB.BASEBOARD_FAB2(SCH_1):PAGE78_I13@MSTR_SCONN.SCONN288_H44441003(CHIPS)':
 'RFU'<0>: CDS_PINID='RFU(0)';
NET_NAME
'TP_CH_G_DIMM0_RFU_1'
 '@BASEBOARD_FAB2_LIB.BASEBOARD_FAB2(SCH_1):TP_CH_G_DIMM0_RFU_1':
 C_SIGNAL='@baseboard_fab2_lib.baseboard_fab2(sch_1):tp_ch_g_dimm0_rfu_1';
NODE_NAME     J9T1 227
 '@BASEBOARD_FAB2_LIB.BASEBOARD_FAB2(SCH_1):PAGE78_I13@MSTR_SCONN.SCONN288_H44441003(CHIPS)':
 'RFU'<1>: CDS_PINID='RFU(1)';
NET_NAME
'TP_CH_G_DIMM0_RFU_2'
 '@BASEBOARD_FAB2_LIB.BASEBOARD_FAB2(SCH_1):TP_CH_G_DIMM0_RFU_2':
 C_SIGNAL='@baseboard_fab2_lib.baseboard_fab2(sch_1):tp_ch_g_dimm0_rfu_2';
NODE_NAME     J9T1 144
 '@BASEBOARD_FAB2_LIB.BASEBOARD_FAB2(SCH_1):PAGE78_I13@MSTR_SCONN.SCONN288_H44441003(CHIPS)':
 'RFU'<2>: CDS_PINID='RFU(2)';
NET_NAME
'TP_CH_G_DIMM_G0_RFU_0'
 '@BASEBOARD_FAB2_LIB.BASEBOARD_FAB2(SCH_1):TP_CH_G_DIMM_G0_RFU_0':
 C_SIGNAL='@baseboard_fab2_lib.baseboard_fab2(sch_1):tp_ch_g_dimm_g0_rfu_0';
NODE_NAME     J1G1 205
 '@BASEBOARD_FAB2_LIB.BASEBOARD_FAB2(SCH_1):PAGE77_I111@MSTR_SCONN.SCONN288_H44441004(CHIPS)':
 'RFU'<0>: CDS_PINID='RFU(0)';
NET_NAME
'TP_CH_G_DIMM_G0_RFU_1'
 '@BASEBOARD_FAB2_LIB.BASEBOARD_FAB2(SCH_1):TP_CH_G_DIMM_G0_RFU_1':
 C_SIGNAL='@baseboard_fab2_lib.baseboard_fab2(sch_1):tp_ch_g_dimm_g0_rfu_1';
NODE_NAME     J1G1 227
 '@BASEBOARD_FAB2_LIB.BASEBOARD_FAB2(SCH_1):PAGE77_I111@MSTR_SCONN.SCONN288_H44441004(CHIPS)':
 'RFU'<1>: CDS_PINID='RFU(1)';
NET_NAME
'TP_CH_G_DIMM_G0_RFU_2'
 '@BASEBOARD_FAB2_LIB.BASEBOARD_FAB2(SCH_1):TP_CH_G_DIMM_G0_RFU_2':
 C_SIGNAL='@baseboard_fab2_lib.baseboard_fab2(sch_1):tp_ch_g_dimm_g0_rfu_2';
NODE_NAME     J1G1 144
 '@BASEBOARD_FAB2_LIB.BASEBOARD_FAB2(SCH_1):PAGE77_I111@MSTR_SCONN.SCONN288_H44441004(CHIPS)':
 'RFU'<2>: CDS_PINID='RFU(2)';
NET_NAME
'TP_CH_H_DIMM0_RFU_0'
 '@BASEBOARD_FAB2_LIB.BASEBOARD_FAB2(SCH_1):TP_CH_H_DIMM0_RFU_0':
 C_SIGNAL='@baseboard_fab2_lib.baseboard_fab2(sch_1):tp_ch_h_dimm0_rfu_0';
NODE_NAME     J9U1 205
 '@BASEBOARD_FAB2_LIB.BASEBOARD_FAB2(SCH_1):PAGE80_I24@MSTR_SCONN.SCONN288_H44441003(CHIPS)':
 'RFU'<0>: CDS_PINID='RFU(0)';
NET_NAME
'TP_CH_H_DIMM0_RFU_1'
 '@BASEBOARD_FAB2_LIB.BASEBOARD_FAB2(SCH_1):TP_CH_H_DIMM0_RFU_1':
 C_SIGNAL='@baseboard_fab2_lib.baseboard_fab2(sch_1):tp_ch_h_dimm0_rfu_1';
NODE_NAME     J9U1 227
 '@BASEBOARD_FAB2_LIB.BASEBOARD_FAB2(SCH_1):PAGE80_I24@MSTR_SCONN.SCONN288_H44441003(CHIPS)':
 'RFU'<1>: CDS_PINID='RFU(1)';
NET_NAME
'TP_CH_H_DIMM0_RFU_2'
 '@BASEBOARD_FAB2_LIB.BASEBOARD_FAB2(SCH_1):TP_CH_H_DIMM0_RFU_2':
 C_SIGNAL='@baseboard_fab2_lib.baseboard_fab2(sch_1):tp_ch_h_dimm0_rfu_2';
NODE_NAME     J9U1 144
 '@BASEBOARD_FAB2_LIB.BASEBOARD_FAB2(SCH_1):PAGE80_I24@MSTR_SCONN.SCONN288_H44441003(CHIPS)':
 'RFU'<2>: CDS_PINID='RFU(2)';
NET_NAME
'TP_CH_H_DIMM_H0_RFU_0'
 '@BASEBOARD_FAB2_LIB.BASEBOARD_FAB2(SCH_1):TP_CH_H_DIMM_H0_RFU_0':
 C_SIGNAL='@baseboard_fab2_lib.baseboard_fab2(sch_1):tp_ch_h_dimm_h0_rfu_0';
NODE_NAME     J1G2 205
 '@BASEBOARD_FAB2_LIB.BASEBOARD_FAB2(SCH_1):PAGE79_I111@MSTR_SCONN.SCONN288_H44441004(CHIPS)':
 'RFU'<0>: CDS_PINID='RFU(0)';
NET_NAME
'TP_CH_H_DIMM_H0_RFU_1'
 '@BASEBOARD_FAB2_LIB.BASEBOARD_FAB2(SCH_1):TP_CH_H_DIMM_H0_RFU_1':
 C_SIGNAL='@baseboard_fab2_lib.baseboard_fab2(sch_1):tp_ch_h_dimm_h0_rfu_1';
NODE_NAME     J1G2 227
 '@BASEBOARD_FAB2_LIB.BASEBOARD_FAB2(SCH_1):PAGE79_I111@MSTR_SCONN.SCONN288_H44441004(CHIPS)':
 'RFU'<1>: CDS_PINID='RFU(1)';
NET_NAME
'TP_CH_H_DIMM_H0_RFU_2'
 '@BASEBOARD_FAB2_LIB.BASEBOARD_FAB2(SCH_1):TP_CH_H_DIMM_H0_RFU_2':
 C_SIGNAL='@baseboard_fab2_lib.baseboard_fab2(sch_1):tp_ch_h_dimm_h0_rfu_2';
NODE_NAME     J1G2 144
 '@BASEBOARD_FAB2_LIB.BASEBOARD_FAB2(SCH_1):PAGE79_I111@MSTR_SCONN.SCONN288_H44441004(CHIPS)':
 'RFU'<2>: CDS_PINID='RFU(2)';
NET_NAME
'TP_CH_J_DIMM_J0_RFU_0'
 '@BASEBOARD_FAB2_LIB.BASEBOARD_FAB2(SCH_1):TP_CH_J_DIMM_J0_RFU_0':
 C_SIGNAL='@baseboard_fab2_lib.baseboard_fab2(sch_1):tp_ch_j_dimm_j0_rfu_0';
NODE_NAME     J1G3 205
 '@BASEBOARD_FAB2_LIB.BASEBOARD_FAB2(SCH_1):PAGE81_I186@MSTR_SCONN.SCONN288_H44441004(CHIPS)':
 'RFU'<0>: CDS_PINID='RFU(0)';
NET_NAME
'TP_CH_J_DIMM_J0_RFU_1'
 '@BASEBOARD_FAB2_LIB.BASEBOARD_FAB2(SCH_1):TP_CH_J_DIMM_J0_RFU_1':
 C_SIGNAL='@baseboard_fab2_lib.baseboard_fab2(sch_1):tp_ch_j_dimm_j0_rfu_1';
NODE_NAME     J1G3 227
 '@BASEBOARD_FAB2_LIB.BASEBOARD_FAB2(SCH_1):PAGE81_I186@MSTR_SCONN.SCONN288_H44441004(CHIPS)':
 'RFU'<1>: CDS_PINID='RFU(1)';
NET_NAME
'TP_CH_J_DIMM_J0_RFU_2'
 '@BASEBOARD_FAB2_LIB.BASEBOARD_FAB2(SCH_1):TP_CH_J_DIMM_J0_RFU_2':
 C_SIGNAL='@baseboard_fab2_lib.baseboard_fab2(sch_1):tp_ch_j_dimm_j0_rfu_2';
NODE_NAME     J1G3 144
 '@BASEBOARD_FAB2_LIB.BASEBOARD_FAB2(SCH_1):PAGE81_I186@MSTR_SCONN.SCONN288_H44441004(CHIPS)':
 'RFU'<2>: CDS_PINID='RFU(2)';
NET_NAME
'TP_CH_J_DIMM_J1_RFU_0'
 '@BASEBOARD_FAB2_LIB.BASEBOARD_FAB2(SCH_1):TP_CH_J_DIMM_J1_RFU_0':
 C_SIGNAL='@baseboard_fab2_lib.baseboard_fab2(sch_1):tp_ch_j_dimm_j1_rfu_0';
NODE_NAME     J9U2 205
 '@BASEBOARD_FAB2_LIB.BASEBOARD_FAB2(SCH_1):PAGE82_I187@MSTR_SCONN.SCONN288_H44441003(CHIPS)':
 'RFU'<0>: CDS_PINID='RFU(0)';
NET_NAME
'TP_CH_J_DIMM_J1_RFU_1'
 '@BASEBOARD_FAB2_LIB.BASEBOARD_FAB2(SCH_1):TP_CH_J_DIMM_J1_RFU_1':
 C_SIGNAL='@baseboard_fab2_lib.baseboard_fab2(sch_1):tp_ch_j_dimm_j1_rfu_1';
NODE_NAME     J9U2 227
 '@BASEBOARD_FAB2_LIB.BASEBOARD_FAB2(SCH_1):PAGE82_I187@MSTR_SCONN.SCONN288_H44441003(CHIPS)':
 'RFU'<1>: CDS_PINID='RFU(1)';
NET_NAME
'TP_CH_J_DIMM_J1_RFU_2'
 '@BASEBOARD_FAB2_LIB.BASEBOARD_FAB2(SCH_1):TP_CH_J_DIMM_J1_RFU_2':
 C_SIGNAL='@baseboard_fab2_lib.baseboard_fab2(sch_1):tp_ch_j_dimm_j1_rfu_2';
NODE_NAME     J9U2 144
 '@BASEBOARD_FAB2_LIB.BASEBOARD_FAB2(SCH_1):PAGE82_I187@MSTR_SCONN.SCONN288_H44441003(CHIPS)':
 'RFU'<2>: CDS_PINID='RFU(2)';
NET_NAME
'TP_CH_K_DIMM0_RFU_0'
 '@BASEBOARD_FAB2_LIB.BASEBOARD_FAB2(SCH_1):TP_CH_K_DIMM0_RFU_0':
 C_SIGNAL='@baseboard_fab2_lib.baseboard_fab2(sch_1):tp_ch_k_dimm0_rfu_0';
NODE_NAME     J9M1 205
 '@BASEBOARD_FAB2_LIB.BASEBOARD_FAB2(SCH_1):PAGE84_I14@MSTR_SCONN.SCONN288_H44441003(CHIPS)':
 'RFU'<0>: CDS_PINID='RFU(0)';
NET_NAME
'TP_CH_K_DIMM0_RFU_1'
 '@BASEBOARD_FAB2_LIB.BASEBOARD_FAB2(SCH_1):TP_CH_K_DIMM0_RFU_1':
 C_SIGNAL='@baseboard_fab2_lib.baseboard_fab2(sch_1):tp_ch_k_dimm0_rfu_1';
NODE_NAME     J9M1 227
 '@BASEBOARD_FAB2_LIB.BASEBOARD_FAB2(SCH_1):PAGE84_I14@MSTR_SCONN.SCONN288_H44441003(CHIPS)':
 'RFU'<1>: CDS_PINID='RFU(1)';
NET_NAME
'TP_CH_K_DIMM0_RFU_2'
 '@BASEBOARD_FAB2_LIB.BASEBOARD_FAB2(SCH_1):TP_CH_K_DIMM0_RFU_2':
 C_SIGNAL='@baseboard_fab2_lib.baseboard_fab2(sch_1):tp_ch_k_dimm0_rfu_2';
NODE_NAME     J9M1 144
 '@BASEBOARD_FAB2_LIB.BASEBOARD_FAB2(SCH_1):PAGE84_I14@MSTR_SCONN.SCONN288_H44441003(CHIPS)':
 'RFU'<2>: CDS_PINID='RFU(2)';
NET_NAME
'TP_CH_K_DIMM_K0_RFU_0'
 '@BASEBOARD_FAB2_LIB.BASEBOARD_FAB2(SCH_1):TP_CH_K_DIMM_K0_RFU_0':
 C_SIGNAL='@baseboard_fab2_lib.baseboard_fab2(sch_1):tp_ch_k_dimm_k0_rfu_0';
NODE_NAME     J1B1 205
 '@BASEBOARD_FAB2_LIB.BASEBOARD_FAB2(SCH_1):PAGE83_I111@MSTR_SCONN.SCONN288_H44441004(CHIPS)':
 'RFU'<0>: CDS_PINID='RFU(0)';
NET_NAME
'TP_CH_K_DIMM_K0_RFU_1'
 '@BASEBOARD_FAB2_LIB.BASEBOARD_FAB2(SCH_1):TP_CH_K_DIMM_K0_RFU_1':
 C_SIGNAL='@baseboard_fab2_lib.baseboard_fab2(sch_1):tp_ch_k_dimm_k0_rfu_1';
NODE_NAME     J1B1 227
 '@BASEBOARD_FAB2_LIB.BASEBOARD_FAB2(SCH_1):PAGE83_I111@MSTR_SCONN.SCONN288_H44441004(CHIPS)':
 'RFU'<1>: CDS_PINID='RFU(1)';
NET_NAME
'TP_CH_K_DIMM_K0_RFU_2'
 '@BASEBOARD_FAB2_LIB.BASEBOARD_FAB2(SCH_1):TP_CH_K_DIMM_K0_RFU_2':
 C_SIGNAL='@baseboard_fab2_lib.baseboard_fab2(sch_1):tp_ch_k_dimm_k0_rfu_2';
NODE_NAME     J1B1 144
 '@BASEBOARD_FAB2_LIB.BASEBOARD_FAB2(SCH_1):PAGE83_I111@MSTR_SCONN.SCONN288_H44441004(CHIPS)':
 'RFU'<2>: CDS_PINID='RFU(2)';
NET_NAME
'TP_CH_L_DIMM0_RFU_0'
 '@BASEBOARD_FAB2_LIB.BASEBOARD_FAB2(SCH_1):TP_CH_L_DIMM0_RFU_0':
 C_SIGNAL='@baseboard_fab2_lib.baseboard_fab2(sch_1):tp_ch_l_dimm0_rfu_0';
NODE_NAME     J9L2 205
 '@BASEBOARD_FAB2_LIB.BASEBOARD_FAB2(SCH_1):PAGE86_I12@MSTR_SCONN.SCONN288_H44441003(CHIPS)':
 'RFU'<0>: CDS_PINID='RFU(0)';
NET_NAME
'TP_CH_L_DIMM0_RFU_1'
 '@BASEBOARD_FAB2_LIB.BASEBOARD_FAB2(SCH_1):TP_CH_L_DIMM0_RFU_1':
 C_SIGNAL='@baseboard_fab2_lib.baseboard_fab2(sch_1):tp_ch_l_dimm0_rfu_1';
NODE_NAME     J9L2 227
 '@BASEBOARD_FAB2_LIB.BASEBOARD_FAB2(SCH_1):PAGE86_I12@MSTR_SCONN.SCONN288_H44441003(CHIPS)':
 'RFU'<1>: CDS_PINID='RFU(1)';
NET_NAME
'TP_CH_L_DIMM0_RFU_2'
 '@BASEBOARD_FAB2_LIB.BASEBOARD_FAB2(SCH_1):TP_CH_L_DIMM0_RFU_2':
 C_SIGNAL='@baseboard_fab2_lib.baseboard_fab2(sch_1):tp_ch_l_dimm0_rfu_2';
NODE_NAME     J9L2 144
 '@BASEBOARD_FAB2_LIB.BASEBOARD_FAB2(SCH_1):PAGE86_I12@MSTR_SCONN.SCONN288_H44441003(CHIPS)':
 'RFU'<2>: CDS_PINID='RFU(2)';
NET_NAME
'TP_CH_L_DIMM_L0_RFU_0'
 '@BASEBOARD_FAB2_LIB.BASEBOARD_FAB2(SCH_1):TP_CH_L_DIMM_L0_RFU_0':
 C_SIGNAL='@baseboard_fab2_lib.baseboard_fab2(sch_1):tp_ch_l_dimm_l0_rfu_0';
NODE_NAME     J1A2 205
 '@BASEBOARD_FAB2_LIB.BASEBOARD_FAB2(SCH_1):PAGE85_I111@MSTR_SCONN.SCONN288_H44441004(CHIPS)':
 'RFU'<0>: CDS_PINID='RFU(0)';
NET_NAME
'TP_CH_L_DIMM_L0_RFU_1'
 '@BASEBOARD_FAB2_LIB.BASEBOARD_FAB2(SCH_1):TP_CH_L_DIMM_L0_RFU_1':
 C_SIGNAL='@baseboard_fab2_lib.baseboard_fab2(sch_1):tp_ch_l_dimm_l0_rfu_1';
NODE_NAME     J1A2 227
 '@BASEBOARD_FAB2_LIB.BASEBOARD_FAB2(SCH_1):PAGE85_I111@MSTR_SCONN.SCONN288_H44441004(CHIPS)':
 'RFU'<1>: CDS_PINID='RFU(1)';
NET_NAME
'TP_CH_L_DIMM_L0_RFU_2'
 '@BASEBOARD_FAB2_LIB.BASEBOARD_FAB2(SCH_1):TP_CH_L_DIMM_L0_RFU_2':
 C_SIGNAL='@baseboard_fab2_lib.baseboard_fab2(sch_1):tp_ch_l_dimm_l0_rfu_2';
NODE_NAME     J1A2 144
 '@BASEBOARD_FAB2_LIB.BASEBOARD_FAB2(SCH_1):PAGE85_I111@MSTR_SCONN.SCONN288_H44441004(CHIPS)':
 'RFU'<2>: CDS_PINID='RFU(2)';
NET_NAME
'TP_CH_M_DIMM_M0_RFU_0'
 '@BASEBOARD_FAB2_LIB.BASEBOARD_FAB2(SCH_1):TP_CH_M_DIMM_M0_RFU_0':
 C_SIGNAL='@baseboard_fab2_lib.baseboard_fab2(sch_1):tp_ch_m_dimm_m0_rfu_0';
NODE_NAME     J1A1 205
 '@BASEBOARD_FAB2_LIB.BASEBOARD_FAB2(SCH_1):PAGE87_I186@MSTR_SCONN.SCONN288_H44441004(CHIPS)':
 'RFU'<0>: CDS_PINID='RFU(0)';
NET_NAME
'TP_CH_M_DIMM_M0_RFU_1'
 '@BASEBOARD_FAB2_LIB.BASEBOARD_FAB2(SCH_1):TP_CH_M_DIMM_M0_RFU_1':
 C_SIGNAL='@baseboard_fab2_lib.baseboard_fab2(sch_1):tp_ch_m_dimm_m0_rfu_1';
NODE_NAME     J1A1 227
 '@BASEBOARD_FAB2_LIB.BASEBOARD_FAB2(SCH_1):PAGE87_I186@MSTR_SCONN.SCONN288_H44441004(CHIPS)':
 'RFU'<1>: CDS_PINID='RFU(1)';
NET_NAME
'TP_CH_M_DIMM_M0_RFU_2'
 '@BASEBOARD_FAB2_LIB.BASEBOARD_FAB2(SCH_1):TP_CH_M_DIMM_M0_RFU_2':
 C_SIGNAL='@baseboard_fab2_lib.baseboard_fab2(sch_1):tp_ch_m_dimm_m0_rfu_2';
NODE_NAME     J1A1 144
 '@BASEBOARD_FAB2_LIB.BASEBOARD_FAB2(SCH_1):PAGE87_I186@MSTR_SCONN.SCONN288_H44441004(CHIPS)':
 'RFU'<2>: CDS_PINID='RFU(2)';
NET_NAME
'TP_CH_M_DIMM_M1_RFU_0'
 '@BASEBOARD_FAB2_LIB.BASEBOARD_FAB2(SCH_1):TP_CH_M_DIMM_M1_RFU_0':
 C_SIGNAL='@baseboard_fab2_lib.baseboard_fab2(sch_1):tp_ch_m_dimm_m1_rfu_0';
NODE_NAME     J9L1 205
 '@BASEBOARD_FAB2_LIB.BASEBOARD_FAB2(SCH_1):PAGE88_I111@MSTR_SCONN.SCONN288_H44441003(CHIPS)':
 'RFU'<0>: CDS_PINID='RFU(0)';
NET_NAME
'TP_CH_M_DIMM_M1_RFU_1'
 '@BASEBOARD_FAB2_LIB.BASEBOARD_FAB2(SCH_1):TP_CH_M_DIMM_M1_RFU_1':
 C_SIGNAL='@baseboard_fab2_lib.baseboard_fab2(sch_1):tp_ch_m_dimm_m1_rfu_1';
NODE_NAME     J9L1 227
 '@BASEBOARD_FAB2_LIB.BASEBOARD_FAB2(SCH_1):PAGE88_I111@MSTR_SCONN.SCONN288_H44441003(CHIPS)':
 'RFU'<1>: CDS_PINID='RFU(1)';
NET_NAME
'TP_CH_M_DIMM_M1_RFU_2'
 '@BASEBOARD_FAB2_LIB.BASEBOARD_FAB2(SCH_1):TP_CH_M_DIMM_M1_RFU_2':
 C_SIGNAL='@baseboard_fab2_lib.baseboard_fab2(sch_1):tp_ch_m_dimm_m1_rfu_2';
NODE_NAME     J9L1 144
 '@BASEBOARD_FAB2_LIB.BASEBOARD_FAB2(SCH_1):PAGE88_I111@MSTR_SCONN.SCONN288_H44441003(CHIPS)':
 'RFU'<2>: CDS_PINID='RFU(2)';
NET_NAME
'TP_CLK5_50M_CKMNG'
 '@BASEBOARD_FAB2_LIB.BASEBOARD_FAB2(SCH_1):TP_CLK5_50M_CKMNG':
 C_SIGNAL='@baseboard_fab2_lib.baseboard_fab2(sch_1):tp_clk5_50m_ckmng';
NODE_NAME     EU8F2 24
 '@BASEBOARD_FAB2_LIB.BASEBOARD_FAB2(SCH_1):PAGE101_I34@MSTR_CLOCK.ICS9FGP204(CHIPS)':
 'RMII'<5>: CDS_PINID='RMII(5)';
NET_NAME
'TP_CLK_100M_NSSCC0_DN'
 '@BASEBOARD_FAB2_LIB.BASEBOARD_FAB2(SCH_1):TP_CLK_100M_NSSCC0_DN':
 C_SIGNAL='@baseboard_fab2_lib.baseboard_fab2(sch_1):tp_clk_100m_nsscc0_dn';
NODE_NAME     U7C1 A32
 '@BASEBOARD_FAB2_LIB.BASEBOARD_FAB2(SCH_1):PAGE114_I40@MSTR_U_PROC.LBG_CORE_QAT_EXT_D(CHIPS)':
 'CLKOUT_NSSCCAP0N': CDS_PINID='CLKOUT_NSSCCAP0N';
NET_NAME
'TP_CLK_100M_NSSCC0_DP'
 '@BASEBOARD_FAB2_LIB.BASEBOARD_FAB2(SCH_1):TP_CLK_100M_NSSCC0_DP':
 C_SIGNAL='@baseboard_fab2_lib.baseboard_fab2(sch_1):tp_clk_100m_nsscc0_dp';
NODE_NAME     U7C1 C32
 '@BASEBOARD_FAB2_LIB.BASEBOARD_FAB2(SCH_1):PAGE114_I40@MSTR_U_PROC.LBG_CORE_QAT_EXT_D(CHIPS)':
 'CLKOUT_NSSCCAP0P': CDS_PINID='CLKOUT_NSSCCAP0P';
NET_NAME
'TP_CLK_100M_NSSCC1_DN'
 '@BASEBOARD_FAB2_LIB.BASEBOARD_FAB2(SCH_1):TP_CLK_100M_NSSCC1_DN':
 C_SIGNAL='@baseboard_fab2_lib.baseboard_fab2(sch_1):tp_clk_100m_nsscc1_dn';
NODE_NAME     U7C1 B38
 '@BASEBOARD_FAB2_LIB.BASEBOARD_FAB2(SCH_1):PAGE114_I40@MSTR_U_PROC.LBG_CORE_QAT_EXT_D(CHIPS)':
 'CLKOUT_NSSCCAP1N': CDS_PINID='CLKOUT_NSSCCAP1N';
NET_NAME
'TP_CLK_100M_NSSCC1_DP'
 '@BASEBOARD_FAB2_LIB.BASEBOARD_FAB2(SCH_1):TP_CLK_100M_NSSCC1_DP':
 C_SIGNAL='@baseboard_fab2_lib.baseboard_fab2(sch_1):tp_clk_100m_nsscc1_dp';
NODE_NAME     U7C1 D38
 '@BASEBOARD_FAB2_LIB.BASEBOARD_FAB2(SCH_1):PAGE114_I40@MSTR_U_PROC.LBG_CORE_QAT_EXT_D(CHIPS)':
 'CLKOUT_NSSCCAP1P': CDS_PINID='CLKOUT_NSSCCAP1P';
NET_NAME
'TP_CLK_100M_PLAT1_DN'
 '@BASEBOARD_FAB2_LIB.BASEBOARD_FAB2(SCH_1):TP_CLK_100M_PLAT1_DN':
 C_SIGNAL='@baseboard_fab2_lib.baseboard_fab2(sch_1):tp_clk_100m_plat1_dn';
NODE_NAME     U7C1 B40
 '@BASEBOARD_FAB2_LIB.BASEBOARD_FAB2(SCH_1):PAGE114_I40@MSTR_U_PROC.LBG_CORE_QAT_EXT_D(CHIPS)':
 'CLKOUT_PLAT1N': CDS_PINID='CLKOUT_PLAT1N';
NET_NAME
'TP_CLK_100M_PLAT1_DP'
 '@BASEBOARD_FAB2_LIB.BASEBOARD_FAB2(SCH_1):TP_CLK_100M_PLAT1_DP':
 C_SIGNAL='@baseboard_fab2_lib.baseboard_fab2(sch_1):tp_clk_100m_plat1_dp';
NODE_NAME     U7C1 D40
 '@BASEBOARD_FAB2_LIB.BASEBOARD_FAB2(SCH_1):PAGE114_I40@MSTR_U_PROC.LBG_CORE_QAT_EXT_D(CHIPS)':
 'CLKOUT_PLAT1P': CDS_PINID='CLKOUT_PLAT1P';
NET_NAME
'TP_CLK_100M_R_DN'
 '@BASEBOARD_FAB2_LIB.BASEBOARD_FAB2(SCH_1):TP_CLK_100M_R_DN':
 C_SIGNAL='@baseboard_fab2_lib.baseboard_fab2(sch_1):tp_clk_100m_r_dn';
NODE_NAME     EU8F2 8
 '@BASEBOARD_FAB2_LIB.BASEBOARD_FAB2(SCH_1):PAGE101_I34@MSTR_CLOCK.ICS9FGP204(CHIPS)':
 'CPUCLKC0': CDS_PINID='CPUCLKC0';
NET_NAME
'TP_CLK_100M_R_DP'
 '@BASEBOARD_FAB2_LIB.BASEBOARD_FAB2(SCH_1):TP_CLK_100M_R_DP':
 C_SIGNAL='@baseboard_fab2_lib.baseboard_fab2(sch_1):tp_clk_100m_r_dp';
NODE_NAME     EU8F2 7
 '@BASEBOARD_FAB2_LIB.BASEBOARD_FAB2(SCH_1):PAGE101_I34@MSTR_CLOCK.ICS9FGP204(CHIPS)':
 'CPUCLKT0': CDS_PINID='CPUCLKT0';
NET_NAME
'TP_CLK_125M'
 '@BASEBOARD_FAB2_LIB.BASEBOARD_FAB2(SCH_1):TP_CLK_125M':
 C_SIGNAL='@baseboard_fab2_lib.baseboard_fab2(sch_1):tp_clk_125m';
NODE_NAME     EU8F2 36
 '@BASEBOARD_FAB2_LIB.BASEBOARD_FAB2(SCH_1):PAGE101_I34@MSTR_CLOCK.ICS9FGP204(CHIPS)':
 'RGMII'<1>: CDS_PINID='RGMII(1)';
NET_NAME
'TP_CLK_125M_BMCA'
 '@BASEBOARD_FAB2_LIB.BASEBOARD_FAB2(SCH_1):TP_CLK_125M_BMCA':
 C_SIGNAL='@baseboard_fab2_lib.baseboard_fab2(sch_1):tp_clk_125m_bmca';
NODE_NAME     EU8F2 37
 '@BASEBOARD_FAB2_LIB.BASEBOARD_FAB2(SCH_1):PAGE101_I34@MSTR_CLOCK.ICS9FGP204(CHIPS)':
 'RGMII'<0>: CDS_PINID='RGMII(0)';
NET_NAME
'TP_CLK_24M_PMSYNC2'
 '@BASEBOARD_FAB2_LIB.BASEBOARD_FAB2(SCH_1):TP_CLK_24M_PMSYNC2':
 C_SIGNAL='@baseboard_fab2_lib.baseboard_fab2(sch_1):tp_clk_24m_pmsync2';
NODE_NAME     U7C1 BV51
 '@BASEBOARD_FAB2_LIB.BASEBOARD_FAB2(SCH_1):PAGE114_I40@MSTR_U_PROC.LBG_CORE_QAT_EXT_D(CHIPS)':
 'CLOCKSE_PMSYNCCLK2': CDS_PINID='CLOCKSE_PMSYNCCLK2';
NET_NAME
'TP_CLK_96M_CKMNG_N'
 '@BASEBOARD_FAB2_LIB.BASEBOARD_FAB2(SCH_1):TP_CLK_96M_CKMNG_N':
 C_SIGNAL='@baseboard_fab2_lib.baseboard_fab2(sch_1):tp_clk_96m_ckmng_n';
NODE_NAME     EU8F2 4
 '@BASEBOARD_FAB2_LIB.BASEBOARD_FAB2(SCH_1):PAGE101_I34@MSTR_CLOCK.ICS9FGP204(CHIPS)':
 'DOT96SSC': CDS_PINID='DOT96SSC';
NET_NAME
'TP_CLK_96M_CKMNG_P'
 '@BASEBOARD_FAB2_LIB.BASEBOARD_FAB2(SCH_1):TP_CLK_96M_CKMNG_P':
 C_SIGNAL='@baseboard_fab2_lib.baseboard_fab2(sch_1):tp_clk_96m_ckmng_p';
NODE_NAME     EU8F2 3
 '@BASEBOARD_FAB2_LIB.BASEBOARD_FAB2(SCH_1):PAGE101_I34@MSTR_CLOCK.ICS9FGP204(CHIPS)':
 'DOT96SST': CDS_PINID='DOT96SST';
NET_NAME
'TP_CPLD1_PB16A_PCLKT2_1'
 '@BASEBOARD_FAB2_LIB.BASEBOARD_FAB2(SCH_1):TP_CPLD1_PB16A_PCLKT2_1':
 C_SIGNAL='@baseboard_fab2_lib.baseboard_fab2(sch_1):tp_cpld1_pb16a_pclkt2_1';
NODE_NAME     U8D7 T9
 '@BASEBOARD_FAB2_LIB.BASEBOARD_FAB2(SCH_1):PAGE190_I179@MSTR_MEMORY.LCMXO2_A(CHIPS)':
 'PB16A_PCLKT2_1': CDS_PINID='PB16A_PCLKT2_1';
NET_NAME
'TP_CPLD1_PB16B_PCLKC2_1'
 '@BASEBOARD_FAB2_LIB.BASEBOARD_FAB2(SCH_1):TP_CPLD1_PB16B_PCLKC2_1':
 C_SIGNAL='@baseboard_fab2_lib.baseboard_fab2(sch_1):tp_cpld1_pb16b_pclkc2_1';
NODE_NAME     U8D7 P9
 '@BASEBOARD_FAB2_LIB.BASEBOARD_FAB2(SCH_1):PAGE190_I179@MSTR_MEMORY.LCMXO2_A(CHIPS)':
 'PB16B_PCLKC2_1': CDS_PINID='PB16B_PCLKC2_1';
NET_NAME
'TP_CPLD1_PB25B_SI_SISPI'
 '@BASEBOARD_FAB2_LIB.BASEBOARD_FAB2(SCH_1):TP_CPLD1_PB25B_SI_SISPI':
 C_SIGNAL='@baseboard_fab2_lib.baseboard_fab2(sch_1):tp_cpld1_pb25b_si_sispi';
NODE_NAME     U8D7 P13
 '@BASEBOARD_FAB2_LIB.BASEBOARD_FAB2(SCH_1):PAGE190_I179@MSTR_MEMORY.LCMXO2_A(CHIPS)':
 'PB25B_SI_SISPI': CDS_PINID='PB25B_SI_SISPI';
NET_NAME
'TP_CPLD1_PB5A_CSSPIN'
 '@BASEBOARD_FAB2_LIB.BASEBOARD_FAB2(SCH_1):TP_CPLD1_PB5A_CSSPIN':
 C_SIGNAL='@baseboard_fab2_lib.baseboard_fab2(sch_1):tp_cpld1_pb5a_csspin';
NODE_NAME     U8D7 R5
 '@BASEBOARD_FAB2_LIB.BASEBOARD_FAB2(SCH_1):PAGE190_I179@MSTR_MEMORY.LCMXO2_A(CHIPS)':
 'PB5A_CSSPIN': CDS_PINID='PB5A_CSSPIN';
NET_NAME
'TP_CPLD1_PB8A_MCLK_CCLK'
 '@BASEBOARD_FAB2_LIB.BASEBOARD_FAB2(SCH_1):TP_CPLD1_PB8A_MCLK_CCLK':
 C_SIGNAL='@baseboard_fab2_lib.baseboard_fab2(sch_1):tp_cpld1_pb8a_mclk_cclk';
NODE_NAME     U8D7 P6
 '@BASEBOARD_FAB2_LIB.BASEBOARD_FAB2(SCH_1):PAGE190_I179@MSTR_MEMORY.LCMXO2_A(CHIPS)':
 'PB8A_MCLK_CCLK': CDS_PINID='PB8A_MCLK_CCLK';
NET_NAME
'TP_CPLD1_PB8B_SO_SPISO'
 '@BASEBOARD_FAB2_LIB.BASEBOARD_FAB2(SCH_1):TP_CPLD1_PB8B_SO_SPISO':
 C_SIGNAL='@baseboard_fab2_lib.baseboard_fab2(sch_1):tp_cpld1_pb8b_so_spiso';
NODE_NAME     U8D7 T6
 '@BASEBOARD_FAB2_LIB.BASEBOARD_FAB2(SCH_1):PAGE190_I179@MSTR_MEMORY.LCMXO2_A(CHIPS)':
 'PB8B_SO_SPISO': CDS_PINID='PB8B_SO_SPISO';
NET_NAME
'TP_CPLD1_PL11A'
 '@BASEBOARD_FAB2_LIB.BASEBOARD_FAB2(SCH_1):TP_CPLD1_PL11A':
 C_SIGNAL='@baseboard_fab2_lib.baseboard_fab2(sch_1):tp_cpld1_pl11a';
NODE_NAME     U8D7 L3
 '@BASEBOARD_FAB2_LIB.BASEBOARD_FAB2(SCH_1):PAGE190_I179@MSTR_MEMORY.LCMXO2_A(CHIPS)':
 'PL11B': CDS_PINID='PL11B';
NET_NAME
'TP_CPLD1_PL1A_L_GPLLT_FB'
 '@BASEBOARD_FAB2_LIB.BASEBOARD_FAB2(SCH_1):TP_CPLD1_PL1A_L_GPLLT_FB':
 C_SIGNAL='@baseboard_fab2_lib.baseboard_fab2(sch_1):tp_cpld1_pl1a_l_gpllt_fb';
NODE_NAME     U8D7 D3
 '@BASEBOARD_FAB2_LIB.BASEBOARD_FAB2(SCH_1):PAGE190_I179@MSTR_MEMORY.LCMXO2_A(CHIPS)':
 'PL1A_L_GPLLT_FB': CDS_PINID='PL1A_L_GPLLT_FB';
NET_NAME
'TP_CPLD1_PL1B_L_GPLLC_FB'
 '@BASEBOARD_FAB2_LIB.BASEBOARD_FAB2(SCH_1):TP_CPLD1_PL1B_L_GPLLC_FB':
 C_SIGNAL='@baseboard_fab2_lib.baseboard_fab2(sch_1):tp_cpld1_pl1b_l_gpllc_fb';
NODE_NAME     U8D7 D1
 '@BASEBOARD_FAB2_LIB.BASEBOARD_FAB2(SCH_1):PAGE190_I179@MSTR_MEMORY.LCMXO2_A(CHIPS)':
 'PL1B_L_GPLLC_FB': CDS_PINID='PL1B_L_GPLLC_FB';
NET_NAME
'TP_CPLD1_PL2B_L_GPLLC_IN'
 '@BASEBOARD_FAB2_LIB.BASEBOARD_FAB2(SCH_1):TP_CPLD1_PL2B_L_GPLLC_IN':
 C_SIGNAL='@baseboard_fab2_lib.baseboard_fab2(sch_1):tp_cpld1_pl2b_l_gpllc_in';
NODE_NAME     U8D7 E3
 '@BASEBOARD_FAB2_LIB.BASEBOARD_FAB2(SCH_1):PAGE190_I179@MSTR_MEMORY.LCMXO2_A(CHIPS)':
 'PL2B_L_GPLLC_IN': CDS_PINID='PL2B_L_GPLLC_IN';
NET_NAME
'TP_CPLD1_PL7D_PCLKT4_0'
 '@BASEBOARD_FAB2_LIB.BASEBOARD_FAB2(SCH_1):TP_CPLD1_PL7D_PCLKT4_0':
 C_SIGNAL='@baseboard_fab2_lib.baseboard_fab2(sch_1):tp_cpld1_pl7d_pclkt4_0';
NODE_NAME     U8D7 J3
 '@BASEBOARD_FAB2_LIB.BASEBOARD_FAB2(SCH_1):PAGE190_I179@MSTR_MEMORY.LCMXO2_A(CHIPS)':
 'PL7D_PCLKC4_0': CDS_PINID='PL7D_PCLKC4_0';
NET_NAME
'TP_CPLD1_PR10C'
 '@BASEBOARD_FAB2_LIB.BASEBOARD_FAB2(SCH_1):TP_CPLD1_PR10C':
 C_SIGNAL='@baseboard_fab2_lib.baseboard_fab2(sch_1):tp_cpld1_pr10c';
NODE_NAME     U8D7 J11
 '@BASEBOARD_FAB2_LIB.BASEBOARD_FAB2(SCH_1):PAGE191_I59@MSTR_MEMORY.LCMXO2_A(CHIPS)':
 'PR10C': CDS_PINID='PR10C';
NET_NAME
'TP_CPLD1_PR11B'
 '@BASEBOARD_FAB2_LIB.BASEBOARD_FAB2(SCH_1):TP_CPLD1_PR11B':
 C_SIGNAL='@baseboard_fab2_lib.baseboard_fab2(sch_1):tp_cpld1_pr11b';
NODE_NAME     U8D7 L14
 '@BASEBOARD_FAB2_LIB.BASEBOARD_FAB2(SCH_1):PAGE191_I59@MSTR_MEMORY.LCMXO2_A(CHIPS)':
 'PR11B': CDS_PINID='PR11B';
NET_NAME
'TP_CPLD1_PR12D'
 '@BASEBOARD_FAB2_LIB.BASEBOARD_FAB2(SCH_1):TP_CPLD1_PR12D':
 C_SIGNAL='@baseboard_fab2_lib.baseboard_fab2(sch_1):tp_cpld1_pr12d';
NODE_NAME     U8D7 L13
 '@BASEBOARD_FAB2_LIB.BASEBOARD_FAB2(SCH_1):PAGE191_I59@MSTR_MEMORY.LCMXO2_A(CHIPS)':
 'PR12D': CDS_PINID='PR12D';
NET_NAME
'TP_CPLD1_PR7A_PCLKT1_0'
 '@BASEBOARD_FAB2_LIB.BASEBOARD_FAB2(SCH_1):TP_CPLD1_PR7A_PCLKT1_0':
 C_SIGNAL='@baseboard_fab2_lib.baseboard_fab2(sch_1):tp_cpld1_pr7a_pclkt1_0';
NODE_NAME     U8D7 H14
 '@BASEBOARD_FAB2_LIB.BASEBOARD_FAB2(SCH_1):PAGE191_I59@MSTR_MEMORY.LCMXO2_A(CHIPS)':
 'PR7A_PCLKT1_0': CDS_PINID='PR7A_PCLKT1_0';
NET_NAME
'TP_CPLD1_PR7B_PCLKC1_0'
 '@BASEBOARD_FAB2_LIB.BASEBOARD_FAB2(SCH_1):TP_CPLD1_PR7B_PCLKC1_0':
 C_SIGNAL='@baseboard_fab2_lib.baseboard_fab2(sch_1):tp_cpld1_pr7b_pclkc1_0';
NODE_NAME     U8D7 H16
 '@BASEBOARD_FAB2_LIB.BASEBOARD_FAB2(SCH_1):PAGE191_I59@MSTR_MEMORY.LCMXO2_A(CHIPS)':
 'PR7B_PCLKC1_0': CDS_PINID='PR7B_PCLKC1_0';
NET_NAME
'TP_CPLD1_PR7C'
 '@BASEBOARD_FAB2_LIB.BASEBOARD_FAB2(SCH_1):TP_CPLD1_PR7C':
 C_SIGNAL='@baseboard_fab2_lib.baseboard_fab2(sch_1):tp_cpld1_pr7c';
NODE_NAME     U8D7 J16
 '@BASEBOARD_FAB2_LIB.BASEBOARD_FAB2(SCH_1):PAGE191_I59@MSTR_MEMORY.LCMXO2_A(CHIPS)':
 'PR7C': CDS_PINID='PR7C';
NET_NAME
'TP_CPLD1_PR7D'
 '@BASEBOARD_FAB2_LIB.BASEBOARD_FAB2(SCH_1):TP_CPLD1_PR7D':
 C_SIGNAL='@baseboard_fab2_lib.baseboard_fab2(sch_1):tp_cpld1_pr7d';
NODE_NAME     U8D7 J14
 '@BASEBOARD_FAB2_LIB.BASEBOARD_FAB2(SCH_1):PAGE191_I59@MSTR_MEMORY.LCMXO2_A(CHIPS)':
 'PR7D': CDS_PINID='PR7D';
NET_NAME
'TP_CPLD1_PR9A'
 '@BASEBOARD_FAB2_LIB.BASEBOARD_FAB2(SCH_1):TP_CPLD1_PR9A':
 C_SIGNAL='@baseboard_fab2_lib.baseboard_fab2(sch_1):tp_cpld1_pr9a';
NODE_NAME     U8D7 J15
 '@BASEBOARD_FAB2_LIB.BASEBOARD_FAB2(SCH_1):PAGE191_I59@MSTR_MEMORY.LCMXO2_A(CHIPS)':
 'PR9A': CDS_PINID='PR9A';
NET_NAME
'TP_CPLD1_PR9C'
 '@BASEBOARD_FAB2_LIB.BASEBOARD_FAB2(SCH_1):TP_CPLD1_PR9C':
 C_SIGNAL='@baseboard_fab2_lib.baseboard_fab2(sch_1):tp_cpld1_pr9c';
NODE_NAME     U8D7 H11
 '@BASEBOARD_FAB2_LIB.BASEBOARD_FAB2(SCH_1):PAGE191_I59@MSTR_MEMORY.LCMXO2_A(CHIPS)':
 'PR9C': CDS_PINID='PR9C';
NET_NAME
'TP_CPLD1_PR9D'
 '@BASEBOARD_FAB2_LIB.BASEBOARD_FAB2(SCH_1):TP_CPLD1_PR9D':
 C_SIGNAL='@baseboard_fab2_lib.baseboard_fab2(sch_1):tp_cpld1_pr9d';
NODE_NAME     U8D7 J13
 '@BASEBOARD_FAB2_LIB.BASEBOARD_FAB2(SCH_1):PAGE191_I59@MSTR_MEMORY.LCMXO2_A(CHIPS)':
 'PR9D': CDS_PINID='PR9D';
NET_NAME
'TP_CPLD1_PT11A'
 '@BASEBOARD_FAB2_LIB.BASEBOARD_FAB2(SCH_1):TP_CPLD1_PT11A':
 C_SIGNAL='@baseboard_fab2_lib.baseboard_fab2(sch_1):tp_cpld1_pt11a';
NODE_NAME     U8D7 A5
 '@BASEBOARD_FAB2_LIB.BASEBOARD_FAB2(SCH_1):PAGE191_I59@MSTR_MEMORY.LCMXO2_A(CHIPS)':
 'PT11A': CDS_PINID='PT11A';
NET_NAME
'TP_CPLD1_PT11B'
 '@BASEBOARD_FAB2_LIB.BASEBOARD_FAB2(SCH_1):TP_CPLD1_PT11B':
 C_SIGNAL='@baseboard_fab2_lib.baseboard_fab2(sch_1):tp_cpld1_pt11b';
NODE_NAME     U8D7 B6
 '@BASEBOARD_FAB2_LIB.BASEBOARD_FAB2(SCH_1):PAGE191_I59@MSTR_MEMORY.LCMXO2_A(CHIPS)':
 'PT11B': CDS_PINID='PT11B';
NET_NAME
'TP_CPLD1_PT13A'
 '@BASEBOARD_FAB2_LIB.BASEBOARD_FAB2(SCH_1):TP_CPLD1_PT13A':
 C_SIGNAL='@baseboard_fab2_lib.baseboard_fab2(sch_1):tp_cpld1_pt13a';
NODE_NAME     U8D7 B7
 '@BASEBOARD_FAB2_LIB.BASEBOARD_FAB2(SCH_1):PAGE191_I59@MSTR_MEMORY.LCMXO2_A(CHIPS)':
 'PT13A': CDS_PINID='PT13A';
NET_NAME
'TP_CPLD1_PT16B'
 '@BASEBOARD_FAB2_LIB.BASEBOARD_FAB2(SCH_1):TP_CPLD1_PT16B':
 C_SIGNAL='@baseboard_fab2_lib.baseboard_fab2(sch_1):tp_cpld1_pt16b';
NODE_NAME     U8D7 E8
 '@BASEBOARD_FAB2_LIB.BASEBOARD_FAB2(SCH_1):PAGE191_I59@MSTR_MEMORY.LCMXO2_A(CHIPS)':
 'PT16B': CDS_PINID='PT16B';
NET_NAME
'TP_CPLD1_PT17B_PCLKC0_1'
 '@BASEBOARD_FAB2_LIB.BASEBOARD_FAB2(SCH_1):TP_CPLD1_PT17B_PCLKC0_1':
 C_SIGNAL='@baseboard_fab2_lib.baseboard_fab2(sch_1):tp_cpld1_pt17b_pclkc0_1';
NODE_NAME     U8D7 A8
 '@BASEBOARD_FAB2_LIB.BASEBOARD_FAB2(SCH_1):PAGE191_I59@MSTR_MEMORY.LCMXO2_A(CHIPS)':
 'PT17B_PCLKC0_1': CDS_PINID='PT17B_PCLKC0_1';
NET_NAME
'TP_CPLD1_PT17C'
 '@BASEBOARD_FAB2_LIB.BASEBOARD_FAB2(SCH_1):TP_CPLD1_PT17C':
 C_SIGNAL='@baseboard_fab2_lib.baseboard_fab2(sch_1):tp_cpld1_pt17c';
NODE_NAME     U8D7 D8
 '@BASEBOARD_FAB2_LIB.BASEBOARD_FAB2(SCH_1):PAGE191_I59@MSTR_MEMORY.LCMXO2_A(CHIPS)':
 'PT17C': CDS_PINID='PT17C';
NET_NAME
'TP_CPLD1_PT19D'
 '@BASEBOARD_FAB2_LIB.BASEBOARD_FAB2(SCH_1):TP_CPLD1_PT19D':
 C_SIGNAL='@baseboard_fab2_lib.baseboard_fab2(sch_1):tp_cpld1_pt19d';
NODE_NAME     U8D7 E11
 '@BASEBOARD_FAB2_LIB.BASEBOARD_FAB2(SCH_1):PAGE191_I59@MSTR_MEMORY.LCMXO2_A(CHIPS)':
 'PT19D': CDS_PINID='PT19D';
NET_NAME
'TP_CPLD1_PT20A'
 '@BASEBOARD_FAB2_LIB.BASEBOARD_FAB2(SCH_1):TP_CPLD1_PT20A':
 C_SIGNAL='@baseboard_fab2_lib.baseboard_fab2(sch_1):tp_cpld1_pt20a';
NODE_NAME     U8D7 D10
 '@BASEBOARD_FAB2_LIB.BASEBOARD_FAB2(SCH_1):PAGE191_I59@MSTR_MEMORY.LCMXO2_A(CHIPS)':
 'PT20A': CDS_PINID='PT20A';
NET_NAME
'TP_CPLD1_PT20B'
 '@BASEBOARD_FAB2_LIB.BASEBOARD_FAB2(SCH_1):TP_CPLD1_PT20B':
 C_SIGNAL='@baseboard_fab2_lib.baseboard_fab2(sch_1):tp_cpld1_pt20b';
NODE_NAME     U8D7 E10
 '@BASEBOARD_FAB2_LIB.BASEBOARD_FAB2(SCH_1):PAGE191_I59@MSTR_MEMORY.LCMXO2_A(CHIPS)':
 'PT20B': CDS_PINID='PT20B';
NET_NAME
'TP_CPLD1_PT22C'
 '@BASEBOARD_FAB2_LIB.BASEBOARD_FAB2(SCH_1):TP_CPLD1_PT22C':
 C_SIGNAL='@baseboard_fab2_lib.baseboard_fab2(sch_1):tp_cpld1_pt22c';
NODE_NAME     U8D7 B13
 '@BASEBOARD_FAB2_LIB.BASEBOARD_FAB2(SCH_1):PAGE191_I59@MSTR_MEMORY.LCMXO2_A(CHIPS)':
 'PT22C': CDS_PINID='PT22C';
NET_NAME
'TP_CPLD1_PT22D'
 '@BASEBOARD_FAB2_LIB.BASEBOARD_FAB2(SCH_1):TP_CPLD1_PT22D':
 C_SIGNAL='@baseboard_fab2_lib.baseboard_fab2(sch_1):tp_cpld1_pt22d';
NODE_NAME     U8D7 A14
 '@BASEBOARD_FAB2_LIB.BASEBOARD_FAB2(SCH_1):PAGE191_I59@MSTR_MEMORY.LCMXO2_A(CHIPS)':
 'PT22D': CDS_PINID='PT22D';
NET_NAME
'TP_CPLD1_PT24B'
 '@BASEBOARD_FAB2_LIB.BASEBOARD_FAB2(SCH_1):TP_CPLD1_PT24B':
 C_SIGNAL='@baseboard_fab2_lib.baseboard_fab2(sch_1):tp_cpld1_pt24b';
NODE_NAME     U8D7 A15
 '@BASEBOARD_FAB2_LIB.BASEBOARD_FAB2(SCH_1):PAGE191_I59@MSTR_MEMORY.LCMXO2_A(CHIPS)':
 'PT24B': CDS_PINID='PT24B';
NET_NAME
'TP_CPLD1_PT24C_INITN'
 '@BASEBOARD_FAB2_LIB.BASEBOARD_FAB2(SCH_1):TP_CPLD1_PT24C_INITN':
 C_SIGNAL='@baseboard_fab2_lib.baseboard_fab2(sch_1):tp_cpld1_pt24c_initn';
NODE_NAME     U8D7 A13
 '@BASEBOARD_FAB2_LIB.BASEBOARD_FAB2(SCH_1):PAGE191_I59@MSTR_MEMORY.LCMXO2_A(CHIPS)':
 'PT24C_INITN': CDS_PINID='PT24C_INITN';
NET_NAME
'TP_CPLD1_PT24D_DONE'
 '@BASEBOARD_FAB2_LIB.BASEBOARD_FAB2(SCH_1):TP_CPLD1_PT24D_DONE':
 C_SIGNAL='@baseboard_fab2_lib.baseboard_fab2(sch_1):tp_cpld1_pt24d_done';
NODE_NAME     U8D7 C13
 '@BASEBOARD_FAB2_LIB.BASEBOARD_FAB2(SCH_1):PAGE191_I59@MSTR_MEMORY.LCMXO2_A(CHIPS)':
 'PT24D_DONE': CDS_PINID='PT24D_DONE';
NET_NAME
'TP_CPU0_KTI2_AMONV'
 '@BASEBOARD_FAB2_LIB.BASEBOARD_FAB2(SCH_1):TP_CPU0_KTI2_AMONV':
 C_SIGNAL='@baseboard_fab2_lib.baseboard_fab2(sch_1):tp_cpu0_kti2_amonv';
NODE_NAME     U5D1 CN22
 '@BASEBOARD_FAB2_LIB.BASEBOARD_FAB2(SCH_1):PAGE39_I127@CHPSET_LIB.SKX_EXT_B(CHIPS)':
 'RSVD'<77>: CDS_PINID='RSVD(77)';
NET_NAME
'TP_CPU0_KTI2_DFX_DN'
 '@BASEBOARD_FAB2_LIB.BASEBOARD_FAB2(SCH_1):TP_CPU0_KTI2_DFX_DN':
 C_SIGNAL='@baseboard_fab2_lib.baseboard_fab2(sch_1):tp_cpu0_kti2_dfx_dn';
NODE_NAME     U5D1 CW22
 '@BASEBOARD_FAB2_LIB.BASEBOARD_FAB2(SCH_1):PAGE39_I127@CHPSET_LIB.SKX_EXT_B(CHIPS)':
 'RSVD'<63>: CDS_PINID='RSVD(63)';
NET_NAME
'TP_CPU0_PROCDIS_G_N'
 '@BASEBOARD_FAB2_LIB.BASEBOARD_FAB2(SCH_1):TP_CPU0_PROCDIS_G_N':
 C_SIGNAL='@baseboard_fab2_lib.baseboard_fab2(sch_1):tp_cpu0_procdis_g_n';
NODE_NAME     U5D1 AB17
 '@BASEBOARD_FAB2_LIB.BASEBOARD_FAB2(SCH_1):PAGE21_I259@CHPSET_LIB.SKX_EXT_B(CHIPS)':
 'PROCDIS_N': CDS_PINID='PROCDIS_N';
NET_NAME
'TP_CPU0_RSVD_0'
 '@BASEBOARD_FAB2_LIB.BASEBOARD_FAB2(SCH_1):TP_CPU0_RSVD_0':
 C_SIGNAL='@baseboard_fab2_lib.baseboard_fab2(sch_1):tp_cpu0_rsvd_0';
NODE_NAME     U5D1 EF83
 '@BASEBOARD_FAB2_LIB.BASEBOARD_FAB2(SCH_1):PAGE39_I127@CHPSET_LIB.SKX_EXT_B(CHIPS)':
 'RSVD'<0>: CDS_PINID='RSVD(0)';
NET_NAME
'TP_CPU0_RSVD_1'
 '@BASEBOARD_FAB2_LIB.BASEBOARD_FAB2(SCH_1):TP_CPU0_RSVD_1':
 C_SIGNAL='@baseboard_fab2_lib.baseboard_fab2(sch_1):tp_cpu0_rsvd_1';
NODE_NAME     U5D1 EF81
 '@BASEBOARD_FAB2_LIB.BASEBOARD_FAB2(SCH_1):PAGE39_I127@CHPSET_LIB.SKX_EXT_B(CHIPS)':
 'RSVD'<1>: CDS_PINID='RSVD(1)';
NET_NAME
'TP_CPU0_RSVD_10'
 '@BASEBOARD_FAB2_LIB.BASEBOARD_FAB2(SCH_1):TP_CPU0_RSVD_10':
 C_SIGNAL='@baseboard_fab2_lib.baseboard_fab2(sch_1):tp_cpu0_rsvd_10';
NODE_NAME     U5D1 ED5
 '@BASEBOARD_FAB2_LIB.BASEBOARD_FAB2(SCH_1):PAGE39_I127@CHPSET_LIB.SKX_EXT_B(CHIPS)':
 'RSVD'<10>: CDS_PINID='RSVD(10)';
NET_NAME
'TP_CPU0_RSVD_100'
 '@BASEBOARD_FAB2_LIB.BASEBOARD_FAB2(SCH_1):TP_CPU0_RSVD_100':
 C_SIGNAL='@baseboard_fab2_lib.baseboard_fab2(sch_1):tp_cpu0_rsvd_100';
NODE_NAME     U5D1 CF81
 '@BASEBOARD_FAB2_LIB.BASEBOARD_FAB2(SCH_1):PAGE36_I15@CHPSET_LIB.SKX_EXT_B(CHIPS)':
 'RSVD'<100>: CDS_PINID='RSVD(100)';
NET_NAME
'TP_CPU0_RSVD_101'
 '@BASEBOARD_FAB2_LIB.BASEBOARD_FAB2(SCH_1):TP_CPU0_RSVD_101':
 C_SIGNAL='@baseboard_fab2_lib.baseboard_fab2(sch_1):tp_cpu0_rsvd_101';
NODE_NAME     U5D1 CF79
 '@BASEBOARD_FAB2_LIB.BASEBOARD_FAB2(SCH_1):PAGE36_I15@CHPSET_LIB.SKX_EXT_B(CHIPS)':
 'RSVD'<101>: CDS_PINID='RSVD(101)';
NET_NAME
'TP_CPU0_RSVD_105'
 '@BASEBOARD_FAB2_LIB.BASEBOARD_FAB2(SCH_1):TP_CPU0_RSVD_105':
 C_SIGNAL='@baseboard_fab2_lib.baseboard_fab2(sch_1):tp_cpu0_rsvd_105';
NODE_NAME     U5D1 CE80
 '@BASEBOARD_FAB2_LIB.BASEBOARD_FAB2(SCH_1):PAGE36_I15@CHPSET_LIB.SKX_EXT_B(CHIPS)':
 'RSVD'<105>: CDS_PINID='RSVD(105)';
NET_NAME
'TP_CPU0_RSVD_106'
 '@BASEBOARD_FAB2_LIB.BASEBOARD_FAB2(SCH_1):TP_CPU0_RSVD_106':
 C_SIGNAL='@baseboard_fab2_lib.baseboard_fab2(sch_1):tp_cpu0_rsvd_106';
NODE_NAME     U5D1 CE78
 '@BASEBOARD_FAB2_LIB.BASEBOARD_FAB2(SCH_1):PAGE36_I15@CHPSET_LIB.SKX_EXT_B(CHIPS)':
 'RSVD'<106>: CDS_PINID='RSVD(106)';
NET_NAME
'TP_CPU0_RSVD_108'
 '@BASEBOARD_FAB2_LIB.BASEBOARD_FAB2(SCH_1):TP_CPU0_RSVD_108':
 C_SIGNAL='@baseboard_fab2_lib.baseboard_fab2(sch_1):tp_cpu0_rsvd_108';
NODE_NAME     U5D1 CD25
 '@BASEBOARD_FAB2_LIB.BASEBOARD_FAB2(SCH_1):PAGE36_I15@CHPSET_LIB.SKX_EXT_B(CHIPS)':
 'RSVD'<108>: CDS_PINID='RSVD(108)';
NET_NAME
'TP_CPU0_RSVD_11'
 '@BASEBOARD_FAB2_LIB.BASEBOARD_FAB2(SCH_1):TP_CPU0_RSVD_11':
 C_SIGNAL='@baseboard_fab2_lib.baseboard_fab2(sch_1):tp_cpu0_rsvd_11';
NODE_NAME     U5D1 ED45
 '@BASEBOARD_FAB2_LIB.BASEBOARD_FAB2(SCH_1):PAGE39_I127@CHPSET_LIB.SKX_EXT_B(CHIPS)':
 'RSVD'<11>: CDS_PINID='RSVD(11)';
NET_NAME
'TP_CPU0_RSVD_111'
 '@BASEBOARD_FAB2_LIB.BASEBOARD_FAB2(SCH_1):TP_CPU0_RSVD_111':
 C_SIGNAL='@baseboard_fab2_lib.baseboard_fab2(sch_1):tp_cpu0_rsvd_111';
NODE_NAME     U5D1 CC6
 '@BASEBOARD_FAB2_LIB.BASEBOARD_FAB2(SCH_1):PAGE36_I15@CHPSET_LIB.SKX_EXT_B(CHIPS)':
 'RSVD'<111>: CDS_PINID='RSVD(111)';
NET_NAME
'TP_CPU0_RSVD_113'
 '@BASEBOARD_FAB2_LIB.BASEBOARD_FAB2(SCH_1):TP_CPU0_RSVD_113':
 C_SIGNAL='@baseboard_fab2_lib.baseboard_fab2(sch_1):tp_cpu0_rsvd_113';
NODE_NAME     U5D1 CB5
 '@BASEBOARD_FAB2_LIB.BASEBOARD_FAB2(SCH_1):PAGE36_I15@CHPSET_LIB.SKX_EXT_B(CHIPS)':
 'RSVD'<113>: CDS_PINID='RSVD(113)';
NET_NAME
'TP_CPU0_RSVD_114'
 '@BASEBOARD_FAB2_LIB.BASEBOARD_FAB2(SCH_1):TP_CPU0_RSVD_114':
 C_SIGNAL='@baseboard_fab2_lib.baseboard_fab2(sch_1):tp_cpu0_rsvd_114';
NODE_NAME     U5D1 CB25
 '@BASEBOARD_FAB2_LIB.BASEBOARD_FAB2(SCH_1):PAGE36_I15@CHPSET_LIB.SKX_EXT_B(CHIPS)':
 'RSVD'<114>: CDS_PINID='RSVD(114)';
NET_NAME
'TP_CPU0_RSVD_117'
 '@BASEBOARD_FAB2_LIB.BASEBOARD_FAB2(SCH_1):TP_CPU0_RSVD_117':
 C_SIGNAL='@baseboard_fab2_lib.baseboard_fab2(sch_1):tp_cpu0_rsvd_117';
NODE_NAME     U5D1 CA24
 '@BASEBOARD_FAB2_LIB.BASEBOARD_FAB2(SCH_1):PAGE36_I15@CHPSET_LIB.SKX_EXT_B(CHIPS)':
 'RSVD'<117>: CDS_PINID='RSVD(117)';
NET_NAME
'TP_CPU0_RSVD_119'
 '@BASEBOARD_FAB2_LIB.BASEBOARD_FAB2(SCH_1):TP_CPU0_RSVD_119':
 C_SIGNAL='@baseboard_fab2_lib.baseboard_fab2(sch_1):tp_cpu0_rsvd_119';
NODE_NAME     U5D1 BY25
 '@BASEBOARD_FAB2_LIB.BASEBOARD_FAB2(SCH_1):PAGE36_I15@CHPSET_LIB.SKX_EXT_B(CHIPS)':
 'RSVD'<119>: CDS_PINID='RSVD(119)';
NET_NAME
'TP_CPU0_RSVD_12'
 '@BASEBOARD_FAB2_LIB.BASEBOARD_FAB2(SCH_1):TP_CPU0_RSVD_12':
 C_SIGNAL='@baseboard_fab2_lib.baseboard_fab2(sch_1):tp_cpu0_rsvd_12';
NODE_NAME     U5D1 EC84
 '@BASEBOARD_FAB2_LIB.BASEBOARD_FAB2(SCH_1):PAGE39_I127@CHPSET_LIB.SKX_EXT_B(CHIPS)':
 'RSVD'<12>: CDS_PINID='RSVD(12)';
NET_NAME
'TP_CPU0_RSVD_121'
 '@BASEBOARD_FAB2_LIB.BASEBOARD_FAB2(SCH_1):TP_CPU0_RSVD_121':
 C_SIGNAL='@baseboard_fab2_lib.baseboard_fab2(sch_1):tp_cpu0_rsvd_121';
NODE_NAME     U5D1 BW22
 '@BASEBOARD_FAB2_LIB.BASEBOARD_FAB2(SCH_1):PAGE36_I15@CHPSET_LIB.SKX_EXT_B(CHIPS)':
 'RSVD'<121>: CDS_PINID='RSVD(121)';
NET_NAME
'TP_CPU0_RSVD_123'
 '@BASEBOARD_FAB2_LIB.BASEBOARD_FAB2(SCH_1):TP_CPU0_RSVD_123':
 C_SIGNAL='@baseboard_fab2_lib.baseboard_fab2(sch_1):tp_cpu0_rsvd_123';
NODE_NAME     U5D1 BW10
 '@BASEBOARD_FAB2_LIB.BASEBOARD_FAB2(SCH_1):PAGE36_I15@CHPSET_LIB.SKX_EXT_B(CHIPS)':
 'RSVD'<123>: CDS_PINID='RSVD(123)';
NET_NAME
'TP_CPU0_RSVD_124'
 '@BASEBOARD_FAB2_LIB.BASEBOARD_FAB2(SCH_1):TP_CPU0_RSVD_124':
 C_SIGNAL='@baseboard_fab2_lib.baseboard_fab2(sch_1):tp_cpu0_rsvd_124';
NODE_NAME     U5D1 BV23
 '@BASEBOARD_FAB2_LIB.BASEBOARD_FAB2(SCH_1):PAGE36_I15@CHPSET_LIB.SKX_EXT_B(CHIPS)':
 'RSVD'<124>: CDS_PINID='RSVD(124)';
NET_NAME
'TP_CPU0_RSVD_13'
 '@BASEBOARD_FAB2_LIB.BASEBOARD_FAB2(SCH_1):TP_CPU0_RSVD_13':
 C_SIGNAL='@baseboard_fab2_lib.baseboard_fab2(sch_1):tp_cpu0_rsvd_13';
NODE_NAME     U5D1 EC44
 '@BASEBOARD_FAB2_LIB.BASEBOARD_FAB2(SCH_1):PAGE39_I127@CHPSET_LIB.SKX_EXT_B(CHIPS)':
 'RSVD'<13>: CDS_PINID='RSVD(13)';
NET_NAME
'TP_CPU0_RSVD_14'
 '@BASEBOARD_FAB2_LIB.BASEBOARD_FAB2(SCH_1):TP_CPU0_RSVD_14':
 C_SIGNAL='@baseboard_fab2_lib.baseboard_fab2(sch_1):tp_cpu0_rsvd_14';
NODE_NAME     U5D1 EC4
 '@BASEBOARD_FAB2_LIB.BASEBOARD_FAB2(SCH_1):PAGE39_I127@CHPSET_LIB.SKX_EXT_B(CHIPS)':
 'RSVD'<14>: CDS_PINID='RSVD(14)';
NET_NAME
'TP_CPU0_RSVD_144'
 '@BASEBOARD_FAB2_LIB.BASEBOARD_FAB2(SCH_1):TP_CPU0_RSVD_144':
 C_SIGNAL='@baseboard_fab2_lib.baseboard_fab2(sch_1):tp_cpu0_rsvd_144';
NODE_NAME     U5D1 BG20
 '@BASEBOARD_FAB2_LIB.BASEBOARD_FAB2(SCH_1):PAGE36_I15@CHPSET_LIB.SKX_EXT_B(CHIPS)':
 'RSVD'<144>: CDS_PINID='RSVD(144)';
NET_NAME
'TP_CPU0_RSVD_145'
 '@BASEBOARD_FAB2_LIB.BASEBOARD_FAB2(SCH_1):TP_CPU0_RSVD_145':
 C_SIGNAL='@baseboard_fab2_lib.baseboard_fab2(sch_1):tp_cpu0_rsvd_145';
NODE_NAME     U5D1 BG18
 '@BASEBOARD_FAB2_LIB.BASEBOARD_FAB2(SCH_1):PAGE36_I15@CHPSET_LIB.SKX_EXT_B(CHIPS)':
 'RSVD'<145>: CDS_PINID='RSVD(145)';
NET_NAME
'TP_CPU0_RSVD_146'
 '@BASEBOARD_FAB2_LIB.BASEBOARD_FAB2(SCH_1):TP_CPU0_RSVD_146':
 C_SIGNAL='@baseboard_fab2_lib.baseboard_fab2(sch_1):tp_cpu0_rsvd_146';
NODE_NAME     U5D1 BF21
 '@BASEBOARD_FAB2_LIB.BASEBOARD_FAB2(SCH_1):PAGE36_I15@CHPSET_LIB.SKX_EXT_B(CHIPS)':
 'RSVD'<146>: CDS_PINID='RSVD(146)';
NET_NAME
'TP_CPU0_RSVD_147'
 '@BASEBOARD_FAB2_LIB.BASEBOARD_FAB2(SCH_1):TP_CPU0_RSVD_147':
 C_SIGNAL='@baseboard_fab2_lib.baseboard_fab2(sch_1):tp_cpu0_rsvd_147';
NODE_NAME     U5D1 BE22
 '@BASEBOARD_FAB2_LIB.BASEBOARD_FAB2(SCH_1):PAGE36_I15@CHPSET_LIB.SKX_EXT_B(CHIPS)':
 'RSVD'<147>: CDS_PINID='RSVD(147)';
NET_NAME
'TP_CPU0_RSVD_148'
 '@BASEBOARD_FAB2_LIB.BASEBOARD_FAB2(SCH_1):TP_CPU0_RSVD_148':
 C_SIGNAL='@baseboard_fab2_lib.baseboard_fab2(sch_1):tp_cpu0_rsvd_148';
NODE_NAME     U5D1 BE20
 '@BASEBOARD_FAB2_LIB.BASEBOARD_FAB2(SCH_1):PAGE36_I15@CHPSET_LIB.SKX_EXT_B(CHIPS)':
 'RSVD'<148>: CDS_PINID='RSVD(148)';
NET_NAME
'TP_CPU0_RSVD_149'
 '@BASEBOARD_FAB2_LIB.BASEBOARD_FAB2(SCH_1):TP_CPU0_RSVD_149':
 C_SIGNAL='@baseboard_fab2_lib.baseboard_fab2(sch_1):tp_cpu0_rsvd_149';
NODE_NAME     U5D1 BE18
 '@BASEBOARD_FAB2_LIB.BASEBOARD_FAB2(SCH_1):PAGE36_I15@CHPSET_LIB.SKX_EXT_B(CHIPS)':
 'RSVD'<149>: CDS_PINID='RSVD(149)';
NET_NAME
'TP_CPU0_RSVD_15'
 '@BASEBOARD_FAB2_LIB.BASEBOARD_FAB2(SCH_1):TP_CPU0_RSVD_15':
 C_SIGNAL='@baseboard_fab2_lib.baseboard_fab2(sch_1):tp_cpu0_rsvd_15';
NODE_NAME     U5D1 EC16
 '@BASEBOARD_FAB2_LIB.BASEBOARD_FAB2(SCH_1):PAGE39_I127@CHPSET_LIB.SKX_EXT_B(CHIPS)':
 'RSVD'<15>: CDS_PINID='RSVD(15)';
NET_NAME
'TP_CPU0_RSVD_150'
 '@BASEBOARD_FAB2_LIB.BASEBOARD_FAB2(SCH_1):TP_CPU0_RSVD_150':
 C_SIGNAL='@baseboard_fab2_lib.baseboard_fab2(sch_1):tp_cpu0_rsvd_150';
NODE_NAME     U5D1 BD69
 '@BASEBOARD_FAB2_LIB.BASEBOARD_FAB2(SCH_1):PAGE36_I15@CHPSET_LIB.SKX_EXT_B(CHIPS)':
 'RSVD'<150>: CDS_PINID='RSVD(150)';
NET_NAME
'TP_CPU0_RSVD_151'
 '@BASEBOARD_FAB2_LIB.BASEBOARD_FAB2(SCH_1):TP_CPU0_RSVD_151':
 C_SIGNAL='@baseboard_fab2_lib.baseboard_fab2(sch_1):tp_cpu0_rsvd_151';
NODE_NAME     U5D1 BD67
 '@BASEBOARD_FAB2_LIB.BASEBOARD_FAB2(SCH_1):PAGE36_I15@CHPSET_LIB.SKX_EXT_B(CHIPS)':
 'RSVD'<151>: CDS_PINID='RSVD(151)';
NET_NAME
'TP_CPU0_RSVD_152'
 '@BASEBOARD_FAB2_LIB.BASEBOARD_FAB2(SCH_1):TP_CPU0_RSVD_152':
 C_SIGNAL='@baseboard_fab2_lib.baseboard_fab2(sch_1):tp_cpu0_rsvd_152';
NODE_NAME     U5D1 BD65
 '@BASEBOARD_FAB2_LIB.BASEBOARD_FAB2(SCH_1):PAGE36_I15@CHPSET_LIB.SKX_EXT_B(CHIPS)':
 'RSVD'<152>: CDS_PINID='RSVD(152)';
NET_NAME
'TP_CPU0_RSVD_154'
 '@BASEBOARD_FAB2_LIB.BASEBOARD_FAB2(SCH_1):TP_CPU0_RSVD_154':
 C_SIGNAL='@baseboard_fab2_lib.baseboard_fab2(sch_1):tp_cpu0_rsvd_154';
NODE_NAME     U5D1 BD19
 '@BASEBOARD_FAB2_LIB.BASEBOARD_FAB2(SCH_1):PAGE36_I15@CHPSET_LIB.SKX_EXT_B(CHIPS)':
 'RSVD'<154>: CDS_PINID='RSVD(154)';
NET_NAME
'TP_CPU0_RSVD_155'
 '@BASEBOARD_FAB2_LIB.BASEBOARD_FAB2(SCH_1):TP_CPU0_RSVD_155':
 C_SIGNAL='@baseboard_fab2_lib.baseboard_fab2(sch_1):tp_cpu0_rsvd_155';
NODE_NAME     U5D1 BD17
 '@BASEBOARD_FAB2_LIB.BASEBOARD_FAB2(SCH_1):PAGE36_I15@CHPSET_LIB.SKX_EXT_B(CHIPS)':
 'RSVD'<155>: CDS_PINID='RSVD(155)';
NET_NAME
'TP_CPU0_RSVD_156'
 '@BASEBOARD_FAB2_LIB.BASEBOARD_FAB2(SCH_1):TP_CPU0_RSVD_156':
 C_SIGNAL='@baseboard_fab2_lib.baseboard_fab2(sch_1):tp_cpu0_rsvd_156';
NODE_NAME     U5D1 BC68
 '@BASEBOARD_FAB2_LIB.BASEBOARD_FAB2(SCH_1):PAGE36_I15@CHPSET_LIB.SKX_EXT_B(CHIPS)':
 'RSVD'<156>: CDS_PINID='RSVD(156)';
NET_NAME
'TP_CPU0_RSVD_157'
 '@BASEBOARD_FAB2_LIB.BASEBOARD_FAB2(SCH_1):TP_CPU0_RSVD_157':
 C_SIGNAL='@baseboard_fab2_lib.baseboard_fab2(sch_1):tp_cpu0_rsvd_157';
NODE_NAME     U5D1 BC66
 '@BASEBOARD_FAB2_LIB.BASEBOARD_FAB2(SCH_1):PAGE36_I15@CHPSET_LIB.SKX_EXT_B(CHIPS)':
 'RSVD'<157>: CDS_PINID='RSVD(157)';
NET_NAME
'TP_CPU0_RSVD_158'
 '@BASEBOARD_FAB2_LIB.BASEBOARD_FAB2(SCH_1):TP_CPU0_RSVD_158':
 C_SIGNAL='@baseboard_fab2_lib.baseboard_fab2(sch_1):tp_cpu0_rsvd_158';
NODE_NAME     U5D1 BC64
 '@BASEBOARD_FAB2_LIB.BASEBOARD_FAB2(SCH_1):PAGE36_I15@CHPSET_LIB.SKX_EXT_B(CHIPS)':
 'RSVD'<158>: CDS_PINID='RSVD(158)';
NET_NAME
'TP_CPU0_RSVD_159'
 '@BASEBOARD_FAB2_LIB.BASEBOARD_FAB2(SCH_1):TP_CPU0_RSVD_159':
 C_SIGNAL='@baseboard_fab2_lib.baseboard_fab2(sch_1):tp_cpu0_rsvd_159';
NODE_NAME     U5D1 BC22
 '@BASEBOARD_FAB2_LIB.BASEBOARD_FAB2(SCH_1):PAGE36_I15@CHPSET_LIB.SKX_EXT_B(CHIPS)':
 'RSVD'<159>: CDS_PINID='RSVD(159)';
NET_NAME
'TP_CPU0_RSVD_16'
 '@BASEBOARD_FAB2_LIB.BASEBOARD_FAB2(SCH_1):TP_CPU0_RSVD_16':
 C_SIGNAL='@baseboard_fab2_lib.baseboard_fab2(sch_1):tp_cpu0_rsvd_16';
NODE_NAME     U5D1 EB85
 '@BASEBOARD_FAB2_LIB.BASEBOARD_FAB2(SCH_1):PAGE39_I127@CHPSET_LIB.SKX_EXT_B(CHIPS)':
 'RSVD'<16>: CDS_PINID='RSVD(16)';
NET_NAME
'TP_CPU0_RSVD_160'
 '@BASEBOARD_FAB2_LIB.BASEBOARD_FAB2(SCH_1):TP_CPU0_RSVD_160':
 C_SIGNAL='@baseboard_fab2_lib.baseboard_fab2(sch_1):tp_cpu0_rsvd_160';
NODE_NAME     U5D1 BC20
 '@BASEBOARD_FAB2_LIB.BASEBOARD_FAB2(SCH_1):PAGE36_I15@CHPSET_LIB.SKX_EXT_B(CHIPS)':
 'RSVD'<160>: CDS_PINID='RSVD(160)';
NET_NAME
'TP_CPU0_RSVD_161'
 '@BASEBOARD_FAB2_LIB.BASEBOARD_FAB2(SCH_1):TP_CPU0_RSVD_161':
 C_SIGNAL='@baseboard_fab2_lib.baseboard_fab2(sch_1):tp_cpu0_rsvd_161';
NODE_NAME     U5D1 BC18
 '@BASEBOARD_FAB2_LIB.BASEBOARD_FAB2(SCH_1):PAGE36_I15@CHPSET_LIB.SKX_EXT_B(CHIPS)':
 'RSVD'<161>: CDS_PINID='RSVD(161)';
NET_NAME
'TP_CPU0_RSVD_162'
 '@BASEBOARD_FAB2_LIB.BASEBOARD_FAB2(SCH_1):TP_CPU0_RSVD_162':
 C_SIGNAL='@baseboard_fab2_lib.baseboard_fab2(sch_1):tp_cpu0_rsvd_162';
NODE_NAME     U5D1 BC14
 '@BASEBOARD_FAB2_LIB.BASEBOARD_FAB2(SCH_1):PAGE36_I15@CHPSET_LIB.SKX_EXT_B(CHIPS)':
 'RSVD'<162>: CDS_PINID='RSVD(162)';
NET_NAME
'TP_CPU0_RSVD_163'
 '@BASEBOARD_FAB2_LIB.BASEBOARD_FAB2(SCH_1):TP_CPU0_RSVD_163':
 C_SIGNAL='@baseboard_fab2_lib.baseboard_fab2(sch_1):tp_cpu0_rsvd_163';
NODE_NAME     U5D1 BB67
 '@BASEBOARD_FAB2_LIB.BASEBOARD_FAB2(SCH_1):PAGE36_I15@CHPSET_LIB.SKX_EXT_B(CHIPS)':
 'RSVD'<163>: CDS_PINID='RSVD(163)';
NET_NAME
'TP_CPU0_RSVD_164'
 '@BASEBOARD_FAB2_LIB.BASEBOARD_FAB2(SCH_1):TP_CPU0_RSVD_164':
 C_SIGNAL='@baseboard_fab2_lib.baseboard_fab2(sch_1):tp_cpu0_rsvd_164';
NODE_NAME     U5D1 BB65
 '@BASEBOARD_FAB2_LIB.BASEBOARD_FAB2(SCH_1):PAGE36_I15@CHPSET_LIB.SKX_EXT_B(CHIPS)':
 'RSVD'<164>: CDS_PINID='RSVD(164)';
NET_NAME
'TP_CPU0_RSVD_166'
 '@BASEBOARD_FAB2_LIB.BASEBOARD_FAB2(SCH_1):TP_CPU0_RSVD_166':
 C_SIGNAL='@baseboard_fab2_lib.baseboard_fab2(sch_1):tp_cpu0_rsvd_166';
NODE_NAME     U5D1 BB21
 '@BASEBOARD_FAB2_LIB.BASEBOARD_FAB2(SCH_1):PAGE36_I15@CHPSET_LIB.SKX_EXT_B(CHIPS)':
 'RSVD'<166>: CDS_PINID='RSVD(166)';
NET_NAME
'TP_CPU0_RSVD_167'
 '@BASEBOARD_FAB2_LIB.BASEBOARD_FAB2(SCH_1):TP_CPU0_RSVD_167':
 C_SIGNAL='@baseboard_fab2_lib.baseboard_fab2(sch_1):tp_cpu0_rsvd_167';
NODE_NAME     U5D1 BB17
 '@BASEBOARD_FAB2_LIB.BASEBOARD_FAB2(SCH_1):PAGE36_I15@CHPSET_LIB.SKX_EXT_B(CHIPS)':
 'RSVD'<167>: CDS_PINID='RSVD(167)';
NET_NAME
'TP_CPU0_RSVD_168'
 '@BASEBOARD_FAB2_LIB.BASEBOARD_FAB2(SCH_1):TP_CPU0_RSVD_168':
 C_SIGNAL='@baseboard_fab2_lib.baseboard_fab2(sch_1):tp_cpu0_rsvd_168';
NODE_NAME     U5D1 BB15
 '@BASEBOARD_FAB2_LIB.BASEBOARD_FAB2(SCH_1):PAGE36_I15@CHPSET_LIB.SKX_EXT_B(CHIPS)':
 'RSVD'<168>: CDS_PINID='RSVD(168)';
NET_NAME
'TP_CPU0_RSVD_169'
 '@BASEBOARD_FAB2_LIB.BASEBOARD_FAB2(SCH_1):TP_CPU0_RSVD_169':
 C_SIGNAL='@baseboard_fab2_lib.baseboard_fab2(sch_1):tp_cpu0_rsvd_169';
NODE_NAME     U5D1 BB13
 '@BASEBOARD_FAB2_LIB.BASEBOARD_FAB2(SCH_1):PAGE36_I15@CHPSET_LIB.SKX_EXT_B(CHIPS)':
 'RSVD'<169>: CDS_PINID='RSVD(169)';
NET_NAME
'TP_CPU0_RSVD_17'
 '@BASEBOARD_FAB2_LIB.BASEBOARD_FAB2(SCH_1):TP_CPU0_RSVD_17':
 C_SIGNAL='@baseboard_fab2_lib.baseboard_fab2(sch_1):tp_cpu0_rsvd_17';
NODE_NAME     U5D1 EB5
 '@BASEBOARD_FAB2_LIB.BASEBOARD_FAB2(SCH_1):PAGE39_I127@CHPSET_LIB.SKX_EXT_B(CHIPS)':
 'RSVD'<17>: CDS_PINID='RSVD(17)';
NET_NAME
'TP_CPU0_RSVD_170'
 '@BASEBOARD_FAB2_LIB.BASEBOARD_FAB2(SCH_1):TP_CPU0_RSVD_170':
 C_SIGNAL='@baseboard_fab2_lib.baseboard_fab2(sch_1):tp_cpu0_rsvd_170';
NODE_NAME     U5D1 BA82
 '@BASEBOARD_FAB2_LIB.BASEBOARD_FAB2(SCH_1):PAGE36_I15@CHPSET_LIB.SKX_EXT_B(CHIPS)':
 'RSVD'<170>: CDS_PINID='RSVD(170)';
NET_NAME
'TP_CPU0_RSVD_171'
 '@BASEBOARD_FAB2_LIB.BASEBOARD_FAB2(SCH_1):TP_CPU0_RSVD_171':
 C_SIGNAL='@baseboard_fab2_lib.baseboard_fab2(sch_1):tp_cpu0_rsvd_171';
NODE_NAME     U5D1 BA78
 '@BASEBOARD_FAB2_LIB.BASEBOARD_FAB2(SCH_1):PAGE36_I15@CHPSET_LIB.SKX_EXT_B(CHIPS)':
 'RSVD'<171>: CDS_PINID='RSVD(171)';
NET_NAME
'TP_CPU0_RSVD_172'
 '@BASEBOARD_FAB2_LIB.BASEBOARD_FAB2(SCH_1):TP_CPU0_RSVD_172':
 C_SIGNAL='@baseboard_fab2_lib.baseboard_fab2(sch_1):tp_cpu0_rsvd_172';
NODE_NAME     U5D1 BA76
 '@BASEBOARD_FAB2_LIB.BASEBOARD_FAB2(SCH_1):PAGE29_I61@CHPSET_LIB.SKX_EXT_B(CHIPS)':
 'RSVD'<172>: CDS_PINID='RSVD(172)';
NET_NAME
'TP_CPU0_RSVD_173'
 '@BASEBOARD_FAB2_LIB.BASEBOARD_FAB2(SCH_1):TP_CPU0_RSVD_173':
 C_SIGNAL='@baseboard_fab2_lib.baseboard_fab2(sch_1):tp_cpu0_rsvd_173';
NODE_NAME     U5D1 BA66
 '@BASEBOARD_FAB2_LIB.BASEBOARD_FAB2(SCH_1):PAGE29_I61@CHPSET_LIB.SKX_EXT_B(CHIPS)':
 'RSVD'<173>: CDS_PINID='RSVD(173)';
NET_NAME
'TP_CPU0_RSVD_174'
 '@BASEBOARD_FAB2_LIB.BASEBOARD_FAB2(SCH_1):TP_CPU0_RSVD_174':
 C_SIGNAL='@baseboard_fab2_lib.baseboard_fab2(sch_1):tp_cpu0_rsvd_174';
NODE_NAME     U5D1 BA64
 '@BASEBOARD_FAB2_LIB.BASEBOARD_FAB2(SCH_1):PAGE29_I61@CHPSET_LIB.SKX_EXT_B(CHIPS)':
 'RSVD'<174>: CDS_PINID='RSVD(174)';
NET_NAME
'TP_CPU0_RSVD_175'
 '@BASEBOARD_FAB2_LIB.BASEBOARD_FAB2(SCH_1):TP_CPU0_RSVD_175':
 C_SIGNAL='@baseboard_fab2_lib.baseboard_fab2(sch_1):tp_cpu0_rsvd_175';
NODE_NAME     U5D1 BA22
 '@BASEBOARD_FAB2_LIB.BASEBOARD_FAB2(SCH_1):PAGE29_I61@CHPSET_LIB.SKX_EXT_B(CHIPS)':
 'RSVD'<175>: CDS_PINID='RSVD(175)';
NET_NAME
'TP_CPU0_RSVD_176'
 '@BASEBOARD_FAB2_LIB.BASEBOARD_FAB2(SCH_1):TP_CPU0_RSVD_176':
 C_SIGNAL='@baseboard_fab2_lib.baseboard_fab2(sch_1):tp_cpu0_rsvd_176';
NODE_NAME     U5D1 BA18
 '@BASEBOARD_FAB2_LIB.BASEBOARD_FAB2(SCH_1):PAGE29_I61@CHPSET_LIB.SKX_EXT_B(CHIPS)':
 'RSVD'<176>: CDS_PINID='RSVD(176)';
NET_NAME
'TP_CPU0_RSVD_177'
 '@BASEBOARD_FAB2_LIB.BASEBOARD_FAB2(SCH_1):TP_CPU0_RSVD_177':
 C_SIGNAL='@baseboard_fab2_lib.baseboard_fab2(sch_1):tp_cpu0_rsvd_177';
NODE_NAME     U5D1 BA16
 '@BASEBOARD_FAB2_LIB.BASEBOARD_FAB2(SCH_1):PAGE29_I61@CHPSET_LIB.SKX_EXT_B(CHIPS)':
 'RSVD'<177>: CDS_PINID='RSVD(177)';
NET_NAME
'TP_CPU0_RSVD_178'
 '@BASEBOARD_FAB2_LIB.BASEBOARD_FAB2(SCH_1):TP_CPU0_RSVD_178':
 C_SIGNAL='@baseboard_fab2_lib.baseboard_fab2(sch_1):tp_cpu0_rsvd_178';
NODE_NAME     U5D1 BA14
 '@BASEBOARD_FAB2_LIB.BASEBOARD_FAB2(SCH_1):PAGE29_I61@CHPSET_LIB.SKX_EXT_B(CHIPS)':
 'RSVD'<178>: CDS_PINID='RSVD(178)';
NET_NAME
'TP_CPU0_RSVD_179'
 '@BASEBOARD_FAB2_LIB.BASEBOARD_FAB2(SCH_1):TP_CPU0_RSVD_179':
 C_SIGNAL='@baseboard_fab2_lib.baseboard_fab2(sch_1):tp_cpu0_rsvd_179';
NODE_NAME     U5D1 AY77
 '@BASEBOARD_FAB2_LIB.BASEBOARD_FAB2(SCH_1):PAGE29_I61@CHPSET_LIB.SKX_EXT_B(CHIPS)':
 'RSVD'<179>: CDS_PINID='RSVD(179)';
NET_NAME
'TP_CPU0_RSVD_18'
 '@BASEBOARD_FAB2_LIB.BASEBOARD_FAB2(SCH_1):TP_CPU0_RSVD_18':
 C_SIGNAL='@baseboard_fab2_lib.baseboard_fab2(sch_1):tp_cpu0_rsvd_18';
NODE_NAME     U5D1 EB3
 '@BASEBOARD_FAB2_LIB.BASEBOARD_FAB2(SCH_1):PAGE39_I127@CHPSET_LIB.SKX_EXT_B(CHIPS)':
 'RSVD'<18>: CDS_PINID='RSVD(18)';
NET_NAME
'TP_CPU0_RSVD_180'
 '@BASEBOARD_FAB2_LIB.BASEBOARD_FAB2(SCH_1):TP_CPU0_RSVD_180':
 C_SIGNAL='@baseboard_fab2_lib.baseboard_fab2(sch_1):tp_cpu0_rsvd_180';
NODE_NAME     U5D1 AY75
 '@BASEBOARD_FAB2_LIB.BASEBOARD_FAB2(SCH_1):PAGE29_I61@CHPSET_LIB.SKX_EXT_B(CHIPS)':
 'RSVD'<180>: CDS_PINID='RSVD(180)';
NET_NAME
'TP_CPU0_RSVD_181'
 '@BASEBOARD_FAB2_LIB.BASEBOARD_FAB2(SCH_1):TP_CPU0_RSVD_181':
 C_SIGNAL='@baseboard_fab2_lib.baseboard_fab2(sch_1):tp_cpu0_rsvd_181';
NODE_NAME     U5D1 AY67
 '@BASEBOARD_FAB2_LIB.BASEBOARD_FAB2(SCH_1):PAGE29_I61@CHPSET_LIB.SKX_EXT_B(CHIPS)':
 'RSVD'<181>: CDS_PINID='RSVD(181)';
NET_NAME
'TP_CPU0_RSVD_182'
 '@BASEBOARD_FAB2_LIB.BASEBOARD_FAB2(SCH_1):TP_CPU0_RSVD_182':
 C_SIGNAL='@baseboard_fab2_lib.baseboard_fab2(sch_1):tp_cpu0_rsvd_182';
NODE_NAME     U5D1 AY65
 '@BASEBOARD_FAB2_LIB.BASEBOARD_FAB2(SCH_1):PAGE29_I61@CHPSET_LIB.SKX_EXT_B(CHIPS)':
 'RSVD'<182>: CDS_PINID='RSVD(182)';
NET_NAME
'TP_CPU0_RSVD_183'
 '@BASEBOARD_FAB2_LIB.BASEBOARD_FAB2(SCH_1):TP_CPU0_RSVD_183':
 C_SIGNAL='@baseboard_fab2_lib.baseboard_fab2(sch_1):tp_cpu0_rsvd_183';
NODE_NAME     U5D1 AW76
 '@BASEBOARD_FAB2_LIB.BASEBOARD_FAB2(SCH_1):PAGE29_I61@CHPSET_LIB.SKX_EXT_B(CHIPS)':
 'RSVD'<183>: CDS_PINID='RSVD(183)';
NET_NAME
'TP_CPU0_RSVD_184'
 '@BASEBOARD_FAB2_LIB.BASEBOARD_FAB2(SCH_1):TP_CPU0_RSVD_184':
 C_SIGNAL='@baseboard_fab2_lib.baseboard_fab2(sch_1):tp_cpu0_rsvd_184';
NODE_NAME     U5D1 AW64
 '@BASEBOARD_FAB2_LIB.BASEBOARD_FAB2(SCH_1):PAGE29_I61@CHPSET_LIB.SKX_EXT_B(CHIPS)':
 'RSVD'<184>: CDS_PINID='RSVD(184)';
NET_NAME
'TP_CPU0_RSVD_186'
 '@BASEBOARD_FAB2_LIB.BASEBOARD_FAB2(SCH_1):TP_CPU0_RSVD_186':
 C_SIGNAL='@baseboard_fab2_lib.baseboard_fab2(sch_1):tp_cpu0_rsvd_186';
NODE_NAME     U5D1 AV77
 '@BASEBOARD_FAB2_LIB.BASEBOARD_FAB2(SCH_1):PAGE29_I61@CHPSET_LIB.SKX_EXT_B(CHIPS)':
 'RSVD'<186>: CDS_PINID='RSVD(186)';
NET_NAME
'TP_CPU0_RSVD_189'
 '@BASEBOARD_FAB2_LIB.BASEBOARD_FAB2(SCH_1):TP_CPU0_RSVD_189':
 C_SIGNAL='@baseboard_fab2_lib.baseboard_fab2(sch_1):tp_cpu0_rsvd_189';
NODE_NAME     U5D1 AT13
 '@BASEBOARD_FAB2_LIB.BASEBOARD_FAB2(SCH_1):PAGE29_I61@CHPSET_LIB.SKX_EXT_B(CHIPS)':
 'RSVD'<189>: CDS_PINID='RSVD(189)';
NET_NAME
'TP_CPU0_RSVD_19'
 '@BASEBOARD_FAB2_LIB.BASEBOARD_FAB2(SCH_1):TP_CPU0_RSVD_19':
 C_SIGNAL='@baseboard_fab2_lib.baseboard_fab2(sch_1):tp_cpu0_rsvd_19';
NODE_NAME     U5D1 EA44
 '@BASEBOARD_FAB2_LIB.BASEBOARD_FAB2(SCH_1):PAGE39_I127@CHPSET_LIB.SKX_EXT_B(CHIPS)':
 'RSVD'<19>: CDS_PINID='RSVD(19)';
NET_NAME
'TP_CPU0_RSVD_190'
 '@BASEBOARD_FAB2_LIB.BASEBOARD_FAB2(SCH_1):TP_CPU0_RSVD_190':
 C_SIGNAL='@baseboard_fab2_lib.baseboard_fab2(sch_1):tp_cpu0_rsvd_190';
NODE_NAME     U5D1 AR62
 '@BASEBOARD_FAB2_LIB.BASEBOARD_FAB2(SCH_1):PAGE29_I61@CHPSET_LIB.SKX_EXT_B(CHIPS)':
 'RSVD'<190>: CDS_PINID='RSVD(190)';
NET_NAME
'TP_CPU0_RSVD_194'
 '@BASEBOARD_FAB2_LIB.BASEBOARD_FAB2(SCH_1):TP_CPU0_RSVD_194':
 C_SIGNAL='@baseboard_fab2_lib.baseboard_fab2(sch_1):tp_cpu0_rsvd_194';
NODE_NAME     U5D1 AP61
 '@BASEBOARD_FAB2_LIB.BASEBOARD_FAB2(SCH_1):PAGE22_I204@CHPSET_LIB.SKX_EXT_B(CHIPS)':
 'RSVD'<194>: CDS_PINID='RSVD(194)';
NET_NAME
'TP_CPU0_RSVD_198'
 '@BASEBOARD_FAB2_LIB.BASEBOARD_FAB2(SCH_1):TP_CPU0_RSVD_198':
 C_SIGNAL='@baseboard_fab2_lib.baseboard_fab2(sch_1):tp_cpu0_rsvd_198';
NODE_NAME     U5D1 AN62
 '@BASEBOARD_FAB2_LIB.BASEBOARD_FAB2(SCH_1):PAGE22_I204@CHPSET_LIB.SKX_EXT_B(CHIPS)':
 'RSVD'<198>: CDS_PINID='RSVD(198)';
NET_NAME
'TP_CPU0_RSVD_199'
 '@BASEBOARD_FAB2_LIB.BASEBOARD_FAB2(SCH_1):TP_CPU0_RSVD_199':
 C_SIGNAL='@baseboard_fab2_lib.baseboard_fab2(sch_1):tp_cpu0_rsvd_199';
NODE_NAME     U5D1 AN60
 '@BASEBOARD_FAB2_LIB.BASEBOARD_FAB2(SCH_1):PAGE22_I204@CHPSET_LIB.SKX_EXT_B(CHIPS)':
 'RSVD'<199>: CDS_PINID='RSVD(199)';
NET_NAME
'TP_CPU0_RSVD_2'
 '@BASEBOARD_FAB2_LIB.BASEBOARD_FAB2(SCH_1):TP_CPU0_RSVD_2':
 C_SIGNAL='@baseboard_fab2_lib.baseboard_fab2(sch_1):tp_cpu0_rsvd_2';
NODE_NAME     U5D1 EF77
 '@BASEBOARD_FAB2_LIB.BASEBOARD_FAB2(SCH_1):PAGE39_I127@CHPSET_LIB.SKX_EXT_B(CHIPS)':
 'RSVD'<2>: CDS_PINID='RSVD(2)';
NET_NAME
'TP_CPU0_RSVD_20'
 '@BASEBOARD_FAB2_LIB.BASEBOARD_FAB2(SCH_1):TP_CPU0_RSVD_20':
 C_SIGNAL='@baseboard_fab2_lib.baseboard_fab2(sch_1):tp_cpu0_rsvd_20';
NODE_NAME     U5D1 EA4
 '@BASEBOARD_FAB2_LIB.BASEBOARD_FAB2(SCH_1):PAGE39_I127@CHPSET_LIB.SKX_EXT_B(CHIPS)':
 'RSVD'<20>: CDS_PINID='RSVD(20)';
NET_NAME
'TP_CPU0_RSVD_204'
 '@BASEBOARD_FAB2_LIB.BASEBOARD_FAB2(SCH_1):TP_CPU0_RSVD_204':
 C_SIGNAL='@baseboard_fab2_lib.baseboard_fab2(sch_1):tp_cpu0_rsvd_204';
NODE_NAME     U5D1 AM61
 '@BASEBOARD_FAB2_LIB.BASEBOARD_FAB2(SCH_1):PAGE22_I204@CHPSET_LIB.SKX_EXT_B(CHIPS)':
 'RSVD'<204>: CDS_PINID='RSVD(204)';
NET_NAME
'TP_CPU0_RSVD_205'
 '@BASEBOARD_FAB2_LIB.BASEBOARD_FAB2(SCH_1):TP_CPU0_RSVD_205':
 C_SIGNAL='@baseboard_fab2_lib.baseboard_fab2(sch_1):tp_cpu0_rsvd_205';
NODE_NAME     U5D1 AM59
 '@BASEBOARD_FAB2_LIB.BASEBOARD_FAB2(SCH_1):PAGE22_I204@CHPSET_LIB.SKX_EXT_B(CHIPS)':
 'RSVD'<205>: CDS_PINID='RSVD(205)';
NET_NAME
'TP_CPU0_RSVD_208'
 '@BASEBOARD_FAB2_LIB.BASEBOARD_FAB2(SCH_1):TP_CPU0_RSVD_208':
 C_SIGNAL='@baseboard_fab2_lib.baseboard_fab2(sch_1):tp_cpu0_rsvd_208';
NODE_NAME     U5D1 AM23
 '@BASEBOARD_FAB2_LIB.BASEBOARD_FAB2(SCH_1):PAGE22_I204@CHPSET_LIB.SKX_EXT_B(CHIPS)':
 'RSVD'<208>: CDS_PINID='RSVD(208)';
NET_NAME
'TP_CPU0_RSVD_21'
 '@BASEBOARD_FAB2_LIB.BASEBOARD_FAB2(SCH_1):TP_CPU0_RSVD_21':
 C_SIGNAL='@baseboard_fab2_lib.baseboard_fab2(sch_1):tp_cpu0_rsvd_21';
NODE_NAME     U5D1 DY3
 '@BASEBOARD_FAB2_LIB.BASEBOARD_FAB2(SCH_1):PAGE39_I127@CHPSET_LIB.SKX_EXT_B(CHIPS)':
 'RSVD'<21>: CDS_PINID='RSVD(21)';
NET_NAME
'TP_CPU0_RSVD_210'
 '@BASEBOARD_FAB2_LIB.BASEBOARD_FAB2(SCH_1):TP_CPU0_RSVD_210':
 C_SIGNAL='@baseboard_fab2_lib.baseboard_fab2(sch_1):tp_cpu0_rsvd_210';
NODE_NAME     U5D1 AL62
 '@BASEBOARD_FAB2_LIB.BASEBOARD_FAB2(SCH_1):PAGE22_I204@CHPSET_LIB.SKX_EXT_B(CHIPS)':
 'RSVD'<210>: CDS_PINID='RSVD(210)';
NET_NAME
'TP_CPU0_RSVD_211'
 '@BASEBOARD_FAB2_LIB.BASEBOARD_FAB2(SCH_1):TP_CPU0_RSVD_211':
 C_SIGNAL='@baseboard_fab2_lib.baseboard_fab2(sch_1):tp_cpu0_rsvd_211';
NODE_NAME     U5D1 AL60
 '@BASEBOARD_FAB2_LIB.BASEBOARD_FAB2(SCH_1):PAGE22_I204@CHPSET_LIB.SKX_EXT_B(CHIPS)':
 'RSVD'<211>: CDS_PINID='RSVD(211)';
NET_NAME
'TP_CPU0_RSVD_212'
 '@BASEBOARD_FAB2_LIB.BASEBOARD_FAB2(SCH_1):TP_CPU0_RSVD_212':
 C_SIGNAL='@baseboard_fab2_lib.baseboard_fab2(sch_1):tp_cpu0_rsvd_212';
NODE_NAME     U5D1 AL58
 '@BASEBOARD_FAB2_LIB.BASEBOARD_FAB2(SCH_1):PAGE22_I204@CHPSET_LIB.SKX_EXT_B(CHIPS)':
 'RSVD'<212>: CDS_PINID='RSVD(212)';
NET_NAME
'TP_CPU0_RSVD_214'
 '@BASEBOARD_FAB2_LIB.BASEBOARD_FAB2(SCH_1):TP_CPU0_RSVD_214':
 C_SIGNAL='@baseboard_fab2_lib.baseboard_fab2(sch_1):tp_cpu0_rsvd_214';
NODE_NAME     U5D1 AL22
 '@BASEBOARD_FAB2_LIB.BASEBOARD_FAB2(SCH_1):PAGE22_I204@CHPSET_LIB.SKX_EXT_B(CHIPS)':
 'RSVD'<214>: CDS_PINID='RSVD(214)';
NET_NAME
'TP_CPU0_RSVD_216'
 '@BASEBOARD_FAB2_LIB.BASEBOARD_FAB2(SCH_1):TP_CPU0_RSVD_216':
 C_SIGNAL='@baseboard_fab2_lib.baseboard_fab2(sch_1):tp_cpu0_rsvd_216';
NODE_NAME     U5D1 AK69
 '@BASEBOARD_FAB2_LIB.BASEBOARD_FAB2(SCH_1):PAGE22_I204@CHPSET_LIB.SKX_EXT_B(CHIPS)':
 'RSVD'<216>: CDS_PINID='RSVD(216)';
NET_NAME
'TP_CPU0_RSVD_217'
 '@BASEBOARD_FAB2_LIB.BASEBOARD_FAB2(SCH_1):TP_CPU0_RSVD_217':
 C_SIGNAL='@baseboard_fab2_lib.baseboard_fab2(sch_1):tp_cpu0_rsvd_217';
NODE_NAME     U5D1 AK61
 '@BASEBOARD_FAB2_LIB.BASEBOARD_FAB2(SCH_1):PAGE22_I204@CHPSET_LIB.SKX_EXT_B(CHIPS)':
 'RSVD'<217>: CDS_PINID='RSVD(217)';
NET_NAME
'TP_CPU0_RSVD_218'
 '@BASEBOARD_FAB2_LIB.BASEBOARD_FAB2(SCH_1):TP_CPU0_RSVD_218':
 C_SIGNAL='@baseboard_fab2_lib.baseboard_fab2(sch_1):tp_cpu0_rsvd_218';
NODE_NAME     U5D1 AK59
 '@BASEBOARD_FAB2_LIB.BASEBOARD_FAB2(SCH_1):PAGE22_I204@CHPSET_LIB.SKX_EXT_B(CHIPS)':
 'RSVD'<218>: CDS_PINID='RSVD(218)';
NET_NAME
'TP_CPU0_RSVD_219'
 '@BASEBOARD_FAB2_LIB.BASEBOARD_FAB2(SCH_1):TP_CPU0_RSVD_219':
 C_SIGNAL='@baseboard_fab2_lib.baseboard_fab2(sch_1):tp_cpu0_rsvd_219';
NODE_NAME     U5D1 AK57
 '@BASEBOARD_FAB2_LIB.BASEBOARD_FAB2(SCH_1):PAGE22_I204@CHPSET_LIB.SKX_EXT_B(CHIPS)':
 'RSVD'<219>: CDS_PINID='RSVD(219)';
NET_NAME
'TP_CPU0_RSVD_22'
 '@BASEBOARD_FAB2_LIB.BASEBOARD_FAB2(SCH_1):TP_CPU0_RSVD_22':
 C_SIGNAL='@baseboard_fab2_lib.baseboard_fab2(sch_1):tp_cpu0_rsvd_22';
NODE_NAME     U5D1 DW46
 '@BASEBOARD_FAB2_LIB.BASEBOARD_FAB2(SCH_1):PAGE39_I127@CHPSET_LIB.SKX_EXT_B(CHIPS)':
 'RSVD'<22>: CDS_PINID='RSVD(22)';
NET_NAME
'TP_CPU0_RSVD_222'
 '@BASEBOARD_FAB2_LIB.BASEBOARD_FAB2(SCH_1):TP_CPU0_RSVD_222':
 C_SIGNAL='@baseboard_fab2_lib.baseboard_fab2(sch_1):tp_cpu0_rsvd_222';
NODE_NAME     U5D1 AJ70
 '@BASEBOARD_FAB2_LIB.BASEBOARD_FAB2(SCH_1):PAGE22_I204@CHPSET_LIB.SKX_EXT_B(CHIPS)':
 'RSVD'<222>: CDS_PINID='RSVD(222)';
NET_NAME
'TP_CPU0_RSVD_223'
 '@BASEBOARD_FAB2_LIB.BASEBOARD_FAB2(SCH_1):TP_CPU0_RSVD_223':
 C_SIGNAL='@baseboard_fab2_lib.baseboard_fab2(sch_1):tp_cpu0_rsvd_223';
NODE_NAME     U5D1 AJ62
 '@BASEBOARD_FAB2_LIB.BASEBOARD_FAB2(SCH_1):PAGE22_I204@CHPSET_LIB.SKX_EXT_B(CHIPS)':
 'RSVD'<223>: CDS_PINID='RSVD(223)';
NET_NAME
'TP_CPU0_RSVD_224'
 '@BASEBOARD_FAB2_LIB.BASEBOARD_FAB2(SCH_1):TP_CPU0_RSVD_224':
 C_SIGNAL='@baseboard_fab2_lib.baseboard_fab2(sch_1):tp_cpu0_rsvd_224';
NODE_NAME     U5D1 AJ60
 '@BASEBOARD_FAB2_LIB.BASEBOARD_FAB2(SCH_1):PAGE22_I204@CHPSET_LIB.SKX_EXT_B(CHIPS)':
 'RSVD'<224>: CDS_PINID='RSVD(224)';
NET_NAME
'TP_CPU0_RSVD_225'
 '@BASEBOARD_FAB2_LIB.BASEBOARD_FAB2(SCH_1):TP_CPU0_RSVD_225':
 C_SIGNAL='@baseboard_fab2_lib.baseboard_fab2(sch_1):tp_cpu0_rsvd_225';
NODE_NAME     U5D1 AJ58
 '@BASEBOARD_FAB2_LIB.BASEBOARD_FAB2(SCH_1):PAGE22_I204@CHPSET_LIB.SKX_EXT_B(CHIPS)':
 'RSVD'<225>: CDS_PINID='RSVD(225)';
NET_NAME
'TP_CPU0_RSVD_226'
 '@BASEBOARD_FAB2_LIB.BASEBOARD_FAB2(SCH_1):TP_CPU0_RSVD_226':
 C_SIGNAL='@baseboard_fab2_lib.baseboard_fab2(sch_1):tp_cpu0_rsvd_226';
NODE_NAME     U5D1 AJ56
 '@BASEBOARD_FAB2_LIB.BASEBOARD_FAB2(SCH_1):PAGE22_I204@CHPSET_LIB.SKX_EXT_B(CHIPS)':
 'RSVD'<226>: CDS_PINID='RSVD(226)';
NET_NAME
'TP_CPU0_RSVD_227'
 '@BASEBOARD_FAB2_LIB.BASEBOARD_FAB2(SCH_1):TP_CPU0_RSVD_227':
 C_SIGNAL='@baseboard_fab2_lib.baseboard_fab2(sch_1):tp_cpu0_rsvd_227';
NODE_NAME     U5D1 AJ20
 '@BASEBOARD_FAB2_LIB.BASEBOARD_FAB2(SCH_1):PAGE22_I204@CHPSET_LIB.SKX_EXT_B(CHIPS)':
 'RSVD'<227>: CDS_PINID='RSVD(227)';
NET_NAME
'TP_CPU0_RSVD_228'
 '@BASEBOARD_FAB2_LIB.BASEBOARD_FAB2(SCH_1):TP_CPU0_RSVD_228':
 C_SIGNAL='@baseboard_fab2_lib.baseboard_fab2(sch_1):tp_cpu0_rsvd_228';
NODE_NAME     U5D1 AH73
 '@BASEBOARD_FAB2_LIB.BASEBOARD_FAB2(SCH_1):PAGE22_I204@CHPSET_LIB.SKX_EXT_B(CHIPS)':
 'RSVD'<228>: CDS_PINID='RSVD(228)';
NET_NAME
'TP_CPU0_RSVD_229'
 '@BASEBOARD_FAB2_LIB.BASEBOARD_FAB2(SCH_1):TP_CPU0_RSVD_229':
 C_SIGNAL='@baseboard_fab2_lib.baseboard_fab2(sch_1):tp_cpu0_rsvd_229';
NODE_NAME     U5D1 AH71
 '@BASEBOARD_FAB2_LIB.BASEBOARD_FAB2(SCH_1):PAGE22_I204@CHPSET_LIB.SKX_EXT_B(CHIPS)':
 'RSVD'<229>: CDS_PINID='RSVD(229)';
NET_NAME
'TP_CPU0_RSVD_23'
 '@BASEBOARD_FAB2_LIB.BASEBOARD_FAB2(SCH_1):TP_CPU0_RSVD_23':
 C_SIGNAL='@baseboard_fab2_lib.baseboard_fab2(sch_1):tp_cpu0_rsvd_23';
NODE_NAME     U5D1 DW44
 '@BASEBOARD_FAB2_LIB.BASEBOARD_FAB2(SCH_1):PAGE39_I127@CHPSET_LIB.SKX_EXT_B(CHIPS)':
 'RSVD'<23>: CDS_PINID='RSVD(23)';
NET_NAME
'TP_CPU0_RSVD_230'
 '@BASEBOARD_FAB2_LIB.BASEBOARD_FAB2(SCH_1):TP_CPU0_RSVD_230':
 C_SIGNAL='@baseboard_fab2_lib.baseboard_fab2(sch_1):tp_cpu0_rsvd_230';
NODE_NAME     U5D1 AH57
 '@BASEBOARD_FAB2_LIB.BASEBOARD_FAB2(SCH_1):PAGE22_I204@CHPSET_LIB.SKX_EXT_B(CHIPS)':
 'RSVD'<230>: CDS_PINID='RSVD(230)';
NET_NAME
'TP_CPU0_RSVD_231'
 '@BASEBOARD_FAB2_LIB.BASEBOARD_FAB2(SCH_1):TP_CPU0_RSVD_231':
 C_SIGNAL='@baseboard_fab2_lib.baseboard_fab2(sch_1):tp_cpu0_rsvd_231';
NODE_NAME     U5D1 AH55
 '@BASEBOARD_FAB2_LIB.BASEBOARD_FAB2(SCH_1):PAGE22_I204@CHPSET_LIB.SKX_EXT_B(CHIPS)':
 'RSVD'<231>: CDS_PINID='RSVD(231)';
NET_NAME
'TP_CPU0_RSVD_232'
 '@BASEBOARD_FAB2_LIB.BASEBOARD_FAB2(SCH_1):TP_CPU0_RSVD_232':
 C_SIGNAL='@baseboard_fab2_lib.baseboard_fab2(sch_1):tp_cpu0_rsvd_232';
NODE_NAME     U5D1 AH19
 '@BASEBOARD_FAB2_LIB.BASEBOARD_FAB2(SCH_1):PAGE22_I204@CHPSET_LIB.SKX_EXT_B(CHIPS)':
 'RSVD'<232>: CDS_PINID='RSVD(232)';
NET_NAME
'TP_CPU0_RSVD_233'
 '@BASEBOARD_FAB2_LIB.BASEBOARD_FAB2(SCH_1):TP_CPU0_RSVD_233':
 C_SIGNAL='@baseboard_fab2_lib.baseboard_fab2(sch_1):tp_cpu0_rsvd_233';
NODE_NAME     U5D1 AH15
 '@BASEBOARD_FAB2_LIB.BASEBOARD_FAB2(SCH_1):PAGE22_I204@CHPSET_LIB.SKX_EXT_B(CHIPS)':
 'RSVD'<233>: CDS_PINID='RSVD(233)';
NET_NAME
'TP_CPU0_RSVD_234'
 '@BASEBOARD_FAB2_LIB.BASEBOARD_FAB2(SCH_1):TP_CPU0_RSVD_234':
 C_SIGNAL='@baseboard_fab2_lib.baseboard_fab2(sch_1):tp_cpu0_rsvd_234';
NODE_NAME     U5D1 AG72
 '@BASEBOARD_FAB2_LIB.BASEBOARD_FAB2(SCH_1):PAGE22_I204@CHPSET_LIB.SKX_EXT_B(CHIPS)':
 'RSVD'<234>: CDS_PINID='RSVD(234)';
NET_NAME
'TP_CPU0_RSVD_235'
 '@BASEBOARD_FAB2_LIB.BASEBOARD_FAB2(SCH_1):TP_CPU0_RSVD_235':
 C_SIGNAL='@baseboard_fab2_lib.baseboard_fab2(sch_1):tp_cpu0_rsvd_235';
NODE_NAME     U5D1 AG56
 '@BASEBOARD_FAB2_LIB.BASEBOARD_FAB2(SCH_1):PAGE22_I204@CHPSET_LIB.SKX_EXT_B(CHIPS)':
 'RSVD'<235>: CDS_PINID='RSVD(235)';
NET_NAME
'TP_CPU0_RSVD_236'
 '@BASEBOARD_FAB2_LIB.BASEBOARD_FAB2(SCH_1):TP_CPU0_RSVD_236':
 C_SIGNAL='@baseboard_fab2_lib.baseboard_fab2(sch_1):tp_cpu0_rsvd_236';
NODE_NAME     U5D1 AG54
 '@BASEBOARD_FAB2_LIB.BASEBOARD_FAB2(SCH_1):PAGE22_I204@CHPSET_LIB.SKX_EXT_B(CHIPS)':
 'RSVD'<236>: CDS_PINID='RSVD(236)';
NET_NAME
'TP_CPU0_RSVD_237'
 '@BASEBOARD_FAB2_LIB.BASEBOARD_FAB2(SCH_1):TP_CPU0_RSVD_237':
 C_SIGNAL='@baseboard_fab2_lib.baseboard_fab2(sch_1):tp_cpu0_rsvd_237';
NODE_NAME     U5D1 AG52
 '@BASEBOARD_FAB2_LIB.BASEBOARD_FAB2(SCH_1):PAGE22_I204@CHPSET_LIB.SKX_EXT_B(CHIPS)':
 'RSVD'<237>: CDS_PINID='RSVD(237)';
NET_NAME
'TP_CPU0_RSVD_238'
 '@BASEBOARD_FAB2_LIB.BASEBOARD_FAB2(SCH_1):TP_CPU0_RSVD_238':
 C_SIGNAL='@baseboard_fab2_lib.baseboard_fab2(sch_1):tp_cpu0_rsvd_238';
NODE_NAME     U5D1 AG50
 '@BASEBOARD_FAB2_LIB.BASEBOARD_FAB2(SCH_1):PAGE22_I204@CHPSET_LIB.SKX_EXT_B(CHIPS)':
 'RSVD'<238>: CDS_PINID='RSVD(238)';
NET_NAME
'TP_CPU0_RSVD_239'
 '@BASEBOARD_FAB2_LIB.BASEBOARD_FAB2(SCH_1):TP_CPU0_RSVD_239':
 C_SIGNAL='@baseboard_fab2_lib.baseboard_fab2(sch_1):tp_cpu0_rsvd_239';
NODE_NAME     U5D1 AG48
 '@BASEBOARD_FAB2_LIB.BASEBOARD_FAB2(SCH_1):PAGE22_I204@CHPSET_LIB.SKX_EXT_B(CHIPS)':
 'RSVD'<239>: CDS_PINID='RSVD(239)';
NET_NAME
'TP_CPU0_RSVD_24'
 '@BASEBOARD_FAB2_LIB.BASEBOARD_FAB2(SCH_1):TP_CPU0_RSVD_24':
 C_SIGNAL='@baseboard_fab2_lib.baseboard_fab2(sch_1):tp_cpu0_rsvd_24';
NODE_NAME     U5D1 DV71
 '@BASEBOARD_FAB2_LIB.BASEBOARD_FAB2(SCH_1):PAGE39_I127@CHPSET_LIB.SKX_EXT_B(CHIPS)':
 'RSVD'<24>: CDS_PINID='RSVD(24)';
NET_NAME
'TP_CPU0_RSVD_240'
 '@BASEBOARD_FAB2_LIB.BASEBOARD_FAB2(SCH_1):TP_CPU0_RSVD_240':
 C_SIGNAL='@baseboard_fab2_lib.baseboard_fab2(sch_1):tp_cpu0_rsvd_240';
NODE_NAME     U5D1 AG20
 '@BASEBOARD_FAB2_LIB.BASEBOARD_FAB2(SCH_1):PAGE22_I204@CHPSET_LIB.SKX_EXT_B(CHIPS)':
 'RSVD'<240>: CDS_PINID='RSVD(240)';
NET_NAME
'TP_CPU0_RSVD_241'
 '@BASEBOARD_FAB2_LIB.BASEBOARD_FAB2(SCH_1):TP_CPU0_RSVD_241':
 C_SIGNAL='@baseboard_fab2_lib.baseboard_fab2(sch_1):tp_cpu0_rsvd_241';
NODE_NAME     U5D1 AF71
 '@BASEBOARD_FAB2_LIB.BASEBOARD_FAB2(SCH_1):PAGE22_I204@CHPSET_LIB.SKX_EXT_B(CHIPS)':
 'RSVD'<241>: CDS_PINID='RSVD(241)';
NET_NAME
'TP_CPU0_RSVD_242'
 '@BASEBOARD_FAB2_LIB.BASEBOARD_FAB2(SCH_1):TP_CPU0_RSVD_242':
 C_SIGNAL='@baseboard_fab2_lib.baseboard_fab2(sch_1):tp_cpu0_rsvd_242';
NODE_NAME     U5D1 AF53
 '@BASEBOARD_FAB2_LIB.BASEBOARD_FAB2(SCH_1):PAGE22_I204@CHPSET_LIB.SKX_EXT_B(CHIPS)':
 'RSVD'<242>: CDS_PINID='RSVD(242)';
NET_NAME
'TP_CPU0_RSVD_243'
 '@BASEBOARD_FAB2_LIB.BASEBOARD_FAB2(SCH_1):TP_CPU0_RSVD_243':
 C_SIGNAL='@baseboard_fab2_lib.baseboard_fab2(sch_1):tp_cpu0_rsvd_243';
NODE_NAME     U5D1 AF51
 '@BASEBOARD_FAB2_LIB.BASEBOARD_FAB2(SCH_1):PAGE22_I204@CHPSET_LIB.SKX_EXT_B(CHIPS)':
 'RSVD'<243>: CDS_PINID='RSVD(243)';
NET_NAME
'TP_CPU0_RSVD_244'
 '@BASEBOARD_FAB2_LIB.BASEBOARD_FAB2(SCH_1):TP_CPU0_RSVD_244':
 C_SIGNAL='@baseboard_fab2_lib.baseboard_fab2(sch_1):tp_cpu0_rsvd_244';
NODE_NAME     U5D1 AF49
 '@BASEBOARD_FAB2_LIB.BASEBOARD_FAB2(SCH_1):PAGE22_I204@CHPSET_LIB.SKX_EXT_B(CHIPS)':
 'RSVD'<244>: CDS_PINID='RSVD(244)';
NET_NAME
'TP_CPU0_RSVD_245'
 '@BASEBOARD_FAB2_LIB.BASEBOARD_FAB2(SCH_1):TP_CPU0_RSVD_245':
 C_SIGNAL='@baseboard_fab2_lib.baseboard_fab2(sch_1):tp_cpu0_rsvd_245';
NODE_NAME     U5D1 AF47
 '@BASEBOARD_FAB2_LIB.BASEBOARD_FAB2(SCH_1):PAGE22_I204@CHPSET_LIB.SKX_EXT_B(CHIPS)':
 'RSVD'<245>: CDS_PINID='RSVD(245)';
NET_NAME
'TP_CPU0_RSVD_246'
 '@BASEBOARD_FAB2_LIB.BASEBOARD_FAB2(SCH_1):TP_CPU0_RSVD_246':
 C_SIGNAL='@baseboard_fab2_lib.baseboard_fab2(sch_1):tp_cpu0_rsvd_246';
NODE_NAME     U5D1 AF19
 '@BASEBOARD_FAB2_LIB.BASEBOARD_FAB2(SCH_1):PAGE22_I204@CHPSET_LIB.SKX_EXT_B(CHIPS)':
 'RSVD'<246>: CDS_PINID='RSVD(246)';
NET_NAME
'TP_CPU0_RSVD_247'
 '@BASEBOARD_FAB2_LIB.BASEBOARD_FAB2(SCH_1):TP_CPU0_RSVD_247':
 C_SIGNAL='@baseboard_fab2_lib.baseboard_fab2(sch_1):tp_cpu0_rsvd_247';
NODE_NAME     U5D1 AE72
 '@BASEBOARD_FAB2_LIB.BASEBOARD_FAB2(SCH_1):PAGE22_I204@CHPSET_LIB.SKX_EXT_B(CHIPS)':
 'RSVD'<247>: CDS_PINID='RSVD(247)';
NET_NAME
'TP_CPU0_RSVD_248'
 '@BASEBOARD_FAB2_LIB.BASEBOARD_FAB2(SCH_1):TP_CPU0_RSVD_248':
 C_SIGNAL='@baseboard_fab2_lib.baseboard_fab2(sch_1):tp_cpu0_rsvd_248';
NODE_NAME     U5D1 AE52
 '@BASEBOARD_FAB2_LIB.BASEBOARD_FAB2(SCH_1):PAGE22_I204@CHPSET_LIB.SKX_EXT_B(CHIPS)':
 'RSVD'<248>: CDS_PINID='RSVD(248)';
NET_NAME
'TP_CPU0_RSVD_249'
 '@BASEBOARD_FAB2_LIB.BASEBOARD_FAB2(SCH_1):TP_CPU0_RSVD_249':
 C_SIGNAL='@baseboard_fab2_lib.baseboard_fab2(sch_1):tp_cpu0_rsvd_249';
NODE_NAME     U5D1 AE50
 '@BASEBOARD_FAB2_LIB.BASEBOARD_FAB2(SCH_1):PAGE22_I204@CHPSET_LIB.SKX_EXT_B(CHIPS)':
 'RSVD'<249>: CDS_PINID='RSVD(249)';
NET_NAME
'TP_CPU0_RSVD_25'
 '@BASEBOARD_FAB2_LIB.BASEBOARD_FAB2(SCH_1):TP_CPU0_RSVD_25':
 C_SIGNAL='@baseboard_fab2_lib.baseboard_fab2(sch_1):tp_cpu0_rsvd_25';
NODE_NAME     U5D1 DV61
 '@BASEBOARD_FAB2_LIB.BASEBOARD_FAB2(SCH_1):PAGE39_I127@CHPSET_LIB.SKX_EXT_B(CHIPS)':
 'RSVD'<25>: CDS_PINID='RSVD(25)';
NET_NAME
'TP_CPU0_RSVD_250'
 '@BASEBOARD_FAB2_LIB.BASEBOARD_FAB2(SCH_1):TP_CPU0_RSVD_250':
 C_SIGNAL='@baseboard_fab2_lib.baseboard_fab2(sch_1):tp_cpu0_rsvd_250';
NODE_NAME     U5D1 AE48
 '@BASEBOARD_FAB2_LIB.BASEBOARD_FAB2(SCH_1):PAGE22_I204@CHPSET_LIB.SKX_EXT_B(CHIPS)':
 'RSVD'<250>: CDS_PINID='RSVD(250)';
NET_NAME
'TP_CPU0_RSVD_251'
 '@BASEBOARD_FAB2_LIB.BASEBOARD_FAB2(SCH_1):TP_CPU0_RSVD_251':
 C_SIGNAL='@baseboard_fab2_lib.baseboard_fab2(sch_1):tp_cpu0_rsvd_251';
NODE_NAME     U5D1 AE46
 '@BASEBOARD_FAB2_LIB.BASEBOARD_FAB2(SCH_1):PAGE22_I204@CHPSET_LIB.SKX_EXT_B(CHIPS)':
 'RSVD'<251>: CDS_PINID='RSVD(251)';
NET_NAME
'TP_CPU0_RSVD_252'
 '@BASEBOARD_FAB2_LIB.BASEBOARD_FAB2(SCH_1):TP_CPU0_RSVD_252':
 C_SIGNAL='@baseboard_fab2_lib.baseboard_fab2(sch_1):tp_cpu0_rsvd_252';
NODE_NAME     U5D1 AD51
 '@BASEBOARD_FAB2_LIB.BASEBOARD_FAB2(SCH_1):PAGE22_I204@CHPSET_LIB.SKX_EXT_B(CHIPS)':
 'RSVD'<252>: CDS_PINID='RSVD(252)';
NET_NAME
'TP_CPU0_RSVD_253'
 '@BASEBOARD_FAB2_LIB.BASEBOARD_FAB2(SCH_1):TP_CPU0_RSVD_253':
 C_SIGNAL='@baseboard_fab2_lib.baseboard_fab2(sch_1):tp_cpu0_rsvd_253';
NODE_NAME     U5D1 AD49
 '@BASEBOARD_FAB2_LIB.BASEBOARD_FAB2(SCH_1):PAGE22_I204@CHPSET_LIB.SKX_EXT_B(CHIPS)':
 'RSVD'<253>: CDS_PINID='RSVD(253)';
NET_NAME
'TP_CPU0_RSVD_254'
 '@BASEBOARD_FAB2_LIB.BASEBOARD_FAB2(SCH_1):TP_CPU0_RSVD_254':
 C_SIGNAL='@baseboard_fab2_lib.baseboard_fab2(sch_1):tp_cpu0_rsvd_254';
NODE_NAME     U5D1 AD47
 '@BASEBOARD_FAB2_LIB.BASEBOARD_FAB2(SCH_1):PAGE22_I204@CHPSET_LIB.SKX_EXT_B(CHIPS)':
 'RSVD'<254>: CDS_PINID='RSVD(254)';
NET_NAME
'TP_CPU0_RSVD_255'
 '@BASEBOARD_FAB2_LIB.BASEBOARD_FAB2(SCH_1):TP_CPU0_RSVD_255':
 C_SIGNAL='@baseboard_fab2_lib.baseboard_fab2(sch_1):tp_cpu0_rsvd_255';
NODE_NAME     U5D1 AY83
 '@BASEBOARD_FAB2_LIB.BASEBOARD_FAB2(SCH_1):PAGE36_I15@CHPSET_LIB.SKX_EXT_B(CHIPS)':
 'RSVD'<255>: CDS_PINID='RSVD(255)';
NET_NAME
'TP_CPU0_RSVD_256'
 '@BASEBOARD_FAB2_LIB.BASEBOARD_FAB2(SCH_1):TP_CPU0_RSVD_256':
 C_SIGNAL='@baseboard_fab2_lib.baseboard_fab2(sch_1):tp_cpu0_rsvd_256';
NODE_NAME     U5D1 Y65
 '@BASEBOARD_FAB2_LIB.BASEBOARD_FAB2(SCH_1):PAGE22_I204@CHPSET_LIB.SKX_EXT_B(CHIPS)':
 'RSVD'<256>: CDS_PINID='RSVD(256)';
NET_NAME
'TP_CPU0_RSVD_258'
 '@BASEBOARD_FAB2_LIB.BASEBOARD_FAB2(SCH_1):TP_CPU0_RSVD_258':
 C_SIGNAL='@baseboard_fab2_lib.baseboard_fab2(sch_1):tp_cpu0_rsvd_258';
NODE_NAME     U5D1 W66
 '@BASEBOARD_FAB2_LIB.BASEBOARD_FAB2(SCH_1):PAGE22_I204@CHPSET_LIB.SKX_EXT_B(CHIPS)':
 'RSVD'<258>: CDS_PINID='RSVD(258)';
NET_NAME
'TP_CPU0_RSVD_259'
 '@BASEBOARD_FAB2_LIB.BASEBOARD_FAB2(SCH_1):TP_CPU0_RSVD_259':
 C_SIGNAL='@baseboard_fab2_lib.baseboard_fab2(sch_1):tp_cpu0_rsvd_259';
NODE_NAME     U5D1 V67
 '@BASEBOARD_FAB2_LIB.BASEBOARD_FAB2(SCH_1):PAGE22_I204@CHPSET_LIB.SKX_EXT_B(CHIPS)':
 'RSVD'<259>: CDS_PINID='RSVD(259)';
NET_NAME
'TP_CPU0_RSVD_26'
 '@BASEBOARD_FAB2_LIB.BASEBOARD_FAB2(SCH_1):TP_CPU0_RSVD_26':
 C_SIGNAL='@baseboard_fab2_lib.baseboard_fab2(sch_1):tp_cpu0_rsvd_26';
NODE_NAME     U5D1 DU44
 '@BASEBOARD_FAB2_LIB.BASEBOARD_FAB2(SCH_1):PAGE39_I127@CHPSET_LIB.SKX_EXT_B(CHIPS)':
 'RSVD'<26>: CDS_PINID='RSVD(26)';
NET_NAME
'TP_CPU0_RSVD_260'
 '@BASEBOARD_FAB2_LIB.BASEBOARD_FAB2(SCH_1):TP_CPU0_RSVD_260':
 C_SIGNAL='@baseboard_fab2_lib.baseboard_fab2(sch_1):tp_cpu0_rsvd_260';
NODE_NAME     U5D1 V65
 '@BASEBOARD_FAB2_LIB.BASEBOARD_FAB2(SCH_1):PAGE22_I204@CHPSET_LIB.SKX_EXT_B(CHIPS)':
 'RSVD'<260>: CDS_PINID='RSVD(260)';
NET_NAME
'TP_CPU0_RSVD_261'
 '@BASEBOARD_FAB2_LIB.BASEBOARD_FAB2(SCH_1):TP_CPU0_RSVD_261':
 C_SIGNAL='@baseboard_fab2_lib.baseboard_fab2(sch_1):tp_cpu0_rsvd_261';
NODE_NAME     U5D1 U66
 '@BASEBOARD_FAB2_LIB.BASEBOARD_FAB2(SCH_1):PAGE22_I204@CHPSET_LIB.SKX_EXT_B(CHIPS)':
 'RSVD'<261>: CDS_PINID='RSVD(261)';
NET_NAME
'TP_CPU0_RSVD_262'
 '@BASEBOARD_FAB2_LIB.BASEBOARD_FAB2(SCH_1):TP_CPU0_RSVD_262':
 C_SIGNAL='@baseboard_fab2_lib.baseboard_fab2(sch_1):tp_cpu0_rsvd_262';
NODE_NAME     U5D1 T67
 '@BASEBOARD_FAB2_LIB.BASEBOARD_FAB2(SCH_1):PAGE22_I204@CHPSET_LIB.SKX_EXT_B(CHIPS)':
 'RSVD'<262>: CDS_PINID='RSVD(262)';
NET_NAME
'TP_CPU0_RSVD_263'
 '@BASEBOARD_FAB2_LIB.BASEBOARD_FAB2(SCH_1):TP_CPU0_RSVD_263':
 C_SIGNAL='@baseboard_fab2_lib.baseboard_fab2(sch_1):tp_cpu0_rsvd_263';
NODE_NAME     U5D1 R66
 '@BASEBOARD_FAB2_LIB.BASEBOARD_FAB2(SCH_1):PAGE22_I204@CHPSET_LIB.SKX_EXT_B(CHIPS)':
 'RSVD'<263>: CDS_PINID='RSVD(263)';
NET_NAME
'TP_CPU0_RSVD_264'
 '@BASEBOARD_FAB2_LIB.BASEBOARD_FAB2(SCH_1):TP_CPU0_RSVD_264':
 C_SIGNAL='@baseboard_fab2_lib.baseboard_fab2(sch_1):tp_cpu0_rsvd_264';
NODE_NAME     U5D1 R62
 '@BASEBOARD_FAB2_LIB.BASEBOARD_FAB2(SCH_1):PAGE22_I204@CHPSET_LIB.SKX_EXT_B(CHIPS)':
 'RSVD'<264>: CDS_PINID='RSVD(264)';
NET_NAME
'TP_CPU0_RSVD_265'
 '@BASEBOARD_FAB2_LIB.BASEBOARD_FAB2(SCH_1):TP_CPU0_RSVD_265':
 C_SIGNAL='@baseboard_fab2_lib.baseboard_fab2(sch_1):tp_cpu0_rsvd_265';
NODE_NAME     U5D1 P65
 '@BASEBOARD_FAB2_LIB.BASEBOARD_FAB2(SCH_1):PAGE22_I204@CHPSET_LIB.SKX_EXT_B(CHIPS)':
 'RSVD'<265>: CDS_PINID='RSVD(265)';
NET_NAME
'TP_CPU0_RSVD_266'
 '@BASEBOARD_FAB2_LIB.BASEBOARD_FAB2(SCH_1):TP_CPU0_RSVD_266':
 C_SIGNAL='@baseboard_fab2_lib.baseboard_fab2(sch_1):tp_cpu0_rsvd_266';
NODE_NAME     U5D1 M63
 '@BASEBOARD_FAB2_LIB.BASEBOARD_FAB2(SCH_1):PAGE22_I204@CHPSET_LIB.SKX_EXT_B(CHIPS)':
 'RSVD'<266>: CDS_PINID='RSVD(266)';
NET_NAME
'TP_CPU0_RSVD_267'
 '@BASEBOARD_FAB2_LIB.BASEBOARD_FAB2(SCH_1):TP_CPU0_RSVD_267':
 C_SIGNAL='@baseboard_fab2_lib.baseboard_fab2(sch_1):tp_cpu0_rsvd_267';
NODE_NAME     U5D1 K61
 '@BASEBOARD_FAB2_LIB.BASEBOARD_FAB2(SCH_1):PAGE22_I204@CHPSET_LIB.SKX_EXT_B(CHIPS)':
 'RSVD'<267>: CDS_PINID='RSVD(267)';
NET_NAME
'TP_CPU0_RSVD_268'
 '@BASEBOARD_FAB2_LIB.BASEBOARD_FAB2(SCH_1):TP_CPU0_RSVD_268':
 C_SIGNAL='@baseboard_fab2_lib.baseboard_fab2(sch_1):tp_cpu0_rsvd_268';
NODE_NAME     U5D1 J62
 '@BASEBOARD_FAB2_LIB.BASEBOARD_FAB2(SCH_1):PAGE22_I204@CHPSET_LIB.SKX_EXT_B(CHIPS)':
 'RSVD'<268>: CDS_PINID='RSVD(268)';
NET_NAME
'TP_CPU0_RSVD_269'
 '@BASEBOARD_FAB2_LIB.BASEBOARD_FAB2(SCH_1):TP_CPU0_RSVD_269':
 C_SIGNAL='@baseboard_fab2_lib.baseboard_fab2(sch_1):tp_cpu0_rsvd_269';
NODE_NAME     U5D1 J46
 '@BASEBOARD_FAB2_LIB.BASEBOARD_FAB2(SCH_1):PAGE22_I204@CHPSET_LIB.SKX_EXT_B(CHIPS)':
 'RSVD'<269>: CDS_PINID='RSVD(269)';
NET_NAME
'TP_CPU0_RSVD_27'
 '@BASEBOARD_FAB2_LIB.BASEBOARD_FAB2(SCH_1):TP_CPU0_RSVD_27':
 C_SIGNAL='@baseboard_fab2_lib.baseboard_fab2(sch_1):tp_cpu0_rsvd_27';
NODE_NAME     U5D1 DT71
 '@BASEBOARD_FAB2_LIB.BASEBOARD_FAB2(SCH_1):PAGE39_I127@CHPSET_LIB.SKX_EXT_B(CHIPS)':
 'RSVD'<27>: CDS_PINID='RSVD(27)';
NET_NAME
'TP_CPU0_RSVD_270'
 '@BASEBOARD_FAB2_LIB.BASEBOARD_FAB2(SCH_1):TP_CPU0_RSVD_270':
 C_SIGNAL='@baseboard_fab2_lib.baseboard_fab2(sch_1):tp_cpu0_rsvd_270';
NODE_NAME     U5D1 H85
 '@BASEBOARD_FAB2_LIB.BASEBOARD_FAB2(SCH_1):PAGE22_I204@CHPSET_LIB.SKX_EXT_B(CHIPS)':
 'RSVD'<270>: CDS_PINID='RSVD(270)';
NET_NAME
'TP_CPU0_RSVD_271'
 '@BASEBOARD_FAB2_LIB.BASEBOARD_FAB2(SCH_1):TP_CPU0_RSVD_271':
 C_SIGNAL='@baseboard_fab2_lib.baseboard_fab2(sch_1):tp_cpu0_rsvd_271';
NODE_NAME     U5D1 H83
 '@BASEBOARD_FAB2_LIB.BASEBOARD_FAB2(SCH_1):PAGE22_I204@CHPSET_LIB.SKX_EXT_B(CHIPS)':
 'RSVD'<271>: CDS_PINID='RSVD(271)';
NET_NAME
'TP_CPU0_RSVD_272'
 '@BASEBOARD_FAB2_LIB.BASEBOARD_FAB2(SCH_1):TP_CPU0_RSVD_272':
 C_SIGNAL='@baseboard_fab2_lib.baseboard_fab2(sch_1):tp_cpu0_rsvd_272';
NODE_NAME     U5D1 H1
 '@BASEBOARD_FAB2_LIB.BASEBOARD_FAB2(SCH_1):PAGE22_I204@CHPSET_LIB.SKX_EXT_B(CHIPS)':
 'RSVD'<272>: CDS_PINID='RSVD(272)';
NET_NAME
'TP_CPU0_RSVD_273'
 '@BASEBOARD_FAB2_LIB.BASEBOARD_FAB2(SCH_1):TP_CPU0_RSVD_273':
 C_SIGNAL='@baseboard_fab2_lib.baseboard_fab2(sch_1):tp_cpu0_rsvd_273';
NODE_NAME     U5D1 G84
 '@BASEBOARD_FAB2_LIB.BASEBOARD_FAB2(SCH_1):PAGE22_I204@CHPSET_LIB.SKX_EXT_B(CHIPS)':
 'RSVD'<273>: CDS_PINID='RSVD(273)';
NET_NAME
'TP_CPU0_RSVD_274'
 '@BASEBOARD_FAB2_LIB.BASEBOARD_FAB2(SCH_1):TP_CPU0_RSVD_274':
 C_SIGNAL='@baseboard_fab2_lib.baseboard_fab2(sch_1):tp_cpu0_rsvd_274';
NODE_NAME     U5D1 G64
 '@BASEBOARD_FAB2_LIB.BASEBOARD_FAB2(SCH_1):PAGE22_I204@CHPSET_LIB.SKX_EXT_B(CHIPS)':
 'RSVD'<274>: CDS_PINID='RSVD(274)';
NET_NAME
'TP_CPU0_RSVD_275'
 '@BASEBOARD_FAB2_LIB.BASEBOARD_FAB2(SCH_1):TP_CPU0_RSVD_275':
 C_SIGNAL='@baseboard_fab2_lib.baseboard_fab2(sch_1):tp_cpu0_rsvd_275';
NODE_NAME     U5D1 G2
 '@BASEBOARD_FAB2_LIB.BASEBOARD_FAB2(SCH_1):PAGE22_I204@CHPSET_LIB.SKX_EXT_B(CHIPS)':
 'RSVD'<275>: CDS_PINID='RSVD(275)';
NET_NAME
'TP_CPU0_RSVD_276'
 '@BASEBOARD_FAB2_LIB.BASEBOARD_FAB2(SCH_1):TP_CPU0_RSVD_276':
 C_SIGNAL='@baseboard_fab2_lib.baseboard_fab2(sch_1):tp_cpu0_rsvd_276';
NODE_NAME     U5D1 F83
 '@BASEBOARD_FAB2_LIB.BASEBOARD_FAB2(SCH_1):PAGE22_I204@CHPSET_LIB.SKX_EXT_B(CHIPS)':
 'RSVD'<276>: CDS_PINID='RSVD(276)';
NET_NAME
'TP_CPU0_RSVD_277'
 '@BASEBOARD_FAB2_LIB.BASEBOARD_FAB2(SCH_1):TP_CPU0_RSVD_277':
 C_SIGNAL='@baseboard_fab2_lib.baseboard_fab2(sch_1):tp_cpu0_rsvd_277';
NODE_NAME     U5D1 F65
 '@BASEBOARD_FAB2_LIB.BASEBOARD_FAB2(SCH_1):PAGE22_I204@CHPSET_LIB.SKX_EXT_B(CHIPS)':
 'RSVD'<277>: CDS_PINID='RSVD(277)';
NET_NAME
'TP_CPU0_RSVD_278'
 '@BASEBOARD_FAB2_LIB.BASEBOARD_FAB2(SCH_1):TP_CPU0_RSVD_278':
 C_SIGNAL='@baseboard_fab2_lib.baseboard_fab2(sch_1):tp_cpu0_rsvd_278';
NODE_NAME     U5D1 F23
 '@BASEBOARD_FAB2_LIB.BASEBOARD_FAB2(SCH_1):PAGE22_I204@CHPSET_LIB.SKX_EXT_B(CHIPS)':
 'RSVD'<278>: CDS_PINID='RSVD(278)';
NET_NAME
'TP_CPU0_RSVD_279'
 '@BASEBOARD_FAB2_LIB.BASEBOARD_FAB2(SCH_1):TP_CPU0_RSVD_279':
 C_SIGNAL='@baseboard_fab2_lib.baseboard_fab2(sch_1):tp_cpu0_rsvd_279';
NODE_NAME     U5D1 F3
 '@BASEBOARD_FAB2_LIB.BASEBOARD_FAB2(SCH_1):PAGE22_I204@CHPSET_LIB.SKX_EXT_B(CHIPS)':
 'RSVD'<279>: CDS_PINID='RSVD(279)';
NET_NAME
'TP_CPU0_RSVD_28'
 '@BASEBOARD_FAB2_LIB.BASEBOARD_FAB2(SCH_1):TP_CPU0_RSVD_28':
 C_SIGNAL='@baseboard_fab2_lib.baseboard_fab2(sch_1):tp_cpu0_rsvd_28';
NODE_NAME     U5D1 DR44
 '@BASEBOARD_FAB2_LIB.BASEBOARD_FAB2(SCH_1):PAGE39_I127@CHPSET_LIB.SKX_EXT_B(CHIPS)':
 'RSVD'<28>: CDS_PINID='RSVD(28)';
NET_NAME
'TP_CPU0_RSVD_280'
 '@BASEBOARD_FAB2_LIB.BASEBOARD_FAB2(SCH_1):TP_CPU0_RSVD_280':
 C_SIGNAL='@baseboard_fab2_lib.baseboard_fab2(sch_1):tp_cpu0_rsvd_280';
NODE_NAME     U5D1 E84
 '@BASEBOARD_FAB2_LIB.BASEBOARD_FAB2(SCH_1):PAGE22_I204@CHPSET_LIB.SKX_EXT_B(CHIPS)':
 'RSVD'<280>: CDS_PINID='RSVD(280)';
NET_NAME
'TP_CPU0_RSVD_281'
 '@BASEBOARD_FAB2_LIB.BASEBOARD_FAB2(SCH_1):TP_CPU0_RSVD_281':
 C_SIGNAL='@baseboard_fab2_lib.baseboard_fab2(sch_1):tp_cpu0_rsvd_281';
NODE_NAME     U5D1 E24
 '@BASEBOARD_FAB2_LIB.BASEBOARD_FAB2(SCH_1):PAGE22_I204@CHPSET_LIB.SKX_EXT_B(CHIPS)':
 'RSVD'<281>: CDS_PINID='RSVD(281)';
NET_NAME
'TP_CPU0_RSVD_282'
 '@BASEBOARD_FAB2_LIB.BASEBOARD_FAB2(SCH_1):TP_CPU0_RSVD_282':
 C_SIGNAL='@baseboard_fab2_lib.baseboard_fab2(sch_1):tp_cpu0_rsvd_282';
NODE_NAME     U5D1 E4
 '@BASEBOARD_FAB2_LIB.BASEBOARD_FAB2(SCH_1):PAGE22_I204@CHPSET_LIB.SKX_EXT_B(CHIPS)':
 'RSVD'<282>: CDS_PINID='RSVD(282)';
NET_NAME
'TP_CPU0_RSVD_283'
 '@BASEBOARD_FAB2_LIB.BASEBOARD_FAB2(SCH_1):TP_CPU0_RSVD_283':
 C_SIGNAL='@baseboard_fab2_lib.baseboard_fab2(sch_1):tp_cpu0_rsvd_283';
NODE_NAME     U5D1 E2
 '@BASEBOARD_FAB2_LIB.BASEBOARD_FAB2(SCH_1):PAGE22_I204@CHPSET_LIB.SKX_EXT_B(CHIPS)':
 'RSVD'<283>: CDS_PINID='RSVD(283)';
NET_NAME
'TP_CPU0_RSVD_284'
 '@BASEBOARD_FAB2_LIB.BASEBOARD_FAB2(SCH_1):TP_CPU0_RSVD_284':
 C_SIGNAL='@baseboard_fab2_lib.baseboard_fab2(sch_1):tp_cpu0_rsvd_284';
NODE_NAME     U5D1 D83
 '@BASEBOARD_FAB2_LIB.BASEBOARD_FAB2(SCH_1):PAGE22_I204@CHPSET_LIB.SKX_EXT_B(CHIPS)':
 'RSVD'<284>: CDS_PINID='RSVD(284)';
NET_NAME
'TP_CPU0_RSVD_285'
 '@BASEBOARD_FAB2_LIB.BASEBOARD_FAB2(SCH_1):TP_CPU0_RSVD_285':
 C_SIGNAL='@baseboard_fab2_lib.baseboard_fab2(sch_1):tp_cpu0_rsvd_285';
NODE_NAME     U5D1 D65
 '@BASEBOARD_FAB2_LIB.BASEBOARD_FAB2(SCH_1):PAGE22_I204@CHPSET_LIB.SKX_EXT_B(CHIPS)':
 'RSVD'<285>: CDS_PINID='RSVD(285)';
NET_NAME
'TP_CPU0_RSVD_286'
 '@BASEBOARD_FAB2_LIB.BASEBOARD_FAB2(SCH_1):TP_CPU0_RSVD_286':
 C_SIGNAL='@baseboard_fab2_lib.baseboard_fab2(sch_1):tp_cpu0_rsvd_286';
NODE_NAME     U5D1 D17
 '@BASEBOARD_FAB2_LIB.BASEBOARD_FAB2(SCH_1):PAGE22_I204@CHPSET_LIB.SKX_EXT_B(CHIPS)':
 'RSVD'<286>: CDS_PINID='RSVD(286)';
NET_NAME
'TP_CPU0_RSVD_287'
 '@BASEBOARD_FAB2_LIB.BASEBOARD_FAB2(SCH_1):TP_CPU0_RSVD_287':
 C_SIGNAL='@baseboard_fab2_lib.baseboard_fab2(sch_1):tp_cpu0_rsvd_287';
NODE_NAME     U5D1 D5
 '@BASEBOARD_FAB2_LIB.BASEBOARD_FAB2(SCH_1):PAGE22_I204@CHPSET_LIB.SKX_EXT_B(CHIPS)':
 'RSVD'<287>: CDS_PINID='RSVD(287)';
NET_NAME
'TP_CPU0_RSVD_288'
 '@BASEBOARD_FAB2_LIB.BASEBOARD_FAB2(SCH_1):TP_CPU0_RSVD_288':
 C_SIGNAL='@baseboard_fab2_lib.baseboard_fab2(sch_1):tp_cpu0_rsvd_288';
NODE_NAME     U5D1 C82
 '@BASEBOARD_FAB2_LIB.BASEBOARD_FAB2(SCH_1):PAGE22_I204@CHPSET_LIB.SKX_EXT_B(CHIPS)':
 'RSVD'<288>: CDS_PINID='RSVD(288)';
NET_NAME
'TP_CPU0_RSVD_289'
 '@BASEBOARD_FAB2_LIB.BASEBOARD_FAB2(SCH_1):TP_CPU0_RSVD_289':
 C_SIGNAL='@baseboard_fab2_lib.baseboard_fab2(sch_1):tp_cpu0_rsvd_289';
NODE_NAME     U5D1 C24
 '@BASEBOARD_FAB2_LIB.BASEBOARD_FAB2(SCH_1):PAGE22_I204@CHPSET_LIB.SKX_EXT_B(CHIPS)':
 'RSVD'<289>: CDS_PINID='RSVD(289)';
NET_NAME
'TP_CPU0_RSVD_29'
 '@BASEBOARD_FAB2_LIB.BASEBOARD_FAB2(SCH_1):TP_CPU0_RSVD_29':
 C_SIGNAL='@baseboard_fab2_lib.baseboard_fab2(sch_1):tp_cpu0_rsvd_29';
NODE_NAME     U5D1 DP65
 '@BASEBOARD_FAB2_LIB.BASEBOARD_FAB2(SCH_1):PAGE39_I127@CHPSET_LIB.SKX_EXT_B(CHIPS)':
 'RSVD'<29>: CDS_PINID='RSVD(29)';
NET_NAME
'TP_CPU0_RSVD_290'
 '@BASEBOARD_FAB2_LIB.BASEBOARD_FAB2(SCH_1):TP_CPU0_RSVD_290':
 C_SIGNAL='@baseboard_fab2_lib.baseboard_fab2(sch_1):tp_cpu0_rsvd_290';
NODE_NAME     U5D1 C18
 '@BASEBOARD_FAB2_LIB.BASEBOARD_FAB2(SCH_1):PAGE22_I204@CHPSET_LIB.SKX_EXT_B(CHIPS)':
 'RSVD'<290>: CDS_PINID='RSVD(290)';
NET_NAME
'TP_CPU0_RSVD_291'
 '@BASEBOARD_FAB2_LIB.BASEBOARD_FAB2(SCH_1):TP_CPU0_RSVD_291':
 C_SIGNAL='@baseboard_fab2_lib.baseboard_fab2(sch_1):tp_cpu0_rsvd_291';
NODE_NAME     U5D1 C6
 '@BASEBOARD_FAB2_LIB.BASEBOARD_FAB2(SCH_1):PAGE22_I204@CHPSET_LIB.SKX_EXT_B(CHIPS)':
 'RSVD'<291>: CDS_PINID='RSVD(291)';
NET_NAME
'TP_CPU0_RSVD_292'
 '@BASEBOARD_FAB2_LIB.BASEBOARD_FAB2(SCH_1):TP_CPU0_RSVD_292':
 C_SIGNAL='@baseboard_fab2_lib.baseboard_fab2(sch_1):tp_cpu0_rsvd_292';
NODE_NAME     U5D1 B81
 '@BASEBOARD_FAB2_LIB.BASEBOARD_FAB2(SCH_1):PAGE22_I204@CHPSET_LIB.SKX_EXT_B(CHIPS)':
 'RSVD'<292>: CDS_PINID='RSVD(292)';
NET_NAME
'TP_CPU0_RSVD_293'
 '@BASEBOARD_FAB2_LIB.BASEBOARD_FAB2(SCH_1):TP_CPU0_RSVD_293':
 C_SIGNAL='@baseboard_fab2_lib.baseboard_fab2(sch_1):tp_cpu0_rsvd_293';
NODE_NAME     U5D1 B77
 '@BASEBOARD_FAB2_LIB.BASEBOARD_FAB2(SCH_1):PAGE22_I204@CHPSET_LIB.SKX_EXT_B(CHIPS)':
 'RSVD'<293>: CDS_PINID='RSVD(293)';
NET_NAME
'TP_CPU0_RSVD_298'
 '@BASEBOARD_FAB2_LIB.BASEBOARD_FAB2(SCH_1):TP_CPU0_RSVD_298':
 C_SIGNAL='@baseboard_fab2_lib.baseboard_fab2(sch_1):tp_cpu0_rsvd_298';
NODE_NAME     U5D1 B7
 '@BASEBOARD_FAB2_LIB.BASEBOARD_FAB2(SCH_1):PAGE22_I204@CHPSET_LIB.SKX_EXT_B(CHIPS)':
 'RSVD'<298>: CDS_PINID='RSVD(298)';
NET_NAME
'TP_CPU0_RSVD_299'
 '@BASEBOARD_FAB2_LIB.BASEBOARD_FAB2(SCH_1):TP_CPU0_RSVD_299':
 C_SIGNAL='@baseboard_fab2_lib.baseboard_fab2(sch_1):tp_cpu0_rsvd_299';
NODE_NAME     U5D1 B3
 '@BASEBOARD_FAB2_LIB.BASEBOARD_FAB2(SCH_1):PAGE22_I204@CHPSET_LIB.SKX_EXT_B(CHIPS)':
 'RSVD'<299>: CDS_PINID='RSVD(299)';
NET_NAME
'TP_CPU0_RSVD_3'
 '@BASEBOARD_FAB2_LIB.BASEBOARD_FAB2(SCH_1):TP_CPU0_RSVD_3':
 C_SIGNAL='@baseboard_fab2_lib.baseboard_fab2(sch_1):tp_cpu0_rsvd_3';
NODE_NAME     U5D1 EF47
 '@BASEBOARD_FAB2_LIB.BASEBOARD_FAB2(SCH_1):PAGE39_I127@CHPSET_LIB.SKX_EXT_B(CHIPS)':
 'RSVD'<3>: CDS_PINID='RSVD(3)';
NET_NAME
'TP_CPU0_RSVD_30'
 '@BASEBOARD_FAB2_LIB.BASEBOARD_FAB2(SCH_1):TP_CPU0_RSVD_30':
 C_SIGNAL='@baseboard_fab2_lib.baseboard_fab2(sch_1):tp_cpu0_rsvd_30';
NODE_NAME     U5D1 DP17
 '@BASEBOARD_FAB2_LIB.BASEBOARD_FAB2(SCH_1):PAGE39_I127@CHPSET_LIB.SKX_EXT_B(CHIPS)':
 'RSVD'<30>: CDS_PINID='RSVD(30)';
NET_NAME
'TP_CPU0_RSVD_300'
 '@BASEBOARD_FAB2_LIB.BASEBOARD_FAB2(SCH_1):TP_CPU0_RSVD_300':
 C_SIGNAL='@baseboard_fab2_lib.baseboard_fab2(sch_1):tp_cpu0_rsvd_300';
NODE_NAME     U5D1 A24
 '@BASEBOARD_FAB2_LIB.BASEBOARD_FAB2(SCH_1):PAGE22_I204@CHPSET_LIB.SKX_EXT_B(CHIPS)':
 'RSVD'<300>: CDS_PINID='RSVD(300)';
NET_NAME
'TP_CPU0_RSVD_303'
 '@BASEBOARD_FAB2_LIB.BASEBOARD_FAB2(SCH_1):TP_CPU0_RSVD_303':
 C_SIGNAL='@baseboard_fab2_lib.baseboard_fab2(sch_1):tp_cpu0_rsvd_303';
NODE_NAME     U5D1 A6
 '@BASEBOARD_FAB2_LIB.BASEBOARD_FAB2(SCH_1):PAGE22_I204@CHPSET_LIB.SKX_EXT_B(CHIPS)':
 'RSVD'<303>: CDS_PINID='RSVD(303)';
NET_NAME
'TP_CPU0_RSVD_304'
 '@BASEBOARD_FAB2_LIB.BASEBOARD_FAB2(SCH_1):TP_CPU0_RSVD_304':
 C_SIGNAL='@baseboard_fab2_lib.baseboard_fab2(sch_1):tp_cpu0_rsvd_304';
NODE_NAME     U5D1 A4
 '@BASEBOARD_FAB2_LIB.BASEBOARD_FAB2(SCH_1):PAGE22_I204@CHPSET_LIB.SKX_EXT_B(CHIPS)':
 'RSVD'<304>: CDS_PINID='RSVD(304)';
NET_NAME
'TP_CPU0_RSVD_31'
 '@BASEBOARD_FAB2_LIB.BASEBOARD_FAB2(SCH_1):TP_CPU0_RSVD_31':
 C_SIGNAL='@baseboard_fab2_lib.baseboard_fab2(sch_1):tp_cpu0_rsvd_31';
NODE_NAME     U5D1 DN66
 '@BASEBOARD_FAB2_LIB.BASEBOARD_FAB2(SCH_1):PAGE39_I127@CHPSET_LIB.SKX_EXT_B(CHIPS)':
 'RSVD'<31>: CDS_PINID='RSVD(31)';
NET_NAME
'TP_CPU0_RSVD_32'
 '@BASEBOARD_FAB2_LIB.BASEBOARD_FAB2(SCH_1):TP_CPU0_RSVD_32':
 C_SIGNAL='@baseboard_fab2_lib.baseboard_fab2(sch_1):tp_cpu0_rsvd_32';
NODE_NAME     U5D1 DN62
 '@BASEBOARD_FAB2_LIB.BASEBOARD_FAB2(SCH_1):PAGE39_I127@CHPSET_LIB.SKX_EXT_B(CHIPS)':
 'RSVD'<32>: CDS_PINID='RSVD(32)';
NET_NAME
'TP_CPU0_RSVD_33'
 '@BASEBOARD_FAB2_LIB.BASEBOARD_FAB2(SCH_1):TP_CPU0_RSVD_33':
 C_SIGNAL='@baseboard_fab2_lib.baseboard_fab2(sch_1):tp_cpu0_rsvd_33';
NODE_NAME     U5D1 DM67
 '@BASEBOARD_FAB2_LIB.BASEBOARD_FAB2(SCH_1):PAGE39_I127@CHPSET_LIB.SKX_EXT_B(CHIPS)':
 'RSVD'<33>: CDS_PINID='RSVD(33)';
NET_NAME
'TP_CPU0_RSVD_34'
 '@BASEBOARD_FAB2_LIB.BASEBOARD_FAB2(SCH_1):TP_CPU0_RSVD_34':
 C_SIGNAL='@baseboard_fab2_lib.baseboard_fab2(sch_1):tp_cpu0_rsvd_34';
NODE_NAME     U5D1 DL66
 '@BASEBOARD_FAB2_LIB.BASEBOARD_FAB2(SCH_1):PAGE39_I127@CHPSET_LIB.SKX_EXT_B(CHIPS)':
 'RSVD'<34>: CDS_PINID='RSVD(34)';
NET_NAME
'TP_CPU0_RSVD_35'
 '@BASEBOARD_FAB2_LIB.BASEBOARD_FAB2(SCH_1):TP_CPU0_RSVD_35':
 C_SIGNAL='@baseboard_fab2_lib.baseboard_fab2(sch_1):tp_cpu0_rsvd_35';
NODE_NAME     U5D1 DL38
 '@BASEBOARD_FAB2_LIB.BASEBOARD_FAB2(SCH_1):PAGE39_I127@CHPSET_LIB.SKX_EXT_B(CHIPS)':
 'RSVD'<35>: CDS_PINID='RSVD(35)';
NET_NAME
'TP_CPU0_RSVD_36'
 '@BASEBOARD_FAB2_LIB.BASEBOARD_FAB2(SCH_1):TP_CPU0_RSVD_36':
 C_SIGNAL='@baseboard_fab2_lib.baseboard_fab2(sch_1):tp_cpu0_rsvd_36';
NODE_NAME     U5D1 DK67
 '@BASEBOARD_FAB2_LIB.BASEBOARD_FAB2(SCH_1):PAGE39_I127@CHPSET_LIB.SKX_EXT_B(CHIPS)':
 'RSVD'<36>: CDS_PINID='RSVD(36)';
NET_NAME
'TP_CPU0_RSVD_37'
 '@BASEBOARD_FAB2_LIB.BASEBOARD_FAB2(SCH_1):TP_CPU0_RSVD_37':
 C_SIGNAL='@baseboard_fab2_lib.baseboard_fab2(sch_1):tp_cpu0_rsvd_37';
NODE_NAME     U5D1 DK65
 '@BASEBOARD_FAB2_LIB.BASEBOARD_FAB2(SCH_1):PAGE39_I127@CHPSET_LIB.SKX_EXT_B(CHIPS)':
 'RSVD'<37>: CDS_PINID='RSVD(37)';
NET_NAME
'TP_CPU0_RSVD_38'
 '@BASEBOARD_FAB2_LIB.BASEBOARD_FAB2(SCH_1):TP_CPU0_RSVD_38':
 C_SIGNAL='@baseboard_fab2_lib.baseboard_fab2(sch_1):tp_cpu0_rsvd_38';
NODE_NAME     U5D1 DK37
 '@BASEBOARD_FAB2_LIB.BASEBOARD_FAB2(SCH_1):PAGE39_I127@CHPSET_LIB.SKX_EXT_B(CHIPS)':
 'RSVD'<38>: CDS_PINID='RSVD(38)';
NET_NAME
'TP_CPU0_RSVD_39'
 '@BASEBOARD_FAB2_LIB.BASEBOARD_FAB2(SCH_1):TP_CPU0_RSVD_39':
 C_SIGNAL='@baseboard_fab2_lib.baseboard_fab2(sch_1):tp_cpu0_rsvd_39';
NODE_NAME     U5D1 DK15
 '@BASEBOARD_FAB2_LIB.BASEBOARD_FAB2(SCH_1):PAGE39_I127@CHPSET_LIB.SKX_EXT_B(CHIPS)':
 'RSVD'<39>: CDS_PINID='RSVD(39)';
NET_NAME
'TP_CPU0_RSVD_4'
 '@BASEBOARD_FAB2_LIB.BASEBOARD_FAB2(SCH_1):TP_CPU0_RSVD_4':
 C_SIGNAL='@baseboard_fab2_lib.baseboard_fab2(sch_1):tp_cpu0_rsvd_4';
NODE_NAME     U5D1 EE84
 '@BASEBOARD_FAB2_LIB.BASEBOARD_FAB2(SCH_1):PAGE39_I127@CHPSET_LIB.SKX_EXT_B(CHIPS)':
 'RSVD'<4>: CDS_PINID='RSVD(4)';
NET_NAME
'TP_CPU0_RSVD_40'
 '@BASEBOARD_FAB2_LIB.BASEBOARD_FAB2(SCH_1):TP_CPU0_RSVD_40':
 C_SIGNAL='@baseboard_fab2_lib.baseboard_fab2(sch_1):tp_cpu0_rsvd_40';
NODE_NAME     U5D1 DJ66
 '@BASEBOARD_FAB2_LIB.BASEBOARD_FAB2(SCH_1):PAGE39_I127@CHPSET_LIB.SKX_EXT_B(CHIPS)':
 'RSVD'<40>: CDS_PINID='RSVD(40)';
NET_NAME
'TP_CPU0_RSVD_41'
 '@BASEBOARD_FAB2_LIB.BASEBOARD_FAB2(SCH_1):TP_CPU0_RSVD_41':
 C_SIGNAL='@baseboard_fab2_lib.baseboard_fab2(sch_1):tp_cpu0_rsvd_41';
NODE_NAME     U5D1 DJ36
 '@BASEBOARD_FAB2_LIB.BASEBOARD_FAB2(SCH_1):PAGE39_I127@CHPSET_LIB.SKX_EXT_B(CHIPS)':
 'RSVD'<41>: CDS_PINID='RSVD(41)';
NET_NAME
'TP_CPU0_RSVD_42'
 '@BASEBOARD_FAB2_LIB.BASEBOARD_FAB2(SCH_1):TP_CPU0_RSVD_42':
 C_SIGNAL='@baseboard_fab2_lib.baseboard_fab2(sch_1):tp_cpu0_rsvd_42';
NODE_NAME     U5D1 DH65
 '@BASEBOARD_FAB2_LIB.BASEBOARD_FAB2(SCH_1):PAGE39_I127@CHPSET_LIB.SKX_EXT_B(CHIPS)':
 'RSVD'<42>: CDS_PINID='RSVD(42)';
NET_NAME
'TP_CPU0_RSVD_43'
 '@BASEBOARD_FAB2_LIB.BASEBOARD_FAB2(SCH_1):TP_CPU0_RSVD_43':
 C_SIGNAL='@baseboard_fab2_lib.baseboard_fab2(sch_1):tp_cpu0_rsvd_43';
NODE_NAME     U5D1 DG64
 '@BASEBOARD_FAB2_LIB.BASEBOARD_FAB2(SCH_1):PAGE39_I127@CHPSET_LIB.SKX_EXT_B(CHIPS)':
 'RSVD'<43>: CDS_PINID='RSVD(43)';
NET_NAME
'TP_CPU0_RSVD_44'
 '@BASEBOARD_FAB2_LIB.BASEBOARD_FAB2(SCH_1):TP_CPU0_RSVD_44':
 C_SIGNAL='@baseboard_fab2_lib.baseboard_fab2(sch_1):tp_cpu0_rsvd_44';
NODE_NAME     U5D1 DG36
 '@BASEBOARD_FAB2_LIB.BASEBOARD_FAB2(SCH_1):PAGE39_I127@CHPSET_LIB.SKX_EXT_B(CHIPS)':
 'RSVD'<44>: CDS_PINID='RSVD(44)';
NET_NAME
'TP_CPU0_RSVD_45'
 '@BASEBOARD_FAB2_LIB.BASEBOARD_FAB2(SCH_1):TP_CPU0_RSVD_45':
 C_SIGNAL='@baseboard_fab2_lib.baseboard_fab2(sch_1):tp_cpu0_rsvd_45';
NODE_NAME     U5D1 DD51
 '@BASEBOARD_FAB2_LIB.BASEBOARD_FAB2(SCH_1):PAGE39_I127@CHPSET_LIB.SKX_EXT_B(CHIPS)':
 'RSVD'<45>: CDS_PINID='RSVD(45)';
NET_NAME
'TP_CPU0_RSVD_46'
 '@BASEBOARD_FAB2_LIB.BASEBOARD_FAB2(SCH_1):TP_CPU0_RSVD_46':
 C_SIGNAL='@baseboard_fab2_lib.baseboard_fab2(sch_1):tp_cpu0_rsvd_46';
NODE_NAME     U5D1 DC52
 '@BASEBOARD_FAB2_LIB.BASEBOARD_FAB2(SCH_1):PAGE39_I127@CHPSET_LIB.SKX_EXT_B(CHIPS)':
 'RSVD'<46>: CDS_PINID='RSVD(46)';
NET_NAME
'TP_CPU0_RSVD_47'
 '@BASEBOARD_FAB2_LIB.BASEBOARD_FAB2(SCH_1):TP_CPU0_RSVD_47':
 C_SIGNAL='@baseboard_fab2_lib.baseboard_fab2(sch_1):tp_cpu0_rsvd_47';
NODE_NAME     U5D1 DC46
 '@BASEBOARD_FAB2_LIB.BASEBOARD_FAB2(SCH_1):PAGE39_I127@CHPSET_LIB.SKX_EXT_B(CHIPS)':
 'RSVD'<47>: CDS_PINID='RSVD(47)';
NET_NAME
'TP_CPU0_RSVD_48'
 '@BASEBOARD_FAB2_LIB.BASEBOARD_FAB2(SCH_1):TP_CPU0_RSVD_48':
 C_SIGNAL='@baseboard_fab2_lib.baseboard_fab2(sch_1):tp_cpu0_rsvd_48';
NODE_NAME     U5D1 DA56
 '@BASEBOARD_FAB2_LIB.BASEBOARD_FAB2(SCH_1):PAGE39_I127@CHPSET_LIB.SKX_EXT_B(CHIPS)':
 'RSVD'<48>: CDS_PINID='RSVD(48)';
NET_NAME
'TP_CPU0_RSVD_49'
 '@BASEBOARD_FAB2_LIB.BASEBOARD_FAB2(SCH_1):TP_CPU0_RSVD_49':
 C_SIGNAL='@baseboard_fab2_lib.baseboard_fab2(sch_1):tp_cpu0_rsvd_49';
NODE_NAME     U5D1 DA54
 '@BASEBOARD_FAB2_LIB.BASEBOARD_FAB2(SCH_1):PAGE39_I127@CHPSET_LIB.SKX_EXT_B(CHIPS)':
 'RSVD'<49>: CDS_PINID='RSVD(49)';
NET_NAME
'TP_CPU0_RSVD_5'
 '@BASEBOARD_FAB2_LIB.BASEBOARD_FAB2(SCH_1):TP_CPU0_RSVD_5':
 C_SIGNAL='@baseboard_fab2_lib.baseboard_fab2(sch_1):tp_cpu0_rsvd_5';
NODE_NAME     U5D1 EE82
 '@BASEBOARD_FAB2_LIB.BASEBOARD_FAB2(SCH_1):PAGE39_I127@CHPSET_LIB.SKX_EXT_B(CHIPS)':
 'RSVD'<5>: CDS_PINID='RSVD(5)';
NET_NAME
'TP_CPU0_RSVD_50'
 '@BASEBOARD_FAB2_LIB.BASEBOARD_FAB2(SCH_1):TP_CPU0_RSVD_50':
 C_SIGNAL='@baseboard_fab2_lib.baseboard_fab2(sch_1):tp_cpu0_rsvd_50';
NODE_NAME     U5D1 DA52
 '@BASEBOARD_FAB2_LIB.BASEBOARD_FAB2(SCH_1):PAGE39_I127@CHPSET_LIB.SKX_EXT_B(CHIPS)':
 'RSVD'<50>: CDS_PINID='RSVD(50)';
NET_NAME
'TP_CPU0_RSVD_51'
 '@BASEBOARD_FAB2_LIB.BASEBOARD_FAB2(SCH_1):TP_CPU0_RSVD_51':
 C_SIGNAL='@baseboard_fab2_lib.baseboard_fab2(sch_1):tp_cpu0_rsvd_51';
NODE_NAME     U5D1 DA40
 '@BASEBOARD_FAB2_LIB.BASEBOARD_FAB2(SCH_1):PAGE39_I127@CHPSET_LIB.SKX_EXT_B(CHIPS)':
 'RSVD'<51>: CDS_PINID='RSVD(51)';
NET_NAME
'TP_CPU0_RSVD_53'
 '@BASEBOARD_FAB2_LIB.BASEBOARD_FAB2(SCH_1):TP_CPU0_RSVD_53':
 C_SIGNAL='@baseboard_fab2_lib.baseboard_fab2(sch_1):tp_cpu0_rsvd_53';
NODE_NAME     U5D1 CY73
 '@BASEBOARD_FAB2_LIB.BASEBOARD_FAB2(SCH_1):PAGE39_I127@CHPSET_LIB.SKX_EXT_B(CHIPS)':
 'RSVD'<53>: CDS_PINID='RSVD(53)';
NET_NAME
'TP_CPU0_RSVD_54'
 '@BASEBOARD_FAB2_LIB.BASEBOARD_FAB2(SCH_1):TP_CPU0_RSVD_54':
 C_SIGNAL='@baseboard_fab2_lib.baseboard_fab2(sch_1):tp_cpu0_rsvd_54';
NODE_NAME     U5D1 CY63
 '@BASEBOARD_FAB2_LIB.BASEBOARD_FAB2(SCH_1):PAGE39_I127@CHPSET_LIB.SKX_EXT_B(CHIPS)':
 'RSVD'<54>: CDS_PINID='RSVD(54)';
NET_NAME
'TP_CPU0_RSVD_55'
 '@BASEBOARD_FAB2_LIB.BASEBOARD_FAB2(SCH_1):TP_CPU0_RSVD_55':
 C_SIGNAL='@baseboard_fab2_lib.baseboard_fab2(sch_1):tp_cpu0_rsvd_55';
NODE_NAME     U5D1 CY57
 '@BASEBOARD_FAB2_LIB.BASEBOARD_FAB2(SCH_1):PAGE39_I127@CHPSET_LIB.SKX_EXT_B(CHIPS)':
 'RSVD'<55>: CDS_PINID='RSVD(55)';
NET_NAME
'TP_CPU0_RSVD_56'
 '@BASEBOARD_FAB2_LIB.BASEBOARD_FAB2(SCH_1):TP_CPU0_RSVD_56':
 C_SIGNAL='@baseboard_fab2_lib.baseboard_fab2(sch_1):tp_cpu0_rsvd_56';
NODE_NAME     U5D1 CY53
 '@BASEBOARD_FAB2_LIB.BASEBOARD_FAB2(SCH_1):PAGE39_I127@CHPSET_LIB.SKX_EXT_B(CHIPS)':
 'RSVD'<56>: CDS_PINID='RSVD(56)';
NET_NAME
'TP_CPU0_RSVD_57'
 '@BASEBOARD_FAB2_LIB.BASEBOARD_FAB2(SCH_1):TP_CPU0_RSVD_57':
 C_SIGNAL='@baseboard_fab2_lib.baseboard_fab2(sch_1):tp_cpu0_rsvd_57';
NODE_NAME     U5D1 CY39
 '@BASEBOARD_FAB2_LIB.BASEBOARD_FAB2(SCH_1):PAGE39_I127@CHPSET_LIB.SKX_EXT_B(CHIPS)':
 'RSVD'<57>: CDS_PINID='RSVD(57)';
NET_NAME
'TP_CPU0_RSVD_59'
 '@BASEBOARD_FAB2_LIB.BASEBOARD_FAB2(SCH_1):TP_CPU0_RSVD_59':
 C_SIGNAL='@baseboard_fab2_lib.baseboard_fab2(sch_1):tp_cpu0_rsvd_59';
NODE_NAME     U5D1 CY23
 '@BASEBOARD_FAB2_LIB.BASEBOARD_FAB2(SCH_1):PAGE39_I127@CHPSET_LIB.SKX_EXT_B(CHIPS)':
 'RSVD'<59>: CDS_PINID='RSVD(59)';
NET_NAME
'TP_CPU0_RSVD_6'
 '@BASEBOARD_FAB2_LIB.BASEBOARD_FAB2(SCH_1):TP_CPU0_RSVD_6':
 C_SIGNAL='@baseboard_fab2_lib.baseboard_fab2(sch_1):tp_cpu0_rsvd_6';
NODE_NAME     U5D1 EE6
 '@BASEBOARD_FAB2_LIB.BASEBOARD_FAB2(SCH_1):PAGE39_I127@CHPSET_LIB.SKX_EXT_B(CHIPS)':
 'RSVD'<6>: CDS_PINID='RSVD(6)';
NET_NAME
'TP_CPU0_RSVD_60'
 '@BASEBOARD_FAB2_LIB.BASEBOARD_FAB2(SCH_1):TP_CPU0_RSVD_60':
 C_SIGNAL='@baseboard_fab2_lib.baseboard_fab2(sch_1):tp_cpu0_rsvd_60';
NODE_NAME     U5D1 CW62
 '@BASEBOARD_FAB2_LIB.BASEBOARD_FAB2(SCH_1):PAGE39_I127@CHPSET_LIB.SKX_EXT_B(CHIPS)':
 'RSVD'<60>: CDS_PINID='RSVD(60)';
NET_NAME
'TP_CPU0_RSVD_61'
 '@BASEBOARD_FAB2_LIB.BASEBOARD_FAB2(SCH_1):TP_CPU0_RSVD_61':
 C_SIGNAL='@baseboard_fab2_lib.baseboard_fab2(sch_1):tp_cpu0_rsvd_61';
NODE_NAME     U5D1 CW60
 '@BASEBOARD_FAB2_LIB.BASEBOARD_FAB2(SCH_1):PAGE39_I127@CHPSET_LIB.SKX_EXT_B(CHIPS)':
 'RSVD'<61>: CDS_PINID='RSVD(61)';
NET_NAME
'TP_CPU0_RSVD_64'
 '@BASEBOARD_FAB2_LIB.BASEBOARD_FAB2(SCH_1):TP_CPU0_RSVD_64':
 C_SIGNAL='@baseboard_fab2_lib.baseboard_fab2(sch_1):tp_cpu0_rsvd_64';
NODE_NAME     U5D1 CV69
 '@BASEBOARD_FAB2_LIB.BASEBOARD_FAB2(SCH_1):PAGE39_I127@CHPSET_LIB.SKX_EXT_B(CHIPS)':
 'RSVD'<64>: CDS_PINID='RSVD(64)';
NET_NAME
'TP_CPU0_RSVD_66'
 '@BASEBOARD_FAB2_LIB.BASEBOARD_FAB2(SCH_1):TP_CPU0_RSVD_66':
 C_SIGNAL='@baseboard_fab2_lib.baseboard_fab2(sch_1):tp_cpu0_rsvd_66';
NODE_NAME     U5D1 CU60
 '@BASEBOARD_FAB2_LIB.BASEBOARD_FAB2(SCH_1):PAGE39_I127@CHPSET_LIB.SKX_EXT_B(CHIPS)':
 'RSVD'<66>: CDS_PINID='RSVD(66)';
NET_NAME
'TP_CPU0_RSVD_67'
 '@BASEBOARD_FAB2_LIB.BASEBOARD_FAB2(SCH_1):TP_CPU0_RSVD_67':
 C_SIGNAL='@baseboard_fab2_lib.baseboard_fab2(sch_1):tp_cpu0_rsvd_67';
NODE_NAME     U5D1 CU6
 '@BASEBOARD_FAB2_LIB.BASEBOARD_FAB2(SCH_1):PAGE39_I127@CHPSET_LIB.SKX_EXT_B(CHIPS)':
 'RSVD'<67>: CDS_PINID='RSVD(67)';
NET_NAME
'TP_CPU0_RSVD_69'
 '@BASEBOARD_FAB2_LIB.BASEBOARD_FAB2(SCH_1):TP_CPU0_RSVD_69':
 C_SIGNAL='@baseboard_fab2_lib.baseboard_fab2(sch_1):tp_cpu0_rsvd_69';
NODE_NAME     U5D1 CT69
 '@BASEBOARD_FAB2_LIB.BASEBOARD_FAB2(SCH_1):PAGE39_I127@CHPSET_LIB.SKX_EXT_B(CHIPS)':
 'RSVD'<69>: CDS_PINID='RSVD(69)';
NET_NAME
'TP_CPU0_RSVD_7'
 '@BASEBOARD_FAB2_LIB.BASEBOARD_FAB2(SCH_1):TP_CPU0_RSVD_7':
 C_SIGNAL='@baseboard_fab2_lib.baseboard_fab2(sch_1):tp_cpu0_rsvd_7';
NODE_NAME     U5D1 EE46
 '@BASEBOARD_FAB2_LIB.BASEBOARD_FAB2(SCH_1):PAGE39_I127@CHPSET_LIB.SKX_EXT_B(CHIPS)':
 'RSVD'<7>: CDS_PINID='RSVD(7)';
NET_NAME
'TP_CPU0_RSVD_70'
 '@BASEBOARD_FAB2_LIB.BASEBOARD_FAB2(SCH_1):TP_CPU0_RSVD_70':
 C_SIGNAL='@baseboard_fab2_lib.baseboard_fab2(sch_1):tp_cpu0_rsvd_70';
NODE_NAME     U5D1 CT5
 '@BASEBOARD_FAB2_LIB.BASEBOARD_FAB2(SCH_1):PAGE39_I127@CHPSET_LIB.SKX_EXT_B(CHIPS)':
 'RSVD'<70>: CDS_PINID='RSVD(70)';
NET_NAME
'TP_CPU0_RSVD_72'
 '@BASEBOARD_FAB2_LIB.BASEBOARD_FAB2(SCH_1):TP_CPU0_RSVD_72':
 C_SIGNAL='@baseboard_fab2_lib.baseboard_fab2(sch_1):tp_cpu0_rsvd_72';
NODE_NAME     U5D1 CR60
 '@BASEBOARD_FAB2_LIB.BASEBOARD_FAB2(SCH_1):PAGE39_I127@CHPSET_LIB.SKX_EXT_B(CHIPS)':
 'RSVD'<72>: CDS_PINID='RSVD(72)';
NET_NAME
'TP_CPU0_RSVD_73'
 '@BASEBOARD_FAB2_LIB.BASEBOARD_FAB2(SCH_1):TP_CPU0_RSVD_73':
 C_SIGNAL='@baseboard_fab2_lib.baseboard_fab2(sch_1):tp_cpu0_rsvd_73';
NODE_NAME     U5D1 CP31
 '@BASEBOARD_FAB2_LIB.BASEBOARD_FAB2(SCH_1):PAGE39_I127@CHPSET_LIB.SKX_EXT_B(CHIPS)':
 'RSVD'<73>: CDS_PINID='RSVD(73)';
NET_NAME
'TP_CPU0_RSVD_8'
 '@BASEBOARD_FAB2_LIB.BASEBOARD_FAB2(SCH_1):TP_CPU0_RSVD_8':
 C_SIGNAL='@baseboard_fab2_lib.baseboard_fab2(sch_1):tp_cpu0_rsvd_8';
NODE_NAME     U5D1 EE16
 '@BASEBOARD_FAB2_LIB.BASEBOARD_FAB2(SCH_1):PAGE39_I127@CHPSET_LIB.SKX_EXT_B(CHIPS)':
 'RSVD'<8>: CDS_PINID='RSVD(8)';
NET_NAME
'TP_CPU0_RSVD_82'
 '@BASEBOARD_FAB2_LIB.BASEBOARD_FAB2(SCH_1):TP_CPU0_RSVD_82':
 C_SIGNAL='@baseboard_fab2_lib.baseboard_fab2(sch_1):tp_cpu0_rsvd_82';
NODE_NAME     U5D1 CK77
 '@BASEBOARD_FAB2_LIB.BASEBOARD_FAB2(SCH_1):PAGE36_I16@CHPSET_LIB.SKX_EXT_B(CHIPS)':
 'RSVD'<82>: CDS_PINID='RSVD(82)';
NET_NAME
'TP_CPU0_RSVD_85'
 '@BASEBOARD_FAB2_LIB.BASEBOARD_FAB2(SCH_1):TP_CPU0_RSVD_85':
 C_SIGNAL='@baseboard_fab2_lib.baseboard_fab2(sch_1):tp_cpu0_rsvd_85';
NODE_NAME     U5D1 CK19
 '@BASEBOARD_FAB2_LIB.BASEBOARD_FAB2(SCH_1):PAGE36_I16@CHPSET_LIB.SKX_EXT_B(CHIPS)':
 'RSVD'<85>: CDS_PINID='RSVD(85)';
NET_NAME
'TP_CPU0_RSVD_9'
 '@BASEBOARD_FAB2_LIB.BASEBOARD_FAB2(SCH_1):TP_CPU0_RSVD_9':
 C_SIGNAL='@baseboard_fab2_lib.baseboard_fab2(sch_1):tp_cpu0_rsvd_9';
NODE_NAME     U5D1 ED83
 '@BASEBOARD_FAB2_LIB.BASEBOARD_FAB2(SCH_1):PAGE39_I127@CHPSET_LIB.SKX_EXT_B(CHIPS)':
 'RSVD'<9>: CDS_PINID='RSVD(9)';
NET_NAME
'TP_CPU0_RSVD_90'
 '@BASEBOARD_FAB2_LIB.BASEBOARD_FAB2(SCH_1):TP_CPU0_RSVD_90':
 C_SIGNAL='@baseboard_fab2_lib.baseboard_fab2(sch_1):tp_cpu0_rsvd_90';
NODE_NAME     U5D1 CH77
 '@BASEBOARD_FAB2_LIB.BASEBOARD_FAB2(SCH_1):PAGE36_I16@CHPSET_LIB.SKX_EXT_B(CHIPS)':
 'RSVD'<90>: CDS_PINID='RSVD(90)';
NET_NAME
'TP_CPU0_RSVD_91'
 '@BASEBOARD_FAB2_LIB.BASEBOARD_FAB2(SCH_1):TP_CPU0_RSVD_91':
 C_SIGNAL='@baseboard_fab2_lib.baseboard_fab2(sch_1):tp_cpu0_rsvd_91';
NODE_NAME     U5D1 CH25
 '@BASEBOARD_FAB2_LIB.BASEBOARD_FAB2(SCH_1):PAGE36_I16@CHPSET_LIB.SKX_EXT_B(CHIPS)':
 'RSVD'<91>: CDS_PINID='RSVD(91)';
NET_NAME
'TP_CPU0_RSVD_94'
 '@BASEBOARD_FAB2_LIB.BASEBOARD_FAB2(SCH_1):TP_CPU0_RSVD_94':
 C_SIGNAL='@baseboard_fab2_lib.baseboard_fab2(sch_1):tp_cpu0_rsvd_94';
NODE_NAME     U5D1 CG82
 '@BASEBOARD_FAB2_LIB.BASEBOARD_FAB2(SCH_1):PAGE36_I15@CHPSET_LIB.SKX_EXT_B(CHIPS)':
 'RSVD'<94>: CDS_PINID='RSVD(94)';
NET_NAME
'TP_CPU0_RSVD_95'
 '@BASEBOARD_FAB2_LIB.BASEBOARD_FAB2(SCH_1):TP_CPU0_RSVD_95':
 C_SIGNAL='@baseboard_fab2_lib.baseboard_fab2(sch_1):tp_cpu0_rsvd_95';
NODE_NAME     U5D1 CG78
 '@BASEBOARD_FAB2_LIB.BASEBOARD_FAB2(SCH_1):PAGE36_I15@CHPSET_LIB.SKX_EXT_B(CHIPS)':
 'RSVD'<95>: CDS_PINID='RSVD(95)';
NET_NAME
'TP_CPU0_RSVD_97'
 '@BASEBOARD_FAB2_LIB.BASEBOARD_FAB2(SCH_1):TP_CPU0_RSVD_97':
 C_SIGNAL='@baseboard_fab2_lib.baseboard_fab2(sch_1):tp_cpu0_rsvd_97';
NODE_NAME     U5D1 CG24
 '@BASEBOARD_FAB2_LIB.BASEBOARD_FAB2(SCH_1):PAGE36_I15@CHPSET_LIB.SKX_EXT_B(CHIPS)':
 'RSVD'<97>: CDS_PINID='RSVD(97)';
NET_NAME
'TP_CPU0_RSVD_99'
 '@BASEBOARD_FAB2_LIB.BASEBOARD_FAB2(SCH_1):TP_CPU0_RSVD_99':
 C_SIGNAL='@baseboard_fab2_lib.baseboard_fab2(sch_1):tp_cpu0_rsvd_99';
NODE_NAME     U5D1 CG10
 '@BASEBOARD_FAB2_LIB.BASEBOARD_FAB2(SCH_1):PAGE36_I15@CHPSET_LIB.SKX_EXT_B(CHIPS)':
 'RSVD'<99>: CDS_PINID='RSVD(99)';
NET_NAME
'TP_CPU0_RSVD_TEST_11'
 '@BASEBOARD_FAB2_LIB.BASEBOARD_FAB2(SCH_1):TP_CPU0_RSVD_TEST_11':
 C_SIGNAL='@baseboard_fab2_lib.baseboard_fab2(sch_1):tp_cpu0_rsvd_test_11';
NODE_NAME     U5D1 AY13
 '@BASEBOARD_FAB2_LIB.BASEBOARD_FAB2(SCH_1):PAGE22_I204@CHPSET_LIB.SKX_EXT_B(CHIPS)':
 'TEST_11': CDS_PINID='TEST_11';
NET_NAME
'TP_CPU0_RSVD_TEST_3'
 '@BASEBOARD_FAB2_LIB.BASEBOARD_FAB2(SCH_1):TP_CPU0_RSVD_TEST_3':
 C_SIGNAL='@baseboard_fab2_lib.baseboard_fab2(sch_1):tp_cpu0_rsvd_test_3';
NODE_NAME     U5D1 AM13
 '@BASEBOARD_FAB2_LIB.BASEBOARD_FAB2(SCH_1):PAGE22_I204@CHPSET_LIB.SKX_EXT_B(CHIPS)':
 'TEST_3': CDS_PINID='TEST_3';
NET_NAME
'TP_CPU0_RSVD_TEST_4'
 '@BASEBOARD_FAB2_LIB.BASEBOARD_FAB2(SCH_1):TP_CPU0_RSVD_TEST_4':
 C_SIGNAL='@baseboard_fab2_lib.baseboard_fab2(sch_1):tp_cpu0_rsvd_test_4';
NODE_NAME     U5D1 AN12
 '@BASEBOARD_FAB2_LIB.BASEBOARD_FAB2(SCH_1):PAGE22_I204@CHPSET_LIB.SKX_EXT_B(CHIPS)':
 'TEST_4': CDS_PINID='TEST_4';
NET_NAME
'TP_CPU0_RSVD_TEST_5'
 '@BASEBOARD_FAB2_LIB.BASEBOARD_FAB2(SCH_1):TP_CPU0_RSVD_TEST_5':
 C_SIGNAL='@baseboard_fab2_lib.baseboard_fab2(sch_1):tp_cpu0_rsvd_test_5';
NODE_NAME     U5D1 AN14
 '@BASEBOARD_FAB2_LIB.BASEBOARD_FAB2(SCH_1):PAGE22_I204@CHPSET_LIB.SKX_EXT_B(CHIPS)':
 'TEST_5': CDS_PINID='TEST_5';
NET_NAME
'TP_CPU0_SOCKET_ID_2'
 '@BASEBOARD_FAB2_LIB.BASEBOARD_FAB2(SCH_1):TP_CPU0_SOCKET_ID_2':
 C_SIGNAL='@baseboard_fab2_lib.baseboard_fab2(sch_1):tp_cpu0_socket_id_2';
NODE_NAME     U5D1 AU20
 '@BASEBOARD_FAB2_LIB.BASEBOARD_FAB2(SCH_1):PAGE21_I259@CHPSET_LIB.SKX_EXT_B(CHIPS)':
 'SOCKET_ID'<2>: CDS_PINID='SOCKET_ID(2)';
NET_NAME
'TP_CPU0_TEST_10'
 '@BASEBOARD_FAB2_LIB.BASEBOARD_FAB2(SCH_1):TP_CPU0_TEST_10':
 C_SIGNAL='@baseboard_fab2_lib.baseboard_fab2(sch_1):tp_cpu0_test_10';
NODE_NAME     U5D1 AW22
 '@BASEBOARD_FAB2_LIB.BASEBOARD_FAB2(SCH_1):PAGE36_I16@CHPSET_LIB.SKX_EXT_B(CHIPS)':
 'TEST_10': CDS_PINID='TEST_10';
NET_NAME
'TP_CPU0_TEST_6'
 '@BASEBOARD_FAB2_LIB.BASEBOARD_FAB2(SCH_1):TP_CPU0_TEST_6':
 C_SIGNAL='@baseboard_fab2_lib.baseboard_fab2(sch_1):tp_cpu0_test_6';
NODE_NAME     U5D1 AR16
 '@BASEBOARD_FAB2_LIB.BASEBOARD_FAB2(SCH_1):PAGE36_I16@CHPSET_LIB.SKX_EXT_B(CHIPS)':
 'TEST_6': CDS_PINID='TEST_6';
NET_NAME
'TP_CPU0_TEST_7'
 '@BASEBOARD_FAB2_LIB.BASEBOARD_FAB2(SCH_1):TP_CPU0_TEST_7':
 C_SIGNAL='@baseboard_fab2_lib.baseboard_fab2(sch_1):tp_cpu0_test_7';
NODE_NAME     U5D1 AU18
 '@BASEBOARD_FAB2_LIB.BASEBOARD_FAB2(SCH_1):PAGE36_I16@CHPSET_LIB.SKX_EXT_B(CHIPS)':
 'TEST_7': CDS_PINID='TEST_7';
NET_NAME
'TP_CPU0_TEST_8'
 '@BASEBOARD_FAB2_LIB.BASEBOARD_FAB2(SCH_1):TP_CPU0_TEST_8':
 C_SIGNAL='@baseboard_fab2_lib.baseboard_fab2(sch_1):tp_cpu0_test_8';
NODE_NAME     U5D1 AW16
 '@BASEBOARD_FAB2_LIB.BASEBOARD_FAB2(SCH_1):PAGE36_I16@CHPSET_LIB.SKX_EXT_B(CHIPS)':
 'TEST_8': CDS_PINID='TEST_8';
NET_NAME
'TP_CPU0_TEST_9'
 '@BASEBOARD_FAB2_LIB.BASEBOARD_FAB2(SCH_1):TP_CPU0_TEST_9':
 C_SIGNAL='@baseboard_fab2_lib.baseboard_fab2(sch_1):tp_cpu0_test_9';
NODE_NAME     U5D1 AW20
 '@BASEBOARD_FAB2_LIB.BASEBOARD_FAB2(SCH_1):PAGE36_I16@CHPSET_LIB.SKX_EXT_B(CHIPS)':
 'TEST_9': CDS_PINID='TEST_9';
NET_NAME
'TP_CPU0_UPI2_RSVD_CA12'
 '@BASEBOARD_FAB2_LIB.BASEBOARD_FAB2(SCH_1):TP_CPU0_UPI2_RSVD_CA12':
 C_SIGNAL='@baseboard_fab2_lib.baseboard_fab2(sch_1):tp_cpu0_upi2_rsvd_ca12';
NODE_NAME     U5D1 DP21
 '@BASEBOARD_FAB2_LIB.BASEBOARD_FAB2(SCH_1):PAGE35_I3@CHPSET_LIB.SKX_EXT_B(CHIPS)':
 'UPI2_TX_DP'<0>: CDS_PINID='UPI2_TX_DP(0)';
NET_NAME
'TP_CPU0_UPI2_RSVD_CB11'
 '@BASEBOARD_FAB2_LIB.BASEBOARD_FAB2(SCH_1):TP_CPU0_UPI2_RSVD_CB11':
 C_SIGNAL='@baseboard_fab2_lib.baseboard_fab2(sch_1):tp_cpu0_upi2_rsvd_cb11';
NODE_NAME     U5D1 DN20
 '@BASEBOARD_FAB2_LIB.BASEBOARD_FAB2(SCH_1):PAGE35_I3@CHPSET_LIB.SKX_EXT_B(CHIPS)':
 'UPI2_TX_DP'<1>: CDS_PINID='UPI2_TX_DP(1)';
NET_NAME
'TP_CPU0_UPI2_RSVD_CC10'
 '@BASEBOARD_FAB2_LIB.BASEBOARD_FAB2(SCH_1):TP_CPU0_UPI2_RSVD_CC10':
 C_SIGNAL='@baseboard_fab2_lib.baseboard_fab2(sch_1):tp_cpu0_upi2_rsvd_cc10';
NODE_NAME     U5D1 DM21
 '@BASEBOARD_FAB2_LIB.BASEBOARD_FAB2(SCH_1):PAGE35_I3@CHPSET_LIB.SKX_EXT_B(CHIPS)':
 'UPI2_TX_DN'<1>: CDS_PINID='UPI2_TX_DN(1)';
NET_NAME
'TP_CPU0_UPI2_RSVD_CC12'
 '@BASEBOARD_FAB2_LIB.BASEBOARD_FAB2(SCH_1):TP_CPU0_UPI2_RSVD_CC12':
 C_SIGNAL='@baseboard_fab2_lib.baseboard_fab2(sch_1):tp_cpu0_upi2_rsvd_cc12';
NODE_NAME     U5D1 DT21
 '@BASEBOARD_FAB2_LIB.BASEBOARD_FAB2(SCH_1):PAGE35_I3@CHPSET_LIB.SKX_EXT_B(CHIPS)':
 'UPI2_TX_DN'<0>: CDS_PINID='UPI2_TX_DN(0)';
NET_NAME
'TP_CPU0_UPI2_RSVD_CD11'
 '@BASEBOARD_FAB2_LIB.BASEBOARD_FAB2(SCH_1):TP_CPU0_UPI2_RSVD_CD11':
 C_SIGNAL='@baseboard_fab2_lib.baseboard_fab2(sch_1):tp_cpu0_upi2_rsvd_cd11';
NODE_NAME     U5D1 DK19
 '@BASEBOARD_FAB2_LIB.BASEBOARD_FAB2(SCH_1):PAGE35_I3@CHPSET_LIB.SKX_EXT_B(CHIPS)':
 'UPI2_TX_DP'<2>: CDS_PINID='UPI2_TX_DP(2)';
NET_NAME
'TP_CPU0_UPI2_RSVD_CE12'
 '@BASEBOARD_FAB2_LIB.BASEBOARD_FAB2(SCH_1):TP_CPU0_UPI2_RSVD_CE12':
 C_SIGNAL='@baseboard_fab2_lib.baseboard_fab2(sch_1):tp_cpu0_upi2_rsvd_ce12';
NODE_NAME     U5D1 DL20
 '@BASEBOARD_FAB2_LIB.BASEBOARD_FAB2(SCH_1):PAGE35_I3@CHPSET_LIB.SKX_EXT_B(CHIPS)':
 'UPI2_TX_DN'<2>: CDS_PINID='UPI2_TX_DN(2)';
NET_NAME
'TP_CPU0_UPI2_RSVD_CF11'
 '@BASEBOARD_FAB2_LIB.BASEBOARD_FAB2(SCH_1):TP_CPU0_UPI2_RSVD_CF11':
 C_SIGNAL='@baseboard_fab2_lib.baseboard_fab2(sch_1):tp_cpu0_upi2_rsvd_cf11';
NODE_NAME     U5D1 DJ20
 '@BASEBOARD_FAB2_LIB.BASEBOARD_FAB2(SCH_1):PAGE35_I3@CHPSET_LIB.SKX_EXT_B(CHIPS)':
 'UPI2_TX_DP'<3>: CDS_PINID='UPI2_TX_DP(3)';
NET_NAME
'TP_CPU0_UPI2_RSVD_CF13'
 '@BASEBOARD_FAB2_LIB.BASEBOARD_FAB2(SCH_1):TP_CPU0_UPI2_RSVD_CF13':
 C_SIGNAL='@baseboard_fab2_lib.baseboard_fab2(sch_1):tp_cpu0_upi2_rsvd_cf13';
NODE_NAME     U5D1 DH19
 '@BASEBOARD_FAB2_LIB.BASEBOARD_FAB2(SCH_1):PAGE35_I3@CHPSET_LIB.SKX_EXT_B(CHIPS)':
 'UPI2_TX_DN'<4>: CDS_PINID='UPI2_TX_DN(4)';
NET_NAME
'TP_CPU0_UPI2_RSVD_CG12'
 '@BASEBOARD_FAB2_LIB.BASEBOARD_FAB2(SCH_1):TP_CPU0_UPI2_RSVD_CG12':
 C_SIGNAL='@baseboard_fab2_lib.baseboard_fab2(sch_1):tp_cpu0_upi2_rsvd_cg12';
NODE_NAME     U5D1 DJ18
 '@BASEBOARD_FAB2_LIB.BASEBOARD_FAB2(SCH_1):PAGE35_I3@CHPSET_LIB.SKX_EXT_B(CHIPS)':
 'UPI2_TX_DP'<4>: CDS_PINID='UPI2_TX_DP(4)';
NET_NAME
'TP_CPU0_UPI2_RSVD_CH11'
 '@BASEBOARD_FAB2_LIB.BASEBOARD_FAB2(SCH_1):TP_CPU0_UPI2_RSVD_CH11':
 C_SIGNAL='@baseboard_fab2_lib.baseboard_fab2(sch_1):tp_cpu0_upi2_rsvd_ch11';
NODE_NAME     U5D1 DG20
 '@BASEBOARD_FAB2_LIB.BASEBOARD_FAB2(SCH_1):PAGE35_I3@CHPSET_LIB.SKX_EXT_B(CHIPS)':
 'UPI2_TX_DN'<3>: CDS_PINID='UPI2_TX_DN(3)';
NET_NAME
'TP_CPU0_UPI2_RSVD_CH13'
 '@BASEBOARD_FAB2_LIB.BASEBOARD_FAB2(SCH_1):TP_CPU0_UPI2_RSVD_CH13':
 C_SIGNAL='@baseboard_fab2_lib.baseboard_fab2(sch_1):tp_cpu0_upi2_rsvd_ch13';
NODE_NAME     U5D1 DH17
 '@BASEBOARD_FAB2_LIB.BASEBOARD_FAB2(SCH_1):PAGE35_I3@CHPSET_LIB.SKX_EXT_B(CHIPS)':
 'UPI2_TX_DP'<5>: CDS_PINID='UPI2_TX_DP(5)';
NET_NAME
'TP_CPU0_UPI2_RSVD_CJ14'
 '@BASEBOARD_FAB2_LIB.BASEBOARD_FAB2(SCH_1):TP_CPU0_UPI2_RSVD_CJ14':
 C_SIGNAL='@baseboard_fab2_lib.baseboard_fab2(sch_1):tp_cpu0_upi2_rsvd_cj14';
NODE_NAME     U5D1 DK17
 '@BASEBOARD_FAB2_LIB.BASEBOARD_FAB2(SCH_1):PAGE35_I3@CHPSET_LIB.SKX_EXT_B(CHIPS)':
 'UPI2_TX_DN'<5>: CDS_PINID='UPI2_TX_DN(5)';
NET_NAME
'TP_CPU0_UPI2_RSVD_CK13'
 '@BASEBOARD_FAB2_LIB.BASEBOARD_FAB2(SCH_1):TP_CPU0_UPI2_RSVD_CK13':
 C_SIGNAL='@baseboard_fab2_lib.baseboard_fab2(sch_1):tp_cpu0_upi2_rsvd_ck13';
NODE_NAME     U5D1 DF17
 '@BASEBOARD_FAB2_LIB.BASEBOARD_FAB2(SCH_1):PAGE35_I3@CHPSET_LIB.SKX_EXT_B(CHIPS)':
 'UPI2_TX_DP'<6>: CDS_PINID='UPI2_TX_DP(6)';
NET_NAME
'TP_CPU0_UPI2_RSVD_CM13'
 '@BASEBOARD_FAB2_LIB.BASEBOARD_FAB2(SCH_1):TP_CPU0_UPI2_RSVD_CM13':
 C_SIGNAL='@baseboard_fab2_lib.baseboard_fab2(sch_1):tp_cpu0_upi2_rsvd_cm13';
NODE_NAME     U5D1 DG18
 '@BASEBOARD_FAB2_LIB.BASEBOARD_FAB2(SCH_1):PAGE35_I3@CHPSET_LIB.SKX_EXT_B(CHIPS)':
 'UPI2_TX_DN'<6>: CDS_PINID='UPI2_TX_DN(6)';
NET_NAME
'TP_CPU0_UPI2_RSVD_CR14'
 '@BASEBOARD_FAB2_LIB.BASEBOARD_FAB2(SCH_1):TP_CPU0_UPI2_RSVD_CR14':
 C_SIGNAL='@baseboard_fab2_lib.baseboard_fab2(sch_1):tp_cpu0_upi2_rsvd_cr14';
NODE_NAME     U5D1 DE16
 '@BASEBOARD_FAB2_LIB.BASEBOARD_FAB2(SCH_1):PAGE35_I3@CHPSET_LIB.SKX_EXT_B(CHIPS)':
 'UPI2_TX_DP'<7>: CDS_PINID='UPI2_TX_DP(7)';
NET_NAME
'TP_CPU0_UPI2_RSVD_CU14'
 '@BASEBOARD_FAB2_LIB.BASEBOARD_FAB2(SCH_1):TP_CPU0_UPI2_RSVD_CU14':
 C_SIGNAL='@baseboard_fab2_lib.baseboard_fab2(sch_1):tp_cpu0_upi2_rsvd_cu14';
NODE_NAME     U5D1 DD17
 '@BASEBOARD_FAB2_LIB.BASEBOARD_FAB2(SCH_1):PAGE35_I3@CHPSET_LIB.SKX_EXT_B(CHIPS)':
 'UPI2_TX_DN'<7>: CDS_PINID='UPI2_TX_DN(7)';
NET_NAME
'TP_CPU0_UPI2_RSVD_CV13'
 '@BASEBOARD_FAB2_LIB.BASEBOARD_FAB2(SCH_1):TP_CPU0_UPI2_RSVD_CV13':
 C_SIGNAL='@baseboard_fab2_lib.baseboard_fab2(sch_1):tp_cpu0_upi2_rsvd_cv13';
NODE_NAME     U5D1 DD15
 '@BASEBOARD_FAB2_LIB.BASEBOARD_FAB2(SCH_1):PAGE35_I3@CHPSET_LIB.SKX_EXT_B(CHIPS)':
 'UPI2_TX_DP'<8>: CDS_PINID='UPI2_TX_DP(8)';
NET_NAME
'TP_CPU0_UPI2_RSVD_CW14'
 '@BASEBOARD_FAB2_LIB.BASEBOARD_FAB2(SCH_1):TP_CPU0_UPI2_RSVD_CW14':
 C_SIGNAL='@baseboard_fab2_lib.baseboard_fab2(sch_1):tp_cpu0_upi2_rsvd_cw14';
NODE_NAME     U5D1 DF15
 '@BASEBOARD_FAB2_LIB.BASEBOARD_FAB2(SCH_1):PAGE35_I3@CHPSET_LIB.SKX_EXT_B(CHIPS)':
 'UPI2_TX_DN'<8>: CDS_PINID='UPI2_TX_DN(8)';
NET_NAME
'TP_CPU0_UPI2_RSVD_CW16'
 '@BASEBOARD_FAB2_LIB.BASEBOARD_FAB2(SCH_1):TP_CPU0_UPI2_RSVD_CW16':
 C_SIGNAL='@baseboard_fab2_lib.baseboard_fab2(sch_1):tp_cpu0_upi2_rsvd_cw16';
NODE_NAME     U5D1 DB15
 '@BASEBOARD_FAB2_LIB.BASEBOARD_FAB2(SCH_1):PAGE35_I3@CHPSET_LIB.SKX_EXT_B(CHIPS)':
 'UPI2_TX_DP'<9>: CDS_PINID='UPI2_TX_DP(9)';
NET_NAME
'TP_CPU0_UPI2_RSVD_DA16'
 '@BASEBOARD_FAB2_LIB.BASEBOARD_FAB2(SCH_1):TP_CPU0_UPI2_RSVD_DA16':
 C_SIGNAL='@baseboard_fab2_lib.baseboard_fab2(sch_1):tp_cpu0_upi2_rsvd_da16';
NODE_NAME     U5D1 DC16
 '@BASEBOARD_FAB2_LIB.BASEBOARD_FAB2(SCH_1):PAGE35_I3@CHPSET_LIB.SKX_EXT_B(CHIPS)':
 'UPI2_TX_DN'<9>: CDS_PINID='UPI2_TX_DN(9)';
NET_NAME
'TP_CPU0_UPI2_RSVD_DB15'
 '@BASEBOARD_FAB2_LIB.BASEBOARD_FAB2(SCH_1):TP_CPU0_UPI2_RSVD_DB15':
 C_SIGNAL='@baseboard_fab2_lib.baseboard_fab2(sch_1):tp_cpu0_upi2_rsvd_db15';
NODE_NAME     U5D1 CW16
 '@BASEBOARD_FAB2_LIB.BASEBOARD_FAB2(SCH_1):PAGE35_I3@CHPSET_LIB.SKX_EXT_B(CHIPS)':
 'UPI2_TX_DP'<10>: CDS_PINID='UPI2_TX_DP(10)';
NET_NAME
'TP_CPU0_UPI2_RSVD_DC16'
 '@BASEBOARD_FAB2_LIB.BASEBOARD_FAB2(SCH_1):TP_CPU0_UPI2_RSVD_DC16':
 C_SIGNAL='@baseboard_fab2_lib.baseboard_fab2(sch_1):tp_cpu0_upi2_rsvd_dc16';
NODE_NAME     U5D1 DA16
 '@BASEBOARD_FAB2_LIB.BASEBOARD_FAB2(SCH_1):PAGE35_I3@CHPSET_LIB.SKX_EXT_B(CHIPS)':
 'UPI2_TX_DN'<10>: CDS_PINID='UPI2_TX_DN(10)';
NET_NAME
'TP_CPU0_UPI2_RSVD_DD15'
 '@BASEBOARD_FAB2_LIB.BASEBOARD_FAB2(SCH_1):TP_CPU0_UPI2_RSVD_DD15':
 C_SIGNAL='@baseboard_fab2_lib.baseboard_fab2(sch_1):tp_cpu0_upi2_rsvd_dd15';
NODE_NAME     U5D1 CV13
 '@BASEBOARD_FAB2_LIB.BASEBOARD_FAB2(SCH_1):PAGE35_I3@CHPSET_LIB.SKX_EXT_B(CHIPS)':
 'UPI2_TX_DP'<11>: CDS_PINID='UPI2_TX_DP(11)';
NET_NAME
'TP_CPU0_UPI2_RSVD_DD17'
 '@BASEBOARD_FAB2_LIB.BASEBOARD_FAB2(SCH_1):TP_CPU0_UPI2_RSVD_DD17':
 C_SIGNAL='@baseboard_fab2_lib.baseboard_fab2(sch_1):tp_cpu0_upi2_rsvd_dd17';
NODE_NAME     U5D1 CU14
 '@BASEBOARD_FAB2_LIB.BASEBOARD_FAB2(SCH_1):PAGE35_I3@CHPSET_LIB.SKX_EXT_B(CHIPS)':
 'UPI2_TX_DN'<12>: CDS_PINID='UPI2_TX_DN(12)';
NET_NAME
'TP_CPU0_UPI2_RSVD_DE16'
 '@BASEBOARD_FAB2_LIB.BASEBOARD_FAB2(SCH_1):TP_CPU0_UPI2_RSVD_DE16':
 C_SIGNAL='@baseboard_fab2_lib.baseboard_fab2(sch_1):tp_cpu0_upi2_rsvd_de16';
NODE_NAME     U5D1 CR14
 '@BASEBOARD_FAB2_LIB.BASEBOARD_FAB2(SCH_1):PAGE35_I3@CHPSET_LIB.SKX_EXT_B(CHIPS)':
 'UPI2_TX_DP'<12>: CDS_PINID='UPI2_TX_DP(12)';
NET_NAME
'TP_CPU0_UPI2_RSVD_DF15'
 '@BASEBOARD_FAB2_LIB.BASEBOARD_FAB2(SCH_1):TP_CPU0_UPI2_RSVD_DF15':
 C_SIGNAL='@baseboard_fab2_lib.baseboard_fab2(sch_1):tp_cpu0_upi2_rsvd_df15';
NODE_NAME     U5D1 CW14
 '@BASEBOARD_FAB2_LIB.BASEBOARD_FAB2(SCH_1):PAGE35_I3@CHPSET_LIB.SKX_EXT_B(CHIPS)':
 'UPI2_TX_DN'<11>: CDS_PINID='UPI2_TX_DN(11)';
NET_NAME
'TP_CPU0_UPI2_RSVD_DF17'
 '@BASEBOARD_FAB2_LIB.BASEBOARD_FAB2(SCH_1):TP_CPU0_UPI2_RSVD_DF17':
 C_SIGNAL='@baseboard_fab2_lib.baseboard_fab2(sch_1):tp_cpu0_upi2_rsvd_df17';
NODE_NAME     U5D1 CK13
 '@BASEBOARD_FAB2_LIB.BASEBOARD_FAB2(SCH_1):PAGE35_I3@CHPSET_LIB.SKX_EXT_B(CHIPS)':
 'UPI2_TX_DP'<13>: CDS_PINID='UPI2_TX_DP(13)';
NET_NAME
'TP_CPU0_UPI2_RSVD_DG18'
 '@BASEBOARD_FAB2_LIB.BASEBOARD_FAB2(SCH_1):TP_CPU0_UPI2_RSVD_DG18':
 C_SIGNAL='@baseboard_fab2_lib.baseboard_fab2(sch_1):tp_cpu0_upi2_rsvd_dg18';
NODE_NAME     U5D1 CM13
 '@BASEBOARD_FAB2_LIB.BASEBOARD_FAB2(SCH_1):PAGE35_I3@CHPSET_LIB.SKX_EXT_B(CHIPS)':
 'UPI2_TX_DN'<13>: CDS_PINID='UPI2_TX_DN(13)';
NET_NAME
'TP_CPU0_UPI2_RSVD_DG20'
 '@BASEBOARD_FAB2_LIB.BASEBOARD_FAB2(SCH_1):TP_CPU0_UPI2_RSVD_DG20':
 C_SIGNAL='@baseboard_fab2_lib.baseboard_fab2(sch_1):tp_cpu0_upi2_rsvd_dg20';
NODE_NAME     U5D1 CH11
 '@BASEBOARD_FAB2_LIB.BASEBOARD_FAB2(SCH_1):PAGE35_I3@CHPSET_LIB.SKX_EXT_B(CHIPS)':
 'UPI2_TX_DN'<16>: CDS_PINID='UPI2_TX_DN(16)';
NET_NAME
'TP_CPU0_UPI2_RSVD_DH17'
 '@BASEBOARD_FAB2_LIB.BASEBOARD_FAB2(SCH_1):TP_CPU0_UPI2_RSVD_DH17':
 C_SIGNAL='@baseboard_fab2_lib.baseboard_fab2(sch_1):tp_cpu0_upi2_rsvd_dh17';
NODE_NAME     U5D1 CH13
 '@BASEBOARD_FAB2_LIB.BASEBOARD_FAB2(SCH_1):PAGE35_I3@CHPSET_LIB.SKX_EXT_B(CHIPS)':
 'UPI2_TX_DP'<14>: CDS_PINID='UPI2_TX_DP(14)';
NET_NAME
'TP_CPU0_UPI2_RSVD_DH19'
 '@BASEBOARD_FAB2_LIB.BASEBOARD_FAB2(SCH_1):TP_CPU0_UPI2_RSVD_DH19':
 C_SIGNAL='@baseboard_fab2_lib.baseboard_fab2(sch_1):tp_cpu0_upi2_rsvd_dh19';
NODE_NAME     U5D1 CF13
 '@BASEBOARD_FAB2_LIB.BASEBOARD_FAB2(SCH_1):PAGE35_I3@CHPSET_LIB.SKX_EXT_B(CHIPS)':
 'UPI2_TX_DN'<15>: CDS_PINID='UPI2_TX_DN(15)';
NET_NAME
'TP_CPU0_UPI2_RSVD_DJ18'
 '@BASEBOARD_FAB2_LIB.BASEBOARD_FAB2(SCH_1):TP_CPU0_UPI2_RSVD_DJ18':
 C_SIGNAL='@baseboard_fab2_lib.baseboard_fab2(sch_1):tp_cpu0_upi2_rsvd_dj18';
NODE_NAME     U5D1 CG12
 '@BASEBOARD_FAB2_LIB.BASEBOARD_FAB2(SCH_1):PAGE35_I3@CHPSET_LIB.SKX_EXT_B(CHIPS)':
 'UPI2_TX_DP'<15>: CDS_PINID='UPI2_TX_DP(15)';
NET_NAME
'TP_CPU0_UPI2_RSVD_DJ20'
 '@BASEBOARD_FAB2_LIB.BASEBOARD_FAB2(SCH_1):TP_CPU0_UPI2_RSVD_DJ20':
 C_SIGNAL='@baseboard_fab2_lib.baseboard_fab2(sch_1):tp_cpu0_upi2_rsvd_dj20';
NODE_NAME     U5D1 CF11
 '@BASEBOARD_FAB2_LIB.BASEBOARD_FAB2(SCH_1):PAGE35_I3@CHPSET_LIB.SKX_EXT_B(CHIPS)':
 'UPI2_TX_DP'<16>: CDS_PINID='UPI2_TX_DP(16)';
NET_NAME
'TP_CPU0_UPI2_RSVD_DK17'
 '@BASEBOARD_FAB2_LIB.BASEBOARD_FAB2(SCH_1):TP_CPU0_UPI2_RSVD_DK17':
 C_SIGNAL='@baseboard_fab2_lib.baseboard_fab2(sch_1):tp_cpu0_upi2_rsvd_dk17';
NODE_NAME     U5D1 CJ14
 '@BASEBOARD_FAB2_LIB.BASEBOARD_FAB2(SCH_1):PAGE35_I3@CHPSET_LIB.SKX_EXT_B(CHIPS)':
 'UPI2_TX_DN'<14>: CDS_PINID='UPI2_TX_DN(14)';
NET_NAME
'TP_CPU0_UPI2_RSVD_DK19'
 '@BASEBOARD_FAB2_LIB.BASEBOARD_FAB2(SCH_1):TP_CPU0_UPI2_RSVD_DK19':
 C_SIGNAL='@baseboard_fab2_lib.baseboard_fab2(sch_1):tp_cpu0_upi2_rsvd_dk19';
NODE_NAME     U5D1 CD11
 '@BASEBOARD_FAB2_LIB.BASEBOARD_FAB2(SCH_1):PAGE35_I3@CHPSET_LIB.SKX_EXT_B(CHIPS)':
 'UPI2_TX_DP'<17>: CDS_PINID='UPI2_TX_DP(17)';
NET_NAME
'TP_CPU0_UPI2_RSVD_DL20'
 '@BASEBOARD_FAB2_LIB.BASEBOARD_FAB2(SCH_1):TP_CPU0_UPI2_RSVD_DL20':
 C_SIGNAL='@baseboard_fab2_lib.baseboard_fab2(sch_1):tp_cpu0_upi2_rsvd_dl20';
NODE_NAME     U5D1 CE12
 '@BASEBOARD_FAB2_LIB.BASEBOARD_FAB2(SCH_1):PAGE35_I3@CHPSET_LIB.SKX_EXT_B(CHIPS)':
 'UPI2_TX_DN'<17>: CDS_PINID='UPI2_TX_DN(17)';
NET_NAME
'TP_CPU0_UPI2_RSVD_DM21'
 '@BASEBOARD_FAB2_LIB.BASEBOARD_FAB2(SCH_1):TP_CPU0_UPI2_RSVD_DM21':
 C_SIGNAL='@baseboard_fab2_lib.baseboard_fab2(sch_1):tp_cpu0_upi2_rsvd_dm21';
NODE_NAME     U5D1 CC10
 '@BASEBOARD_FAB2_LIB.BASEBOARD_FAB2(SCH_1):PAGE35_I3@CHPSET_LIB.SKX_EXT_B(CHIPS)':
 'UPI2_TX_DN'<18>: CDS_PINID='UPI2_TX_DN(18)';
NET_NAME
'TP_CPU0_UPI2_RSVD_DN20'
 '@BASEBOARD_FAB2_LIB.BASEBOARD_FAB2(SCH_1):TP_CPU0_UPI2_RSVD_DN20':
 C_SIGNAL='@baseboard_fab2_lib.baseboard_fab2(sch_1):tp_cpu0_upi2_rsvd_dn20';
NODE_NAME     U5D1 CB11
 '@BASEBOARD_FAB2_LIB.BASEBOARD_FAB2(SCH_1):PAGE35_I3@CHPSET_LIB.SKX_EXT_B(CHIPS)':
 'UPI2_TX_DP'<18>: CDS_PINID='UPI2_TX_DP(18)';
NET_NAME
'TP_CPU0_UPI2_RSVD_DP21'
 '@BASEBOARD_FAB2_LIB.BASEBOARD_FAB2(SCH_1):TP_CPU0_UPI2_RSVD_DP21':
 C_SIGNAL='@baseboard_fab2_lib.baseboard_fab2(sch_1):tp_cpu0_upi2_rsvd_dp21';
NODE_NAME     U5D1 CA12
 '@BASEBOARD_FAB2_LIB.BASEBOARD_FAB2(SCH_1):PAGE35_I3@CHPSET_LIB.SKX_EXT_B(CHIPS)':
 'UPI2_TX_DP'<19>: CDS_PINID='UPI2_TX_DP(19)';
NET_NAME
'TP_CPU0_UPI2_RSVD_DT21'
 '@BASEBOARD_FAB2_LIB.BASEBOARD_FAB2(SCH_1):TP_CPU0_UPI2_RSVD_DT21':
 C_SIGNAL='@baseboard_fab2_lib.baseboard_fab2(sch_1):tp_cpu0_upi2_rsvd_dt21';
NODE_NAME     U5D1 CC12
 '@BASEBOARD_FAB2_LIB.BASEBOARD_FAB2(SCH_1):PAGE35_I3@CHPSET_LIB.SKX_EXT_B(CHIPS)':
 'UPI2_TX_DN'<19>: CDS_PINID='UPI2_TX_DN(19)';
NET_NAME
'TP_CPU1_DMI_RX_DN0'
 '@BASEBOARD_FAB2_LIB.BASEBOARD_FAB2(SCH_1):TP_CPU1_DMI_RX_DN0':
 C_SIGNAL='@baseboard_fab2_lib.baseboard_fab2(sch_1):tp_cpu1_dmi_rx_dn0';
NODE_NAME     U2D1 CK9
 '@BASEBOARD_FAB2_LIB.BASEBOARD_FAB2(SCH_1):PAGE63_I23@CHPSET_LIB.SKX_EXT_B(CHIPS)':
 'DMI_RX_DN'<0>: CDS_PINID='DMI_RX_DN(0)';
NET_NAME
'TP_CPU1_DMI_RX_DN1'
 '@BASEBOARD_FAB2_LIB.BASEBOARD_FAB2(SCH_1):TP_CPU1_DMI_RX_DN1':
 C_SIGNAL='@baseboard_fab2_lib.baseboard_fab2(sch_1):tp_cpu1_dmi_rx_dn1';
NODE_NAME     U2D1 CM11
 '@BASEBOARD_FAB2_LIB.BASEBOARD_FAB2(SCH_1):PAGE63_I23@CHPSET_LIB.SKX_EXT_B(CHIPS)':
 'DMI_RX_DN'<1>: CDS_PINID='DMI_RX_DN(1)';
NET_NAME
'TP_CPU1_DMI_RX_DN2'
 '@BASEBOARD_FAB2_LIB.BASEBOARD_FAB2(SCH_1):TP_CPU1_DMI_RX_DN2':
 C_SIGNAL='@baseboard_fab2_lib.baseboard_fab2(sch_1):tp_cpu1_dmi_rx_dn2';
NODE_NAME     U2D1 CR12
 '@BASEBOARD_FAB2_LIB.BASEBOARD_FAB2(SCH_1):PAGE63_I23@CHPSET_LIB.SKX_EXT_B(CHIPS)':
 'DMI_RX_DN'<2>: CDS_PINID='DMI_RX_DN(2)';
NET_NAME
'TP_CPU1_DMI_RX_DN3'
 '@BASEBOARD_FAB2_LIB.BASEBOARD_FAB2(SCH_1):TP_CPU1_DMI_RX_DN3':
 C_SIGNAL='@baseboard_fab2_lib.baseboard_fab2(sch_1):tp_cpu1_dmi_rx_dn3';
NODE_NAME     U2D1 CT11
 '@BASEBOARD_FAB2_LIB.BASEBOARD_FAB2(SCH_1):PAGE63_I23@CHPSET_LIB.SKX_EXT_B(CHIPS)':
 'DMI_RX_DN'<3>: CDS_PINID='DMI_RX_DN(3)';
NET_NAME
'TP_CPU1_DMI_RX_DP0'
 '@BASEBOARD_FAB2_LIB.BASEBOARD_FAB2(SCH_1):TP_CPU1_DMI_RX_DP0':
 C_SIGNAL='@baseboard_fab2_lib.baseboard_fab2(sch_1):tp_cpu1_dmi_rx_dp0';
NODE_NAME     U2D1 CL10
 '@BASEBOARD_FAB2_LIB.BASEBOARD_FAB2(SCH_1):PAGE63_I23@CHPSET_LIB.SKX_EXT_B(CHIPS)':
 'DMI_RX_DP'<0>: CDS_PINID='DMI_RX_DP(0)';
NET_NAME
'TP_CPU1_DMI_RX_DP1'
 '@BASEBOARD_FAB2_LIB.BASEBOARD_FAB2(SCH_1):TP_CPU1_DMI_RX_DP1':
 C_SIGNAL='@baseboard_fab2_lib.baseboard_fab2(sch_1):tp_cpu1_dmi_rx_dp1';
NODE_NAME     U2D1 CN10
 '@BASEBOARD_FAB2_LIB.BASEBOARD_FAB2(SCH_1):PAGE63_I23@CHPSET_LIB.SKX_EXT_B(CHIPS)':
 'DMI_RX_DP'<1>: CDS_PINID='DMI_RX_DP(1)';
NET_NAME
'TP_CPU1_DMI_RX_DP2'
 '@BASEBOARD_FAB2_LIB.BASEBOARD_FAB2(SCH_1):TP_CPU1_DMI_RX_DP2':
 C_SIGNAL='@baseboard_fab2_lib.baseboard_fab2(sch_1):tp_cpu1_dmi_rx_dp2';
NODE_NAME     U2D1 CP11
 '@BASEBOARD_FAB2_LIB.BASEBOARD_FAB2(SCH_1):PAGE63_I23@CHPSET_LIB.SKX_EXT_B(CHIPS)':
 'DMI_RX_DP'<2>: CDS_PINID='DMI_RX_DP(2)';
NET_NAME
'TP_CPU1_DMI_RX_DP3'
 '@BASEBOARD_FAB2_LIB.BASEBOARD_FAB2(SCH_1):TP_CPU1_DMI_RX_DP3':
 C_SIGNAL='@baseboard_fab2_lib.baseboard_fab2(sch_1):tp_cpu1_dmi_rx_dp3';
NODE_NAME     U2D1 CV11
 '@BASEBOARD_FAB2_LIB.BASEBOARD_FAB2(SCH_1):PAGE63_I23@CHPSET_LIB.SKX_EXT_B(CHIPS)':
 'DMI_RX_DP'<3>: CDS_PINID='DMI_RX_DP(3)';
NET_NAME
'TP_CPU1_DMI_TX_DN0'
 '@BASEBOARD_FAB2_LIB.BASEBOARD_FAB2(SCH_1):TP_CPU1_DMI_TX_DN0':
 C_SIGNAL='@baseboard_fab2_lib.baseboard_fab2(sch_1):tp_cpu1_dmi_tx_dn0';
NODE_NAME     U2D1 CG4
 '@BASEBOARD_FAB2_LIB.BASEBOARD_FAB2(SCH_1):PAGE63_I23@CHPSET_LIB.SKX_EXT_B(CHIPS)':
 'DMI_TX_DN'<0>: CDS_PINID='DMI_TX_DN(0)';
NET_NAME
'TP_CPU1_DMI_TX_DN1'
 '@BASEBOARD_FAB2_LIB.BASEBOARD_FAB2(SCH_1):TP_CPU1_DMI_TX_DN1':
 C_SIGNAL='@baseboard_fab2_lib.baseboard_fab2(sch_1):tp_cpu1_dmi_tx_dn1';
NODE_NAME     U2D1 CJ4
 '@BASEBOARD_FAB2_LIB.BASEBOARD_FAB2(SCH_1):PAGE63_I23@CHPSET_LIB.SKX_EXT_B(CHIPS)':
 'DMI_TX_DN'<1>: CDS_PINID='DMI_TX_DN(1)';
NET_NAME
'TP_CPU1_DMI_TX_DN2'
 '@BASEBOARD_FAB2_LIB.BASEBOARD_FAB2(SCH_1):TP_CPU1_DMI_TX_DN2':
 C_SIGNAL='@baseboard_fab2_lib.baseboard_fab2(sch_1):tp_cpu1_dmi_tx_dn2';
NODE_NAME     U2D1 CN4
 '@BASEBOARD_FAB2_LIB.BASEBOARD_FAB2(SCH_1):PAGE63_I23@CHPSET_LIB.SKX_EXT_B(CHIPS)':
 'DMI_TX_DN'<2>: CDS_PINID='DMI_TX_DN(2)';
NET_NAME
'TP_CPU1_DMI_TX_DN3'
 '@BASEBOARD_FAB2_LIB.BASEBOARD_FAB2(SCH_1):TP_CPU1_DMI_TX_DN3':
 C_SIGNAL='@baseboard_fab2_lib.baseboard_fab2(sch_1):tp_cpu1_dmi_tx_dn3';
NODE_NAME     U2D1 CP5
 '@BASEBOARD_FAB2_LIB.BASEBOARD_FAB2(SCH_1):PAGE63_I23@CHPSET_LIB.SKX_EXT_B(CHIPS)':
 'DMI_TX_DN'<3>: CDS_PINID='DMI_TX_DN(3)';
NET_NAME
'TP_CPU1_DMI_TX_DP0'
 '@BASEBOARD_FAB2_LIB.BASEBOARD_FAB2(SCH_1):TP_CPU1_DMI_TX_DP0':
 C_SIGNAL='@baseboard_fab2_lib.baseboard_fab2(sch_1):tp_cpu1_dmi_tx_dp0';
NODE_NAME     U2D1 CH5
 '@BASEBOARD_FAB2_LIB.BASEBOARD_FAB2(SCH_1):PAGE63_I23@CHPSET_LIB.SKX_EXT_B(CHIPS)':
 'DMI_TX_DP'<0>: CDS_PINID='DMI_TX_DP(0)';
NET_NAME
'TP_CPU1_DMI_TX_DP1'
 '@BASEBOARD_FAB2_LIB.BASEBOARD_FAB2(SCH_1):TP_CPU1_DMI_TX_DP1':
 C_SIGNAL='@baseboard_fab2_lib.baseboard_fab2(sch_1):tp_cpu1_dmi_tx_dp1';
NODE_NAME     U2D1 CL4
 '@BASEBOARD_FAB2_LIB.BASEBOARD_FAB2(SCH_1):PAGE63_I23@CHPSET_LIB.SKX_EXT_B(CHIPS)':
 'DMI_TX_DP'<1>: CDS_PINID='DMI_TX_DP(1)';
NET_NAME
'TP_CPU1_DMI_TX_DP2'
 '@BASEBOARD_FAB2_LIB.BASEBOARD_FAB2(SCH_1):TP_CPU1_DMI_TX_DP2':
 C_SIGNAL='@baseboard_fab2_lib.baseboard_fab2(sch_1):tp_cpu1_dmi_tx_dp2';
NODE_NAME     U2D1 CM3
 '@BASEBOARD_FAB2_LIB.BASEBOARD_FAB2(SCH_1):PAGE63_I23@CHPSET_LIB.SKX_EXT_B(CHIPS)':
 'DMI_TX_DP'<2>: CDS_PINID='DMI_TX_DP(2)';
NET_NAME
'TP_CPU1_DMI_TX_DP3'
 '@BASEBOARD_FAB2_LIB.BASEBOARD_FAB2(SCH_1):TP_CPU1_DMI_TX_DP3':
 C_SIGNAL='@baseboard_fab2_lib.baseboard_fab2(sch_1):tp_cpu1_dmi_tx_dp3';
NODE_NAME     U2D1 CR4
 '@BASEBOARD_FAB2_LIB.BASEBOARD_FAB2(SCH_1):PAGE63_I23@CHPSET_LIB.SKX_EXT_B(CHIPS)':
 'DMI_TX_DP'<3>: CDS_PINID='DMI_TX_DP(3)';
NET_NAME
'TP_CPU1_KTI2_AMONV'
 '@BASEBOARD_FAB2_LIB.BASEBOARD_FAB2(SCH_1):TP_CPU1_KTI2_AMONV':
 C_SIGNAL='@baseboard_fab2_lib.baseboard_fab2(sch_1):tp_cpu1_kti2_amonv';
NODE_NAME     U2D1 CN22
 '@BASEBOARD_FAB2_LIB.BASEBOARD_FAB2(SCH_1):PAGE73_I107@CHPSET_LIB.SKX_EXT_B(CHIPS)':
 'RSVD'<77>: CDS_PINID='RSVD(77)';
NET_NAME
'TP_CPU1_KTI2_DFX_DN'
 '@BASEBOARD_FAB2_LIB.BASEBOARD_FAB2(SCH_1):TP_CPU1_KTI2_DFX_DN':
 C_SIGNAL='@baseboard_fab2_lib.baseboard_fab2(sch_1):tp_cpu1_kti2_dfx_dn';
NODE_NAME     U2D1 CW22
 '@BASEBOARD_FAB2_LIB.BASEBOARD_FAB2(SCH_1):PAGE73_I107@CHPSET_LIB.SKX_EXT_B(CHIPS)':
 'RSVD'<63>: CDS_PINID='RSVD(63)';
NET_NAME
'TP_CPU1_NMI'
 '@BASEBOARD_FAB2_LIB.BASEBOARD_FAB2(SCH_1):TP_CPU1_NMI':
 C_SIGNAL='@baseboard_fab2_lib.baseboard_fab2(sch_1):tp_cpu1_nmi';
NODE_NAME     U2D1 AP11
 '@BASEBOARD_FAB2_LIB.BASEBOARD_FAB2(SCH_1):PAGE55_I172@CHPSET_LIB.SKX_EXT_B(CHIPS)':
 'NMI': CDS_PINID='NMI';
NET_NAME
'TP_CPU1_PROC_DIS_G_N'
 '@BASEBOARD_FAB2_LIB.BASEBOARD_FAB2(SCH_1):TP_CPU1_PROC_DIS_G_N':
 C_SIGNAL='@baseboard_fab2_lib.baseboard_fab2(sch_1):tp_cpu1_proc_dis_g_n';
NODE_NAME     U2D1 AB17
 '@BASEBOARD_FAB2_LIB.BASEBOARD_FAB2(SCH_1):PAGE55_I172@CHPSET_LIB.SKX_EXT_B(CHIPS)':
 'PROCDIS_N': CDS_PINID='PROCDIS_N';
NET_NAME
'TP_CPU1_RSVD_0'
 '@BASEBOARD_FAB2_LIB.BASEBOARD_FAB2(SCH_1):TP_CPU1_RSVD_0':
 C_SIGNAL='@baseboard_fab2_lib.baseboard_fab2(sch_1):tp_cpu1_rsvd_0';
NODE_NAME     U2D1 EF83
 '@BASEBOARD_FAB2_LIB.BASEBOARD_FAB2(SCH_1):PAGE73_I107@CHPSET_LIB.SKX_EXT_B(CHIPS)':
 'RSVD'<0>: CDS_PINID='RSVD(0)';
NET_NAME
'TP_CPU1_RSVD_1'
 '@BASEBOARD_FAB2_LIB.BASEBOARD_FAB2(SCH_1):TP_CPU1_RSVD_1':
 C_SIGNAL='@baseboard_fab2_lib.baseboard_fab2(sch_1):tp_cpu1_rsvd_1';
NODE_NAME     U2D1 EF81
 '@BASEBOARD_FAB2_LIB.BASEBOARD_FAB2(SCH_1):PAGE73_I107@CHPSET_LIB.SKX_EXT_B(CHIPS)':
 'RSVD'<1>: CDS_PINID='RSVD(1)';
NET_NAME
'TP_CPU1_RSVD_10'
 '@BASEBOARD_FAB2_LIB.BASEBOARD_FAB2(SCH_1):TP_CPU1_RSVD_10':
 C_SIGNAL='@baseboard_fab2_lib.baseboard_fab2(sch_1):tp_cpu1_rsvd_10';
NODE_NAME     U2D1 ED5
 '@BASEBOARD_FAB2_LIB.BASEBOARD_FAB2(SCH_1):PAGE73_I107@CHPSET_LIB.SKX_EXT_B(CHIPS)':
 'RSVD'<10>: CDS_PINID='RSVD(10)';
NET_NAME
'TP_CPU1_RSVD_100'
 '@BASEBOARD_FAB2_LIB.BASEBOARD_FAB2(SCH_1):TP_CPU1_RSVD_100':
 C_SIGNAL='@baseboard_fab2_lib.baseboard_fab2(sch_1):tp_cpu1_rsvd_100';
NODE_NAME     U2D1 CF81
 '@BASEBOARD_FAB2_LIB.BASEBOARD_FAB2(SCH_1):PAGE70_I9@CHPSET_LIB.SKX_EXT_B(CHIPS)':
 'RSVD'<100>: CDS_PINID='RSVD(100)';
NET_NAME
'TP_CPU1_RSVD_101'
 '@BASEBOARD_FAB2_LIB.BASEBOARD_FAB2(SCH_1):TP_CPU1_RSVD_101':
 C_SIGNAL='@baseboard_fab2_lib.baseboard_fab2(sch_1):tp_cpu1_rsvd_101';
NODE_NAME     U2D1 CF79
 '@BASEBOARD_FAB2_LIB.BASEBOARD_FAB2(SCH_1):PAGE70_I9@CHPSET_LIB.SKX_EXT_B(CHIPS)':
 'RSVD'<101>: CDS_PINID='RSVD(101)';
NET_NAME
'TP_CPU1_RSVD_105'
 '@BASEBOARD_FAB2_LIB.BASEBOARD_FAB2(SCH_1):TP_CPU1_RSVD_105':
 C_SIGNAL='@baseboard_fab2_lib.baseboard_fab2(sch_1):tp_cpu1_rsvd_105';
NODE_NAME     U2D1 CE80
 '@BASEBOARD_FAB2_LIB.BASEBOARD_FAB2(SCH_1):PAGE70_I9@CHPSET_LIB.SKX_EXT_B(CHIPS)':
 'RSVD'<105>: CDS_PINID='RSVD(105)';
NET_NAME
'TP_CPU1_RSVD_106'
 '@BASEBOARD_FAB2_LIB.BASEBOARD_FAB2(SCH_1):TP_CPU1_RSVD_106':
 C_SIGNAL='@baseboard_fab2_lib.baseboard_fab2(sch_1):tp_cpu1_rsvd_106';
NODE_NAME     U2D1 CE78
 '@BASEBOARD_FAB2_LIB.BASEBOARD_FAB2(SCH_1):PAGE70_I9@CHPSET_LIB.SKX_EXT_B(CHIPS)':
 'RSVD'<106>: CDS_PINID='RSVD(106)';
NET_NAME
'TP_CPU1_RSVD_108'
 '@BASEBOARD_FAB2_LIB.BASEBOARD_FAB2(SCH_1):TP_CPU1_RSVD_108':
 C_SIGNAL='@baseboard_fab2_lib.baseboard_fab2(sch_1):tp_cpu1_rsvd_108';
NODE_NAME     U2D1 CD25
 '@BASEBOARD_FAB2_LIB.BASEBOARD_FAB2(SCH_1):PAGE70_I9@CHPSET_LIB.SKX_EXT_B(CHIPS)':
 'RSVD'<108>: CDS_PINID='RSVD(108)';
NET_NAME
'TP_CPU1_RSVD_11'
 '@BASEBOARD_FAB2_LIB.BASEBOARD_FAB2(SCH_1):TP_CPU1_RSVD_11':
 C_SIGNAL='@baseboard_fab2_lib.baseboard_fab2(sch_1):tp_cpu1_rsvd_11';
NODE_NAME     U2D1 ED45
 '@BASEBOARD_FAB2_LIB.BASEBOARD_FAB2(SCH_1):PAGE73_I107@CHPSET_LIB.SKX_EXT_B(CHIPS)':
 'RSVD'<11>: CDS_PINID='RSVD(11)';
NET_NAME
'TP_CPU1_RSVD_111'
 '@BASEBOARD_FAB2_LIB.BASEBOARD_FAB2(SCH_1):TP_CPU1_RSVD_111':
 C_SIGNAL='@baseboard_fab2_lib.baseboard_fab2(sch_1):tp_cpu1_rsvd_111';
NODE_NAME     U2D1 CC6
 '@BASEBOARD_FAB2_LIB.BASEBOARD_FAB2(SCH_1):PAGE70_I9@CHPSET_LIB.SKX_EXT_B(CHIPS)':
 'RSVD'<111>: CDS_PINID='RSVD(111)';
NET_NAME
'TP_CPU1_RSVD_113'
 '@BASEBOARD_FAB2_LIB.BASEBOARD_FAB2(SCH_1):TP_CPU1_RSVD_113':
 C_SIGNAL='@baseboard_fab2_lib.baseboard_fab2(sch_1):tp_cpu1_rsvd_113';
NODE_NAME     U2D1 CB5
 '@BASEBOARD_FAB2_LIB.BASEBOARD_FAB2(SCH_1):PAGE70_I9@CHPSET_LIB.SKX_EXT_B(CHIPS)':
 'RSVD'<113>: CDS_PINID='RSVD(113)';
NET_NAME
'TP_CPU1_RSVD_114'
 '@BASEBOARD_FAB2_LIB.BASEBOARD_FAB2(SCH_1):TP_CPU1_RSVD_114':
 C_SIGNAL='@baseboard_fab2_lib.baseboard_fab2(sch_1):tp_cpu1_rsvd_114';
NODE_NAME     U2D1 CB25
 '@BASEBOARD_FAB2_LIB.BASEBOARD_FAB2(SCH_1):PAGE70_I9@CHPSET_LIB.SKX_EXT_B(CHIPS)':
 'RSVD'<114>: CDS_PINID='RSVD(114)';
NET_NAME
'TP_CPU1_RSVD_117'
 '@BASEBOARD_FAB2_LIB.BASEBOARD_FAB2(SCH_1):TP_CPU1_RSVD_117':
 C_SIGNAL='@baseboard_fab2_lib.baseboard_fab2(sch_1):tp_cpu1_rsvd_117';
NODE_NAME     U2D1 CA24
 '@BASEBOARD_FAB2_LIB.BASEBOARD_FAB2(SCH_1):PAGE70_I9@CHPSET_LIB.SKX_EXT_B(CHIPS)':
 'RSVD'<117>: CDS_PINID='RSVD(117)';
NET_NAME
'TP_CPU1_RSVD_119'
 '@BASEBOARD_FAB2_LIB.BASEBOARD_FAB2(SCH_1):TP_CPU1_RSVD_119':
 C_SIGNAL='@baseboard_fab2_lib.baseboard_fab2(sch_1):tp_cpu1_rsvd_119';
NODE_NAME     U2D1 BY25
 '@BASEBOARD_FAB2_LIB.BASEBOARD_FAB2(SCH_1):PAGE70_I9@CHPSET_LIB.SKX_EXT_B(CHIPS)':
 'RSVD'<119>: CDS_PINID='RSVD(119)';
NET_NAME
'TP_CPU1_RSVD_12'
 '@BASEBOARD_FAB2_LIB.BASEBOARD_FAB2(SCH_1):TP_CPU1_RSVD_12':
 C_SIGNAL='@baseboard_fab2_lib.baseboard_fab2(sch_1):tp_cpu1_rsvd_12';
NODE_NAME     U2D1 EC84
 '@BASEBOARD_FAB2_LIB.BASEBOARD_FAB2(SCH_1):PAGE73_I107@CHPSET_LIB.SKX_EXT_B(CHIPS)':
 'RSVD'<12>: CDS_PINID='RSVD(12)';
NET_NAME
'TP_CPU1_RSVD_121'
 '@BASEBOARD_FAB2_LIB.BASEBOARD_FAB2(SCH_1):TP_CPU1_RSVD_121':
 C_SIGNAL='@baseboard_fab2_lib.baseboard_fab2(sch_1):tp_cpu1_rsvd_121';
NODE_NAME     U2D1 BW22
 '@BASEBOARD_FAB2_LIB.BASEBOARD_FAB2(SCH_1):PAGE70_I9@CHPSET_LIB.SKX_EXT_B(CHIPS)':
 'RSVD'<121>: CDS_PINID='RSVD(121)';
NET_NAME
'TP_CPU1_RSVD_123'
 '@BASEBOARD_FAB2_LIB.BASEBOARD_FAB2(SCH_1):TP_CPU1_RSVD_123':
 C_SIGNAL='@baseboard_fab2_lib.baseboard_fab2(sch_1):tp_cpu1_rsvd_123';
NODE_NAME     U2D1 BW10
 '@BASEBOARD_FAB2_LIB.BASEBOARD_FAB2(SCH_1):PAGE70_I9@CHPSET_LIB.SKX_EXT_B(CHIPS)':
 'RSVD'<123>: CDS_PINID='RSVD(123)';
NET_NAME
'TP_CPU1_RSVD_124'
 '@BASEBOARD_FAB2_LIB.BASEBOARD_FAB2(SCH_1):TP_CPU1_RSVD_124':
 C_SIGNAL='@baseboard_fab2_lib.baseboard_fab2(sch_1):tp_cpu1_rsvd_124';
NODE_NAME     U2D1 BV23
 '@BASEBOARD_FAB2_LIB.BASEBOARD_FAB2(SCH_1):PAGE70_I9@CHPSET_LIB.SKX_EXT_B(CHIPS)':
 'RSVD'<124>: CDS_PINID='RSVD(124)';
NET_NAME
'TP_CPU1_RSVD_13'
 '@BASEBOARD_FAB2_LIB.BASEBOARD_FAB2(SCH_1):TP_CPU1_RSVD_13':
 C_SIGNAL='@baseboard_fab2_lib.baseboard_fab2(sch_1):tp_cpu1_rsvd_13';
NODE_NAME     U2D1 EC44
 '@BASEBOARD_FAB2_LIB.BASEBOARD_FAB2(SCH_1):PAGE73_I107@CHPSET_LIB.SKX_EXT_B(CHIPS)':
 'RSVD'<13>: CDS_PINID='RSVD(13)';
NET_NAME
'TP_CPU1_RSVD_14'
 '@BASEBOARD_FAB2_LIB.BASEBOARD_FAB2(SCH_1):TP_CPU1_RSVD_14':
 C_SIGNAL='@baseboard_fab2_lib.baseboard_fab2(sch_1):tp_cpu1_rsvd_14';
NODE_NAME     U2D1 EC4
 '@BASEBOARD_FAB2_LIB.BASEBOARD_FAB2(SCH_1):PAGE73_I107@CHPSET_LIB.SKX_EXT_B(CHIPS)':
 'RSVD'<14>: CDS_PINID='RSVD(14)';
NET_NAME
'TP_CPU1_RSVD_144'
 '@BASEBOARD_FAB2_LIB.BASEBOARD_FAB2(SCH_1):TP_CPU1_RSVD_144':
 C_SIGNAL='@baseboard_fab2_lib.baseboard_fab2(sch_1):tp_cpu1_rsvd_144';
NODE_NAME     U2D1 BG20
 '@BASEBOARD_FAB2_LIB.BASEBOARD_FAB2(SCH_1):PAGE70_I9@CHPSET_LIB.SKX_EXT_B(CHIPS)':
 'RSVD'<144>: CDS_PINID='RSVD(144)';
NET_NAME
'TP_CPU1_RSVD_145'
 '@BASEBOARD_FAB2_LIB.BASEBOARD_FAB2(SCH_1):TP_CPU1_RSVD_145':
 C_SIGNAL='@baseboard_fab2_lib.baseboard_fab2(sch_1):tp_cpu1_rsvd_145';
NODE_NAME     U2D1 BG18
 '@BASEBOARD_FAB2_LIB.BASEBOARD_FAB2(SCH_1):PAGE70_I9@CHPSET_LIB.SKX_EXT_B(CHIPS)':
 'RSVD'<145>: CDS_PINID='RSVD(145)';
NET_NAME
'TP_CPU1_RSVD_146'
 '@BASEBOARD_FAB2_LIB.BASEBOARD_FAB2(SCH_1):TP_CPU1_RSVD_146':
 C_SIGNAL='@baseboard_fab2_lib.baseboard_fab2(sch_1):tp_cpu1_rsvd_146';
NODE_NAME     U2D1 BF21
 '@BASEBOARD_FAB2_LIB.BASEBOARD_FAB2(SCH_1):PAGE70_I9@CHPSET_LIB.SKX_EXT_B(CHIPS)':
 'RSVD'<146>: CDS_PINID='RSVD(146)';
NET_NAME
'TP_CPU1_RSVD_147'
 '@BASEBOARD_FAB2_LIB.BASEBOARD_FAB2(SCH_1):TP_CPU1_RSVD_147':
 C_SIGNAL='@baseboard_fab2_lib.baseboard_fab2(sch_1):tp_cpu1_rsvd_147';
NODE_NAME     U2D1 BE22
 '@BASEBOARD_FAB2_LIB.BASEBOARD_FAB2(SCH_1):PAGE70_I9@CHPSET_LIB.SKX_EXT_B(CHIPS)':
 'RSVD'<147>: CDS_PINID='RSVD(147)';
NET_NAME
'TP_CPU1_RSVD_148'
 '@BASEBOARD_FAB2_LIB.BASEBOARD_FAB2(SCH_1):TP_CPU1_RSVD_148':
 C_SIGNAL='@baseboard_fab2_lib.baseboard_fab2(sch_1):tp_cpu1_rsvd_148';
NODE_NAME     U2D1 BE20
 '@BASEBOARD_FAB2_LIB.BASEBOARD_FAB2(SCH_1):PAGE70_I9@CHPSET_LIB.SKX_EXT_B(CHIPS)':
 'RSVD'<148>: CDS_PINID='RSVD(148)';
NET_NAME
'TP_CPU1_RSVD_149'
 '@BASEBOARD_FAB2_LIB.BASEBOARD_FAB2(SCH_1):TP_CPU1_RSVD_149':
 C_SIGNAL='@baseboard_fab2_lib.baseboard_fab2(sch_1):tp_cpu1_rsvd_149';
NODE_NAME     U2D1 BE18
 '@BASEBOARD_FAB2_LIB.BASEBOARD_FAB2(SCH_1):PAGE70_I9@CHPSET_LIB.SKX_EXT_B(CHIPS)':
 'RSVD'<149>: CDS_PINID='RSVD(149)';
NET_NAME
'TP_CPU1_RSVD_15'
 '@BASEBOARD_FAB2_LIB.BASEBOARD_FAB2(SCH_1):TP_CPU1_RSVD_15':
 C_SIGNAL='@baseboard_fab2_lib.baseboard_fab2(sch_1):tp_cpu1_rsvd_15';
NODE_NAME     U2D1 EC16
 '@BASEBOARD_FAB2_LIB.BASEBOARD_FAB2(SCH_1):PAGE73_I107@CHPSET_LIB.SKX_EXT_B(CHIPS)':
 'RSVD'<15>: CDS_PINID='RSVD(15)';
NET_NAME
'TP_CPU1_RSVD_150'
 '@BASEBOARD_FAB2_LIB.BASEBOARD_FAB2(SCH_1):TP_CPU1_RSVD_150':
 C_SIGNAL='@baseboard_fab2_lib.baseboard_fab2(sch_1):tp_cpu1_rsvd_150';
NODE_NAME     U2D1 BD69
 '@BASEBOARD_FAB2_LIB.BASEBOARD_FAB2(SCH_1):PAGE70_I9@CHPSET_LIB.SKX_EXT_B(CHIPS)':
 'RSVD'<150>: CDS_PINID='RSVD(150)';
NET_NAME
'TP_CPU1_RSVD_151'
 '@BASEBOARD_FAB2_LIB.BASEBOARD_FAB2(SCH_1):TP_CPU1_RSVD_151':
 C_SIGNAL='@baseboard_fab2_lib.baseboard_fab2(sch_1):tp_cpu1_rsvd_151';
NODE_NAME     U2D1 BD67
 '@BASEBOARD_FAB2_LIB.BASEBOARD_FAB2(SCH_1):PAGE70_I9@CHPSET_LIB.SKX_EXT_B(CHIPS)':
 'RSVD'<151>: CDS_PINID='RSVD(151)';
NET_NAME
'TP_CPU1_RSVD_152'
 '@BASEBOARD_FAB2_LIB.BASEBOARD_FAB2(SCH_1):TP_CPU1_RSVD_152':
 C_SIGNAL='@baseboard_fab2_lib.baseboard_fab2(sch_1):tp_cpu1_rsvd_152';
NODE_NAME     U2D1 BD65
 '@BASEBOARD_FAB2_LIB.BASEBOARD_FAB2(SCH_1):PAGE70_I9@CHPSET_LIB.SKX_EXT_B(CHIPS)':
 'RSVD'<152>: CDS_PINID='RSVD(152)';
NET_NAME
'TP_CPU1_RSVD_154'
 '@BASEBOARD_FAB2_LIB.BASEBOARD_FAB2(SCH_1):TP_CPU1_RSVD_154':
 C_SIGNAL='@baseboard_fab2_lib.baseboard_fab2(sch_1):tp_cpu1_rsvd_154';
NODE_NAME     U2D1 BD19
 '@BASEBOARD_FAB2_LIB.BASEBOARD_FAB2(SCH_1):PAGE70_I9@CHPSET_LIB.SKX_EXT_B(CHIPS)':
 'RSVD'<154>: CDS_PINID='RSVD(154)';
NET_NAME
'TP_CPU1_RSVD_155'
 '@BASEBOARD_FAB2_LIB.BASEBOARD_FAB2(SCH_1):TP_CPU1_RSVD_155':
 C_SIGNAL='@baseboard_fab2_lib.baseboard_fab2(sch_1):tp_cpu1_rsvd_155';
NODE_NAME     U2D1 BD17
 '@BASEBOARD_FAB2_LIB.BASEBOARD_FAB2(SCH_1):PAGE70_I9@CHPSET_LIB.SKX_EXT_B(CHIPS)':
 'RSVD'<155>: CDS_PINID='RSVD(155)';
NET_NAME
'TP_CPU1_RSVD_156'
 '@BASEBOARD_FAB2_LIB.BASEBOARD_FAB2(SCH_1):TP_CPU1_RSVD_156':
 C_SIGNAL='@baseboard_fab2_lib.baseboard_fab2(sch_1):tp_cpu1_rsvd_156';
NODE_NAME     U2D1 BC68
 '@BASEBOARD_FAB2_LIB.BASEBOARD_FAB2(SCH_1):PAGE70_I9@CHPSET_LIB.SKX_EXT_B(CHIPS)':
 'RSVD'<156>: CDS_PINID='RSVD(156)';
NET_NAME
'TP_CPU1_RSVD_157'
 '@BASEBOARD_FAB2_LIB.BASEBOARD_FAB2(SCH_1):TP_CPU1_RSVD_157':
 C_SIGNAL='@baseboard_fab2_lib.baseboard_fab2(sch_1):tp_cpu1_rsvd_157';
NODE_NAME     U2D1 BC66
 '@BASEBOARD_FAB2_LIB.BASEBOARD_FAB2(SCH_1):PAGE70_I9@CHPSET_LIB.SKX_EXT_B(CHIPS)':
 'RSVD'<157>: CDS_PINID='RSVD(157)';
NET_NAME
'TP_CPU1_RSVD_158'
 '@BASEBOARD_FAB2_LIB.BASEBOARD_FAB2(SCH_1):TP_CPU1_RSVD_158':
 C_SIGNAL='@baseboard_fab2_lib.baseboard_fab2(sch_1):tp_cpu1_rsvd_158';
NODE_NAME     U2D1 BC64
 '@BASEBOARD_FAB2_LIB.BASEBOARD_FAB2(SCH_1):PAGE70_I9@CHPSET_LIB.SKX_EXT_B(CHIPS)':
 'RSVD'<158>: CDS_PINID='RSVD(158)';
NET_NAME
'TP_CPU1_RSVD_159'
 '@BASEBOARD_FAB2_LIB.BASEBOARD_FAB2(SCH_1):TP_CPU1_RSVD_159':
 C_SIGNAL='@baseboard_fab2_lib.baseboard_fab2(sch_1):tp_cpu1_rsvd_159';
NODE_NAME     U2D1 BC22
 '@BASEBOARD_FAB2_LIB.BASEBOARD_FAB2(SCH_1):PAGE70_I9@CHPSET_LIB.SKX_EXT_B(CHIPS)':
 'RSVD'<159>: CDS_PINID='RSVD(159)';
NET_NAME
'TP_CPU1_RSVD_16'
 '@BASEBOARD_FAB2_LIB.BASEBOARD_FAB2(SCH_1):TP_CPU1_RSVD_16':
 C_SIGNAL='@baseboard_fab2_lib.baseboard_fab2(sch_1):tp_cpu1_rsvd_16';
NODE_NAME     U2D1 EB85
 '@BASEBOARD_FAB2_LIB.BASEBOARD_FAB2(SCH_1):PAGE73_I107@CHPSET_LIB.SKX_EXT_B(CHIPS)':
 'RSVD'<16>: CDS_PINID='RSVD(16)';
NET_NAME
'TP_CPU1_RSVD_160'
 '@BASEBOARD_FAB2_LIB.BASEBOARD_FAB2(SCH_1):TP_CPU1_RSVD_160':
 C_SIGNAL='@baseboard_fab2_lib.baseboard_fab2(sch_1):tp_cpu1_rsvd_160';
NODE_NAME     U2D1 BC20
 '@BASEBOARD_FAB2_LIB.BASEBOARD_FAB2(SCH_1):PAGE70_I9@CHPSET_LIB.SKX_EXT_B(CHIPS)':
 'RSVD'<160>: CDS_PINID='RSVD(160)';
NET_NAME
'TP_CPU1_RSVD_161'
 '@BASEBOARD_FAB2_LIB.BASEBOARD_FAB2(SCH_1):TP_CPU1_RSVD_161':
 C_SIGNAL='@baseboard_fab2_lib.baseboard_fab2(sch_1):tp_cpu1_rsvd_161';
NODE_NAME     U2D1 BC18
 '@BASEBOARD_FAB2_LIB.BASEBOARD_FAB2(SCH_1):PAGE70_I9@CHPSET_LIB.SKX_EXT_B(CHIPS)':
 'RSVD'<161>: CDS_PINID='RSVD(161)';
NET_NAME
'TP_CPU1_RSVD_162'
 '@BASEBOARD_FAB2_LIB.BASEBOARD_FAB2(SCH_1):TP_CPU1_RSVD_162':
 C_SIGNAL='@baseboard_fab2_lib.baseboard_fab2(sch_1):tp_cpu1_rsvd_162';
NODE_NAME     U2D1 BC14
 '@BASEBOARD_FAB2_LIB.BASEBOARD_FAB2(SCH_1):PAGE70_I9@CHPSET_LIB.SKX_EXT_B(CHIPS)':
 'RSVD'<162>: CDS_PINID='RSVD(162)';
NET_NAME
'TP_CPU1_RSVD_163'
 '@BASEBOARD_FAB2_LIB.BASEBOARD_FAB2(SCH_1):TP_CPU1_RSVD_163':
 C_SIGNAL='@baseboard_fab2_lib.baseboard_fab2(sch_1):tp_cpu1_rsvd_163';
NODE_NAME     U2D1 BB67
 '@BASEBOARD_FAB2_LIB.BASEBOARD_FAB2(SCH_1):PAGE70_I9@CHPSET_LIB.SKX_EXT_B(CHIPS)':
 'RSVD'<163>: CDS_PINID='RSVD(163)';
NET_NAME
'TP_CPU1_RSVD_164'
 '@BASEBOARD_FAB2_LIB.BASEBOARD_FAB2(SCH_1):TP_CPU1_RSVD_164':
 C_SIGNAL='@baseboard_fab2_lib.baseboard_fab2(sch_1):tp_cpu1_rsvd_164';
NODE_NAME     U2D1 BB65
 '@BASEBOARD_FAB2_LIB.BASEBOARD_FAB2(SCH_1):PAGE70_I9@CHPSET_LIB.SKX_EXT_B(CHIPS)':
 'RSVD'<164>: CDS_PINID='RSVD(164)';
NET_NAME
'TP_CPU1_RSVD_166'
 '@BASEBOARD_FAB2_LIB.BASEBOARD_FAB2(SCH_1):TP_CPU1_RSVD_166':
 C_SIGNAL='@baseboard_fab2_lib.baseboard_fab2(sch_1):tp_cpu1_rsvd_166';
NODE_NAME     U2D1 BB21
 '@BASEBOARD_FAB2_LIB.BASEBOARD_FAB2(SCH_1):PAGE70_I9@CHPSET_LIB.SKX_EXT_B(CHIPS)':
 'RSVD'<166>: CDS_PINID='RSVD(166)';
NET_NAME
'TP_CPU1_RSVD_167'
 '@BASEBOARD_FAB2_LIB.BASEBOARD_FAB2(SCH_1):TP_CPU1_RSVD_167':
 C_SIGNAL='@baseboard_fab2_lib.baseboard_fab2(sch_1):tp_cpu1_rsvd_167';
NODE_NAME     U2D1 BB17
 '@BASEBOARD_FAB2_LIB.BASEBOARD_FAB2(SCH_1):PAGE70_I9@CHPSET_LIB.SKX_EXT_B(CHIPS)':
 'RSVD'<167>: CDS_PINID='RSVD(167)';
NET_NAME
'TP_CPU1_RSVD_168'
 '@BASEBOARD_FAB2_LIB.BASEBOARD_FAB2(SCH_1):TP_CPU1_RSVD_168':
 C_SIGNAL='@baseboard_fab2_lib.baseboard_fab2(sch_1):tp_cpu1_rsvd_168';
NODE_NAME     U2D1 BB15
 '@BASEBOARD_FAB2_LIB.BASEBOARD_FAB2(SCH_1):PAGE70_I9@CHPSET_LIB.SKX_EXT_B(CHIPS)':
 'RSVD'<168>: CDS_PINID='RSVD(168)';
NET_NAME
'TP_CPU1_RSVD_169'
 '@BASEBOARD_FAB2_LIB.BASEBOARD_FAB2(SCH_1):TP_CPU1_RSVD_169':
 C_SIGNAL='@baseboard_fab2_lib.baseboard_fab2(sch_1):tp_cpu1_rsvd_169';
NODE_NAME     U2D1 BB13
 '@BASEBOARD_FAB2_LIB.BASEBOARD_FAB2(SCH_1):PAGE70_I9@CHPSET_LIB.SKX_EXT_B(CHIPS)':
 'RSVD'<169>: CDS_PINID='RSVD(169)';
NET_NAME
'TP_CPU1_RSVD_17'
 '@BASEBOARD_FAB2_LIB.BASEBOARD_FAB2(SCH_1):TP_CPU1_RSVD_17':
 C_SIGNAL='@baseboard_fab2_lib.baseboard_fab2(sch_1):tp_cpu1_rsvd_17';
NODE_NAME     U2D1 EB5
 '@BASEBOARD_FAB2_LIB.BASEBOARD_FAB2(SCH_1):PAGE73_I107@CHPSET_LIB.SKX_EXT_B(CHIPS)':
 'RSVD'<17>: CDS_PINID='RSVD(17)';
NET_NAME
'TP_CPU1_RSVD_170'
 '@BASEBOARD_FAB2_LIB.BASEBOARD_FAB2(SCH_1):TP_CPU1_RSVD_170':
 C_SIGNAL='@baseboard_fab2_lib.baseboard_fab2(sch_1):tp_cpu1_rsvd_170';
NODE_NAME     U2D1 BA82
 '@BASEBOARD_FAB2_LIB.BASEBOARD_FAB2(SCH_1):PAGE70_I9@CHPSET_LIB.SKX_EXT_B(CHIPS)':
 'RSVD'<170>: CDS_PINID='RSVD(170)';
NET_NAME
'TP_CPU1_RSVD_171'
 '@BASEBOARD_FAB2_LIB.BASEBOARD_FAB2(SCH_1):TP_CPU1_RSVD_171':
 C_SIGNAL='@baseboard_fab2_lib.baseboard_fab2(sch_1):tp_cpu1_rsvd_171';
NODE_NAME     U2D1 BA78
 '@BASEBOARD_FAB2_LIB.BASEBOARD_FAB2(SCH_1):PAGE70_I9@CHPSET_LIB.SKX_EXT_B(CHIPS)':
 'RSVD'<171>: CDS_PINID='RSVD(171)';
NET_NAME
'TP_CPU1_RSVD_172'
 '@BASEBOARD_FAB2_LIB.BASEBOARD_FAB2(SCH_1):TP_CPU1_RSVD_172':
 C_SIGNAL='@baseboard_fab2_lib.baseboard_fab2(sch_1):tp_cpu1_rsvd_172';
NODE_NAME     U2D1 BA76
 '@BASEBOARD_FAB2_LIB.BASEBOARD_FAB2(SCH_1):PAGE63_I23@CHPSET_LIB.SKX_EXT_B(CHIPS)':
 'RSVD'<172>: CDS_PINID='RSVD(172)';
NET_NAME
'TP_CPU1_RSVD_173'
 '@BASEBOARD_FAB2_LIB.BASEBOARD_FAB2(SCH_1):TP_CPU1_RSVD_173':
 C_SIGNAL='@baseboard_fab2_lib.baseboard_fab2(sch_1):tp_cpu1_rsvd_173';
NODE_NAME     U2D1 BA66
 '@BASEBOARD_FAB2_LIB.BASEBOARD_FAB2(SCH_1):PAGE63_I23@CHPSET_LIB.SKX_EXT_B(CHIPS)':
 'RSVD'<173>: CDS_PINID='RSVD(173)';
NET_NAME
'TP_CPU1_RSVD_174'
 '@BASEBOARD_FAB2_LIB.BASEBOARD_FAB2(SCH_1):TP_CPU1_RSVD_174':
 C_SIGNAL='@baseboard_fab2_lib.baseboard_fab2(sch_1):tp_cpu1_rsvd_174';
NODE_NAME     U2D1 BA64
 '@BASEBOARD_FAB2_LIB.BASEBOARD_FAB2(SCH_1):PAGE63_I23@CHPSET_LIB.SKX_EXT_B(CHIPS)':
 'RSVD'<174>: CDS_PINID='RSVD(174)';
NET_NAME
'TP_CPU1_RSVD_175'
 '@BASEBOARD_FAB2_LIB.BASEBOARD_FAB2(SCH_1):TP_CPU1_RSVD_175':
 C_SIGNAL='@baseboard_fab2_lib.baseboard_fab2(sch_1):tp_cpu1_rsvd_175';
NODE_NAME     U2D1 BA22
 '@BASEBOARD_FAB2_LIB.BASEBOARD_FAB2(SCH_1):PAGE63_I23@CHPSET_LIB.SKX_EXT_B(CHIPS)':
 'RSVD'<175>: CDS_PINID='RSVD(175)';
NET_NAME
'TP_CPU1_RSVD_176'
 '@BASEBOARD_FAB2_LIB.BASEBOARD_FAB2(SCH_1):TP_CPU1_RSVD_176':
 C_SIGNAL='@baseboard_fab2_lib.baseboard_fab2(sch_1):tp_cpu1_rsvd_176';
NODE_NAME     U2D1 BA18
 '@BASEBOARD_FAB2_LIB.BASEBOARD_FAB2(SCH_1):PAGE63_I23@CHPSET_LIB.SKX_EXT_B(CHIPS)':
 'RSVD'<176>: CDS_PINID='RSVD(176)';
NET_NAME
'TP_CPU1_RSVD_177'
 '@BASEBOARD_FAB2_LIB.BASEBOARD_FAB2(SCH_1):TP_CPU1_RSVD_177':
 C_SIGNAL='@baseboard_fab2_lib.baseboard_fab2(sch_1):tp_cpu1_rsvd_177';
NODE_NAME     U2D1 BA16
 '@BASEBOARD_FAB2_LIB.BASEBOARD_FAB2(SCH_1):PAGE63_I23@CHPSET_LIB.SKX_EXT_B(CHIPS)':
 'RSVD'<177>: CDS_PINID='RSVD(177)';
NET_NAME
'TP_CPU1_RSVD_178'
 '@BASEBOARD_FAB2_LIB.BASEBOARD_FAB2(SCH_1):TP_CPU1_RSVD_178':
 C_SIGNAL='@baseboard_fab2_lib.baseboard_fab2(sch_1):tp_cpu1_rsvd_178';
NODE_NAME     U2D1 BA14
 '@BASEBOARD_FAB2_LIB.BASEBOARD_FAB2(SCH_1):PAGE63_I23@CHPSET_LIB.SKX_EXT_B(CHIPS)':
 'RSVD'<178>: CDS_PINID='RSVD(178)';
NET_NAME
'TP_CPU1_RSVD_179'
 '@BASEBOARD_FAB2_LIB.BASEBOARD_FAB2(SCH_1):TP_CPU1_RSVD_179':
 C_SIGNAL='@baseboard_fab2_lib.baseboard_fab2(sch_1):tp_cpu1_rsvd_179';
NODE_NAME     U2D1 AY77
 '@BASEBOARD_FAB2_LIB.BASEBOARD_FAB2(SCH_1):PAGE63_I23@CHPSET_LIB.SKX_EXT_B(CHIPS)':
 'RSVD'<179>: CDS_PINID='RSVD(179)';
NET_NAME
'TP_CPU1_RSVD_18'
 '@BASEBOARD_FAB2_LIB.BASEBOARD_FAB2(SCH_1):TP_CPU1_RSVD_18':
 C_SIGNAL='@baseboard_fab2_lib.baseboard_fab2(sch_1):tp_cpu1_rsvd_18';
NODE_NAME     U2D1 EB3
 '@BASEBOARD_FAB2_LIB.BASEBOARD_FAB2(SCH_1):PAGE73_I107@CHPSET_LIB.SKX_EXT_B(CHIPS)':
 'RSVD'<18>: CDS_PINID='RSVD(18)';
NET_NAME
'TP_CPU1_RSVD_180'
 '@BASEBOARD_FAB2_LIB.BASEBOARD_FAB2(SCH_1):TP_CPU1_RSVD_180':
 C_SIGNAL='@baseboard_fab2_lib.baseboard_fab2(sch_1):tp_cpu1_rsvd_180';
NODE_NAME     U2D1 AY75
 '@BASEBOARD_FAB2_LIB.BASEBOARD_FAB2(SCH_1):PAGE63_I23@CHPSET_LIB.SKX_EXT_B(CHIPS)':
 'RSVD'<180>: CDS_PINID='RSVD(180)';
NET_NAME
'TP_CPU1_RSVD_181'
 '@BASEBOARD_FAB2_LIB.BASEBOARD_FAB2(SCH_1):TP_CPU1_RSVD_181':
 C_SIGNAL='@baseboard_fab2_lib.baseboard_fab2(sch_1):tp_cpu1_rsvd_181';
NODE_NAME     U2D1 AY67
 '@BASEBOARD_FAB2_LIB.BASEBOARD_FAB2(SCH_1):PAGE63_I23@CHPSET_LIB.SKX_EXT_B(CHIPS)':
 'RSVD'<181>: CDS_PINID='RSVD(181)';
NET_NAME
'TP_CPU1_RSVD_182'
 '@BASEBOARD_FAB2_LIB.BASEBOARD_FAB2(SCH_1):TP_CPU1_RSVD_182':
 C_SIGNAL='@baseboard_fab2_lib.baseboard_fab2(sch_1):tp_cpu1_rsvd_182';
NODE_NAME     U2D1 AY65
 '@BASEBOARD_FAB2_LIB.BASEBOARD_FAB2(SCH_1):PAGE63_I23@CHPSET_LIB.SKX_EXT_B(CHIPS)':
 'RSVD'<182>: CDS_PINID='RSVD(182)';
NET_NAME
'TP_CPU1_RSVD_183'
 '@BASEBOARD_FAB2_LIB.BASEBOARD_FAB2(SCH_1):TP_CPU1_RSVD_183':
 C_SIGNAL='@baseboard_fab2_lib.baseboard_fab2(sch_1):tp_cpu1_rsvd_183';
NODE_NAME     U2D1 AW76
 '@BASEBOARD_FAB2_LIB.BASEBOARD_FAB2(SCH_1):PAGE63_I23@CHPSET_LIB.SKX_EXT_B(CHIPS)':
 'RSVD'<183>: CDS_PINID='RSVD(183)';
NET_NAME
'TP_CPU1_RSVD_184'
 '@BASEBOARD_FAB2_LIB.BASEBOARD_FAB2(SCH_1):TP_CPU1_RSVD_184':
 C_SIGNAL='@baseboard_fab2_lib.baseboard_fab2(sch_1):tp_cpu1_rsvd_184';
NODE_NAME     U2D1 AW64
 '@BASEBOARD_FAB2_LIB.BASEBOARD_FAB2(SCH_1):PAGE63_I23@CHPSET_LIB.SKX_EXT_B(CHIPS)':
 'RSVD'<184>: CDS_PINID='RSVD(184)';
NET_NAME
'TP_CPU1_RSVD_186'
 '@BASEBOARD_FAB2_LIB.BASEBOARD_FAB2(SCH_1):TP_CPU1_RSVD_186':
 C_SIGNAL='@baseboard_fab2_lib.baseboard_fab2(sch_1):tp_cpu1_rsvd_186';
NODE_NAME     U2D1 AV77
 '@BASEBOARD_FAB2_LIB.BASEBOARD_FAB2(SCH_1):PAGE63_I23@CHPSET_LIB.SKX_EXT_B(CHIPS)':
 'RSVD'<186>: CDS_PINID='RSVD(186)';
NET_NAME
'TP_CPU1_RSVD_189'
 '@BASEBOARD_FAB2_LIB.BASEBOARD_FAB2(SCH_1):TP_CPU1_RSVD_189':
 C_SIGNAL='@baseboard_fab2_lib.baseboard_fab2(sch_1):tp_cpu1_rsvd_189';
NODE_NAME     U2D1 AT13
 '@BASEBOARD_FAB2_LIB.BASEBOARD_FAB2(SCH_1):PAGE63_I23@CHPSET_LIB.SKX_EXT_B(CHIPS)':
 'RSVD'<189>: CDS_PINID='RSVD(189)';
NET_NAME
'TP_CPU1_RSVD_19'
 '@BASEBOARD_FAB2_LIB.BASEBOARD_FAB2(SCH_1):TP_CPU1_RSVD_19':
 C_SIGNAL='@baseboard_fab2_lib.baseboard_fab2(sch_1):tp_cpu1_rsvd_19';
NODE_NAME     U2D1 EA44
 '@BASEBOARD_FAB2_LIB.BASEBOARD_FAB2(SCH_1):PAGE73_I107@CHPSET_LIB.SKX_EXT_B(CHIPS)':
 'RSVD'<19>: CDS_PINID='RSVD(19)';
NET_NAME
'TP_CPU1_RSVD_190'
 '@BASEBOARD_FAB2_LIB.BASEBOARD_FAB2(SCH_1):TP_CPU1_RSVD_190':
 C_SIGNAL='@baseboard_fab2_lib.baseboard_fab2(sch_1):tp_cpu1_rsvd_190';
NODE_NAME     U2D1 AR62
 '@BASEBOARD_FAB2_LIB.BASEBOARD_FAB2(SCH_1):PAGE63_I23@CHPSET_LIB.SKX_EXT_B(CHIPS)':
 'RSVD'<190>: CDS_PINID='RSVD(190)';
NET_NAME
'TP_CPU1_RSVD_194'
 '@BASEBOARD_FAB2_LIB.BASEBOARD_FAB2(SCH_1):TP_CPU1_RSVD_194':
 C_SIGNAL='@baseboard_fab2_lib.baseboard_fab2(sch_1):tp_cpu1_rsvd_194';
NODE_NAME     U2D1 AP61
 '@BASEBOARD_FAB2_LIB.BASEBOARD_FAB2(SCH_1):PAGE56_I169@CHPSET_LIB.SKX_EXT_B(CHIPS)':
 'RSVD'<194>: CDS_PINID='RSVD(194)';
NET_NAME
'TP_CPU1_RSVD_198'
 '@BASEBOARD_FAB2_LIB.BASEBOARD_FAB2(SCH_1):TP_CPU1_RSVD_198':
 C_SIGNAL='@baseboard_fab2_lib.baseboard_fab2(sch_1):tp_cpu1_rsvd_198';
NODE_NAME     U2D1 AN62
 '@BASEBOARD_FAB2_LIB.BASEBOARD_FAB2(SCH_1):PAGE56_I169@CHPSET_LIB.SKX_EXT_B(CHIPS)':
 'RSVD'<198>: CDS_PINID='RSVD(198)';
NET_NAME
'TP_CPU1_RSVD_199'
 '@BASEBOARD_FAB2_LIB.BASEBOARD_FAB2(SCH_1):TP_CPU1_RSVD_199':
 C_SIGNAL='@baseboard_fab2_lib.baseboard_fab2(sch_1):tp_cpu1_rsvd_199';
NODE_NAME     U2D1 AN60
 '@BASEBOARD_FAB2_LIB.BASEBOARD_FAB2(SCH_1):PAGE56_I169@CHPSET_LIB.SKX_EXT_B(CHIPS)':
 'RSVD'<199>: CDS_PINID='RSVD(199)';
NET_NAME
'TP_CPU1_RSVD_2'
 '@BASEBOARD_FAB2_LIB.BASEBOARD_FAB2(SCH_1):TP_CPU1_RSVD_2':
 C_SIGNAL='@baseboard_fab2_lib.baseboard_fab2(sch_1):tp_cpu1_rsvd_2';
NODE_NAME     U2D1 EF77
 '@BASEBOARD_FAB2_LIB.BASEBOARD_FAB2(SCH_1):PAGE73_I107@CHPSET_LIB.SKX_EXT_B(CHIPS)':
 'RSVD'<2>: CDS_PINID='RSVD(2)';
NET_NAME
'TP_CPU1_RSVD_20'
 '@BASEBOARD_FAB2_LIB.BASEBOARD_FAB2(SCH_1):TP_CPU1_RSVD_20':
 C_SIGNAL='@baseboard_fab2_lib.baseboard_fab2(sch_1):tp_cpu1_rsvd_20';
NODE_NAME     U2D1 EA4
 '@BASEBOARD_FAB2_LIB.BASEBOARD_FAB2(SCH_1):PAGE73_I107@CHPSET_LIB.SKX_EXT_B(CHIPS)':
 'RSVD'<20>: CDS_PINID='RSVD(20)';
NET_NAME
'TP_CPU1_RSVD_204'
 '@BASEBOARD_FAB2_LIB.BASEBOARD_FAB2(SCH_1):TP_CPU1_RSVD_204':
 C_SIGNAL='@baseboard_fab2_lib.baseboard_fab2(sch_1):tp_cpu1_rsvd_204';
NODE_NAME     U2D1 AM61
 '@BASEBOARD_FAB2_LIB.BASEBOARD_FAB2(SCH_1):PAGE56_I169@CHPSET_LIB.SKX_EXT_B(CHIPS)':
 'RSVD'<204>: CDS_PINID='RSVD(204)';
NET_NAME
'TP_CPU1_RSVD_205'
 '@BASEBOARD_FAB2_LIB.BASEBOARD_FAB2(SCH_1):TP_CPU1_RSVD_205':
 C_SIGNAL='@baseboard_fab2_lib.baseboard_fab2(sch_1):tp_cpu1_rsvd_205';
NODE_NAME     U2D1 AM59
 '@BASEBOARD_FAB2_LIB.BASEBOARD_FAB2(SCH_1):PAGE56_I169@CHPSET_LIB.SKX_EXT_B(CHIPS)':
 'RSVD'<205>: CDS_PINID='RSVD(205)';
NET_NAME
'TP_CPU1_RSVD_208'
 '@BASEBOARD_FAB2_LIB.BASEBOARD_FAB2(SCH_1):TP_CPU1_RSVD_208':
 C_SIGNAL='@baseboard_fab2_lib.baseboard_fab2(sch_1):tp_cpu1_rsvd_208';
NODE_NAME     U2D1 AM23
 '@BASEBOARD_FAB2_LIB.BASEBOARD_FAB2(SCH_1):PAGE56_I169@CHPSET_LIB.SKX_EXT_B(CHIPS)':
 'RSVD'<208>: CDS_PINID='RSVD(208)';
NET_NAME
'TP_CPU1_RSVD_21'
 '@BASEBOARD_FAB2_LIB.BASEBOARD_FAB2(SCH_1):TP_CPU1_RSVD_21':
 C_SIGNAL='@baseboard_fab2_lib.baseboard_fab2(sch_1):tp_cpu1_rsvd_21';
NODE_NAME     U2D1 DY3
 '@BASEBOARD_FAB2_LIB.BASEBOARD_FAB2(SCH_1):PAGE73_I107@CHPSET_LIB.SKX_EXT_B(CHIPS)':
 'RSVD'<21>: CDS_PINID='RSVD(21)';
NET_NAME
'TP_CPU1_RSVD_210'
 '@BASEBOARD_FAB2_LIB.BASEBOARD_FAB2(SCH_1):TP_CPU1_RSVD_210':
 C_SIGNAL='@baseboard_fab2_lib.baseboard_fab2(sch_1):tp_cpu1_rsvd_210';
NODE_NAME     U2D1 AL62
 '@BASEBOARD_FAB2_LIB.BASEBOARD_FAB2(SCH_1):PAGE56_I169@CHPSET_LIB.SKX_EXT_B(CHIPS)':
 'RSVD'<210>: CDS_PINID='RSVD(210)';
NET_NAME
'TP_CPU1_RSVD_211'
 '@BASEBOARD_FAB2_LIB.BASEBOARD_FAB2(SCH_1):TP_CPU1_RSVD_211':
 C_SIGNAL='@baseboard_fab2_lib.baseboard_fab2(sch_1):tp_cpu1_rsvd_211';
NODE_NAME     U2D1 AL60
 '@BASEBOARD_FAB2_LIB.BASEBOARD_FAB2(SCH_1):PAGE56_I169@CHPSET_LIB.SKX_EXT_B(CHIPS)':
 'RSVD'<211>: CDS_PINID='RSVD(211)';
NET_NAME
'TP_CPU1_RSVD_212'
 '@BASEBOARD_FAB2_LIB.BASEBOARD_FAB2(SCH_1):TP_CPU1_RSVD_212':
 C_SIGNAL='@baseboard_fab2_lib.baseboard_fab2(sch_1):tp_cpu1_rsvd_212';
NODE_NAME     U2D1 AL58
 '@BASEBOARD_FAB2_LIB.BASEBOARD_FAB2(SCH_1):PAGE56_I169@CHPSET_LIB.SKX_EXT_B(CHIPS)':
 'RSVD'<212>: CDS_PINID='RSVD(212)';
NET_NAME
'TP_CPU1_RSVD_214'
 '@BASEBOARD_FAB2_LIB.BASEBOARD_FAB2(SCH_1):TP_CPU1_RSVD_214':
 C_SIGNAL='@baseboard_fab2_lib.baseboard_fab2(sch_1):tp_cpu1_rsvd_214';
NODE_NAME     U2D1 AL22
 '@BASEBOARD_FAB2_LIB.BASEBOARD_FAB2(SCH_1):PAGE56_I169@CHPSET_LIB.SKX_EXT_B(CHIPS)':
 'RSVD'<214>: CDS_PINID='RSVD(214)';
NET_NAME
'TP_CPU1_RSVD_216'
 '@BASEBOARD_FAB2_LIB.BASEBOARD_FAB2(SCH_1):TP_CPU1_RSVD_216':
 C_SIGNAL='@baseboard_fab2_lib.baseboard_fab2(sch_1):tp_cpu1_rsvd_216';
NODE_NAME     U2D1 AK69
 '@BASEBOARD_FAB2_LIB.BASEBOARD_FAB2(SCH_1):PAGE56_I169@CHPSET_LIB.SKX_EXT_B(CHIPS)':
 'RSVD'<216>: CDS_PINID='RSVD(216)';
NET_NAME
'TP_CPU1_RSVD_217'
 '@BASEBOARD_FAB2_LIB.BASEBOARD_FAB2(SCH_1):TP_CPU1_RSVD_217':
 C_SIGNAL='@baseboard_fab2_lib.baseboard_fab2(sch_1):tp_cpu1_rsvd_217';
NODE_NAME     U2D1 AK61
 '@BASEBOARD_FAB2_LIB.BASEBOARD_FAB2(SCH_1):PAGE56_I169@CHPSET_LIB.SKX_EXT_B(CHIPS)':
 'RSVD'<217>: CDS_PINID='RSVD(217)';
NET_NAME
'TP_CPU1_RSVD_218'
 '@BASEBOARD_FAB2_LIB.BASEBOARD_FAB2(SCH_1):TP_CPU1_RSVD_218':
 C_SIGNAL='@baseboard_fab2_lib.baseboard_fab2(sch_1):tp_cpu1_rsvd_218';
NODE_NAME     U2D1 AK59
 '@BASEBOARD_FAB2_LIB.BASEBOARD_FAB2(SCH_1):PAGE56_I169@CHPSET_LIB.SKX_EXT_B(CHIPS)':
 'RSVD'<218>: CDS_PINID='RSVD(218)';
NET_NAME
'TP_CPU1_RSVD_219'
 '@BASEBOARD_FAB2_LIB.BASEBOARD_FAB2(SCH_1):TP_CPU1_RSVD_219':
 C_SIGNAL='@baseboard_fab2_lib.baseboard_fab2(sch_1):tp_cpu1_rsvd_219';
NODE_NAME     U2D1 AK57
 '@BASEBOARD_FAB2_LIB.BASEBOARD_FAB2(SCH_1):PAGE56_I169@CHPSET_LIB.SKX_EXT_B(CHIPS)':
 'RSVD'<219>: CDS_PINID='RSVD(219)';
NET_NAME
'TP_CPU1_RSVD_22'
 '@BASEBOARD_FAB2_LIB.BASEBOARD_FAB2(SCH_1):TP_CPU1_RSVD_22':
 C_SIGNAL='@baseboard_fab2_lib.baseboard_fab2(sch_1):tp_cpu1_rsvd_22';
NODE_NAME     U2D1 DW46
 '@BASEBOARD_FAB2_LIB.BASEBOARD_FAB2(SCH_1):PAGE73_I107@CHPSET_LIB.SKX_EXT_B(CHIPS)':
 'RSVD'<22>: CDS_PINID='RSVD(22)';
NET_NAME
'TP_CPU1_RSVD_222'
 '@BASEBOARD_FAB2_LIB.BASEBOARD_FAB2(SCH_1):TP_CPU1_RSVD_222':
 C_SIGNAL='@baseboard_fab2_lib.baseboard_fab2(sch_1):tp_cpu1_rsvd_222';
NODE_NAME     U2D1 AJ70
 '@BASEBOARD_FAB2_LIB.BASEBOARD_FAB2(SCH_1):PAGE56_I169@CHPSET_LIB.SKX_EXT_B(CHIPS)':
 'RSVD'<222>: CDS_PINID='RSVD(222)';
NET_NAME
'TP_CPU1_RSVD_223'
 '@BASEBOARD_FAB2_LIB.BASEBOARD_FAB2(SCH_1):TP_CPU1_RSVD_223':
 C_SIGNAL='@baseboard_fab2_lib.baseboard_fab2(sch_1):tp_cpu1_rsvd_223';
NODE_NAME     U2D1 AJ62
 '@BASEBOARD_FAB2_LIB.BASEBOARD_FAB2(SCH_1):PAGE56_I169@CHPSET_LIB.SKX_EXT_B(CHIPS)':
 'RSVD'<223>: CDS_PINID='RSVD(223)';
NET_NAME
'TP_CPU1_RSVD_224'
 '@BASEBOARD_FAB2_LIB.BASEBOARD_FAB2(SCH_1):TP_CPU1_RSVD_224':
 C_SIGNAL='@baseboard_fab2_lib.baseboard_fab2(sch_1):tp_cpu1_rsvd_224';
NODE_NAME     U2D1 AJ60
 '@BASEBOARD_FAB2_LIB.BASEBOARD_FAB2(SCH_1):PAGE56_I169@CHPSET_LIB.SKX_EXT_B(CHIPS)':
 'RSVD'<224>: CDS_PINID='RSVD(224)';
NET_NAME
'TP_CPU1_RSVD_225'
 '@BASEBOARD_FAB2_LIB.BASEBOARD_FAB2(SCH_1):TP_CPU1_RSVD_225':
 C_SIGNAL='@baseboard_fab2_lib.baseboard_fab2(sch_1):tp_cpu1_rsvd_225';
NODE_NAME     U2D1 AJ58
 '@BASEBOARD_FAB2_LIB.BASEBOARD_FAB2(SCH_1):PAGE56_I169@CHPSET_LIB.SKX_EXT_B(CHIPS)':
 'RSVD'<225>: CDS_PINID='RSVD(225)';
NET_NAME
'TP_CPU1_RSVD_226'
 '@BASEBOARD_FAB2_LIB.BASEBOARD_FAB2(SCH_1):TP_CPU1_RSVD_226':
 C_SIGNAL='@baseboard_fab2_lib.baseboard_fab2(sch_1):tp_cpu1_rsvd_226';
NODE_NAME     U2D1 AJ56
 '@BASEBOARD_FAB2_LIB.BASEBOARD_FAB2(SCH_1):PAGE56_I169@CHPSET_LIB.SKX_EXT_B(CHIPS)':
 'RSVD'<226>: CDS_PINID='RSVD(226)';
NET_NAME
'TP_CPU1_RSVD_227'
 '@BASEBOARD_FAB2_LIB.BASEBOARD_FAB2(SCH_1):TP_CPU1_RSVD_227':
 C_SIGNAL='@baseboard_fab2_lib.baseboard_fab2(sch_1):tp_cpu1_rsvd_227';
NODE_NAME     U2D1 AJ20
 '@BASEBOARD_FAB2_LIB.BASEBOARD_FAB2(SCH_1):PAGE56_I169@CHPSET_LIB.SKX_EXT_B(CHIPS)':
 'RSVD'<227>: CDS_PINID='RSVD(227)';
NET_NAME
'TP_CPU1_RSVD_228'
 '@BASEBOARD_FAB2_LIB.BASEBOARD_FAB2(SCH_1):TP_CPU1_RSVD_228':
 C_SIGNAL='@baseboard_fab2_lib.baseboard_fab2(sch_1):tp_cpu1_rsvd_228';
NODE_NAME     U2D1 AH73
 '@BASEBOARD_FAB2_LIB.BASEBOARD_FAB2(SCH_1):PAGE56_I169@CHPSET_LIB.SKX_EXT_B(CHIPS)':
 'RSVD'<228>: CDS_PINID='RSVD(228)';
NET_NAME
'TP_CPU1_RSVD_229'
 '@BASEBOARD_FAB2_LIB.BASEBOARD_FAB2(SCH_1):TP_CPU1_RSVD_229':
 C_SIGNAL='@baseboard_fab2_lib.baseboard_fab2(sch_1):tp_cpu1_rsvd_229';
NODE_NAME     U2D1 AH71
 '@BASEBOARD_FAB2_LIB.BASEBOARD_FAB2(SCH_1):PAGE56_I169@CHPSET_LIB.SKX_EXT_B(CHIPS)':
 'RSVD'<229>: CDS_PINID='RSVD(229)';
NET_NAME
'TP_CPU1_RSVD_23'
 '@BASEBOARD_FAB2_LIB.BASEBOARD_FAB2(SCH_1):TP_CPU1_RSVD_23':
 C_SIGNAL='@baseboard_fab2_lib.baseboard_fab2(sch_1):tp_cpu1_rsvd_23';
NODE_NAME     U2D1 DW44
 '@BASEBOARD_FAB2_LIB.BASEBOARD_FAB2(SCH_1):PAGE73_I107@CHPSET_LIB.SKX_EXT_B(CHIPS)':
 'RSVD'<23>: CDS_PINID='RSVD(23)';
NET_NAME
'TP_CPU1_RSVD_230'
 '@BASEBOARD_FAB2_LIB.BASEBOARD_FAB2(SCH_1):TP_CPU1_RSVD_230':
 C_SIGNAL='@baseboard_fab2_lib.baseboard_fab2(sch_1):tp_cpu1_rsvd_230';
NODE_NAME     U2D1 AH57
 '@BASEBOARD_FAB2_LIB.BASEBOARD_FAB2(SCH_1):PAGE56_I169@CHPSET_LIB.SKX_EXT_B(CHIPS)':
 'RSVD'<230>: CDS_PINID='RSVD(230)';
NET_NAME
'TP_CPU1_RSVD_231'
 '@BASEBOARD_FAB2_LIB.BASEBOARD_FAB2(SCH_1):TP_CPU1_RSVD_231':
 C_SIGNAL='@baseboard_fab2_lib.baseboard_fab2(sch_1):tp_cpu1_rsvd_231';
NODE_NAME     U2D1 AH55
 '@BASEBOARD_FAB2_LIB.BASEBOARD_FAB2(SCH_1):PAGE56_I169@CHPSET_LIB.SKX_EXT_B(CHIPS)':
 'RSVD'<231>: CDS_PINID='RSVD(231)';
NET_NAME
'TP_CPU1_RSVD_232'
 '@BASEBOARD_FAB2_LIB.BASEBOARD_FAB2(SCH_1):TP_CPU1_RSVD_232':
 C_SIGNAL='@baseboard_fab2_lib.baseboard_fab2(sch_1):tp_cpu1_rsvd_232';
NODE_NAME     U2D1 AH19
 '@BASEBOARD_FAB2_LIB.BASEBOARD_FAB2(SCH_1):PAGE56_I169@CHPSET_LIB.SKX_EXT_B(CHIPS)':
 'RSVD'<232>: CDS_PINID='RSVD(232)';
NET_NAME
'TP_CPU1_RSVD_233'
 '@BASEBOARD_FAB2_LIB.BASEBOARD_FAB2(SCH_1):TP_CPU1_RSVD_233':
 C_SIGNAL='@baseboard_fab2_lib.baseboard_fab2(sch_1):tp_cpu1_rsvd_233';
NODE_NAME     U2D1 AH15
 '@BASEBOARD_FAB2_LIB.BASEBOARD_FAB2(SCH_1):PAGE56_I169@CHPSET_LIB.SKX_EXT_B(CHIPS)':
 'RSVD'<233>: CDS_PINID='RSVD(233)';
NET_NAME
'TP_CPU1_RSVD_234'
 '@BASEBOARD_FAB2_LIB.BASEBOARD_FAB2(SCH_1):TP_CPU1_RSVD_234':
 C_SIGNAL='@baseboard_fab2_lib.baseboard_fab2(sch_1):tp_cpu1_rsvd_234';
NODE_NAME     U2D1 AG72
 '@BASEBOARD_FAB2_LIB.BASEBOARD_FAB2(SCH_1):PAGE56_I169@CHPSET_LIB.SKX_EXT_B(CHIPS)':
 'RSVD'<234>: CDS_PINID='RSVD(234)';
NET_NAME
'TP_CPU1_RSVD_235'
 '@BASEBOARD_FAB2_LIB.BASEBOARD_FAB2(SCH_1):TP_CPU1_RSVD_235':
 C_SIGNAL='@baseboard_fab2_lib.baseboard_fab2(sch_1):tp_cpu1_rsvd_235';
NODE_NAME     U2D1 AG56
 '@BASEBOARD_FAB2_LIB.BASEBOARD_FAB2(SCH_1):PAGE56_I169@CHPSET_LIB.SKX_EXT_B(CHIPS)':
 'RSVD'<235>: CDS_PINID='RSVD(235)';
NET_NAME
'TP_CPU1_RSVD_236'
 '@BASEBOARD_FAB2_LIB.BASEBOARD_FAB2(SCH_1):TP_CPU1_RSVD_236':
 C_SIGNAL='@baseboard_fab2_lib.baseboard_fab2(sch_1):tp_cpu1_rsvd_236';
NODE_NAME     U2D1 AG54
 '@BASEBOARD_FAB2_LIB.BASEBOARD_FAB2(SCH_1):PAGE56_I169@CHPSET_LIB.SKX_EXT_B(CHIPS)':
 'RSVD'<236>: CDS_PINID='RSVD(236)';
NET_NAME
'TP_CPU1_RSVD_237'
 '@BASEBOARD_FAB2_LIB.BASEBOARD_FAB2(SCH_1):TP_CPU1_RSVD_237':
 C_SIGNAL='@baseboard_fab2_lib.baseboard_fab2(sch_1):tp_cpu1_rsvd_237';
NODE_NAME     U2D1 AG52
 '@BASEBOARD_FAB2_LIB.BASEBOARD_FAB2(SCH_1):PAGE56_I169@CHPSET_LIB.SKX_EXT_B(CHIPS)':
 'RSVD'<237>: CDS_PINID='RSVD(237)';
NET_NAME
'TP_CPU1_RSVD_238'
 '@BASEBOARD_FAB2_LIB.BASEBOARD_FAB2(SCH_1):TP_CPU1_RSVD_238':
 C_SIGNAL='@baseboard_fab2_lib.baseboard_fab2(sch_1):tp_cpu1_rsvd_238';
NODE_NAME     U2D1 AG50
 '@BASEBOARD_FAB2_LIB.BASEBOARD_FAB2(SCH_1):PAGE56_I169@CHPSET_LIB.SKX_EXT_B(CHIPS)':
 'RSVD'<238>: CDS_PINID='RSVD(238)';
NET_NAME
'TP_CPU1_RSVD_239'
 '@BASEBOARD_FAB2_LIB.BASEBOARD_FAB2(SCH_1):TP_CPU1_RSVD_239':
 C_SIGNAL='@baseboard_fab2_lib.baseboard_fab2(sch_1):tp_cpu1_rsvd_239';
NODE_NAME     U2D1 AG48
 '@BASEBOARD_FAB2_LIB.BASEBOARD_FAB2(SCH_1):PAGE56_I169@CHPSET_LIB.SKX_EXT_B(CHIPS)':
 'RSVD'<239>: CDS_PINID='RSVD(239)';
NET_NAME
'TP_CPU1_RSVD_24'
 '@BASEBOARD_FAB2_LIB.BASEBOARD_FAB2(SCH_1):TP_CPU1_RSVD_24':
 C_SIGNAL='@baseboard_fab2_lib.baseboard_fab2(sch_1):tp_cpu1_rsvd_24';
NODE_NAME     U2D1 DV71
 '@BASEBOARD_FAB2_LIB.BASEBOARD_FAB2(SCH_1):PAGE73_I107@CHPSET_LIB.SKX_EXT_B(CHIPS)':
 'RSVD'<24>: CDS_PINID='RSVD(24)';
NET_NAME
'TP_CPU1_RSVD_240'
 '@BASEBOARD_FAB2_LIB.BASEBOARD_FAB2(SCH_1):TP_CPU1_RSVD_240':
 C_SIGNAL='@baseboard_fab2_lib.baseboard_fab2(sch_1):tp_cpu1_rsvd_240';
NODE_NAME     U2D1 AG20
 '@BASEBOARD_FAB2_LIB.BASEBOARD_FAB2(SCH_1):PAGE56_I169@CHPSET_LIB.SKX_EXT_B(CHIPS)':
 'RSVD'<240>: CDS_PINID='RSVD(240)';
NET_NAME
'TP_CPU1_RSVD_241'
 '@BASEBOARD_FAB2_LIB.BASEBOARD_FAB2(SCH_1):TP_CPU1_RSVD_241':
 C_SIGNAL='@baseboard_fab2_lib.baseboard_fab2(sch_1):tp_cpu1_rsvd_241';
NODE_NAME     U2D1 AF71
 '@BASEBOARD_FAB2_LIB.BASEBOARD_FAB2(SCH_1):PAGE56_I169@CHPSET_LIB.SKX_EXT_B(CHIPS)':
 'RSVD'<241>: CDS_PINID='RSVD(241)';
NET_NAME
'TP_CPU1_RSVD_242'
 '@BASEBOARD_FAB2_LIB.BASEBOARD_FAB2(SCH_1):TP_CPU1_RSVD_242':
 C_SIGNAL='@baseboard_fab2_lib.baseboard_fab2(sch_1):tp_cpu1_rsvd_242';
NODE_NAME     U2D1 AF53
 '@BASEBOARD_FAB2_LIB.BASEBOARD_FAB2(SCH_1):PAGE56_I169@CHPSET_LIB.SKX_EXT_B(CHIPS)':
 'RSVD'<242>: CDS_PINID='RSVD(242)';
NET_NAME
'TP_CPU1_RSVD_243'
 '@BASEBOARD_FAB2_LIB.BASEBOARD_FAB2(SCH_1):TP_CPU1_RSVD_243':
 C_SIGNAL='@baseboard_fab2_lib.baseboard_fab2(sch_1):tp_cpu1_rsvd_243';
NODE_NAME     U2D1 AF51
 '@BASEBOARD_FAB2_LIB.BASEBOARD_FAB2(SCH_1):PAGE56_I169@CHPSET_LIB.SKX_EXT_B(CHIPS)':
 'RSVD'<243>: CDS_PINID='RSVD(243)';
NET_NAME
'TP_CPU1_RSVD_244'
 '@BASEBOARD_FAB2_LIB.BASEBOARD_FAB2(SCH_1):TP_CPU1_RSVD_244':
 C_SIGNAL='@baseboard_fab2_lib.baseboard_fab2(sch_1):tp_cpu1_rsvd_244';
NODE_NAME     U2D1 AF49
 '@BASEBOARD_FAB2_LIB.BASEBOARD_FAB2(SCH_1):PAGE56_I169@CHPSET_LIB.SKX_EXT_B(CHIPS)':
 'RSVD'<244>: CDS_PINID='RSVD(244)';
NET_NAME
'TP_CPU1_RSVD_245'
 '@BASEBOARD_FAB2_LIB.BASEBOARD_FAB2(SCH_1):TP_CPU1_RSVD_245':
 C_SIGNAL='@baseboard_fab2_lib.baseboard_fab2(sch_1):tp_cpu1_rsvd_245';
NODE_NAME     U2D1 AF47
 '@BASEBOARD_FAB2_LIB.BASEBOARD_FAB2(SCH_1):PAGE56_I169@CHPSET_LIB.SKX_EXT_B(CHIPS)':
 'RSVD'<245>: CDS_PINID='RSVD(245)';
NET_NAME
'TP_CPU1_RSVD_246'
 '@BASEBOARD_FAB2_LIB.BASEBOARD_FAB2(SCH_1):TP_CPU1_RSVD_246':
 C_SIGNAL='@baseboard_fab2_lib.baseboard_fab2(sch_1):tp_cpu1_rsvd_246';
NODE_NAME     U2D1 AF19
 '@BASEBOARD_FAB2_LIB.BASEBOARD_FAB2(SCH_1):PAGE56_I169@CHPSET_LIB.SKX_EXT_B(CHIPS)':
 'RSVD'<246>: CDS_PINID='RSVD(246)';
NET_NAME
'TP_CPU1_RSVD_247'
 '@BASEBOARD_FAB2_LIB.BASEBOARD_FAB2(SCH_1):TP_CPU1_RSVD_247':
 C_SIGNAL='@baseboard_fab2_lib.baseboard_fab2(sch_1):tp_cpu1_rsvd_247';
NODE_NAME     U2D1 AE72
 '@BASEBOARD_FAB2_LIB.BASEBOARD_FAB2(SCH_1):PAGE56_I169@CHPSET_LIB.SKX_EXT_B(CHIPS)':
 'RSVD'<247>: CDS_PINID='RSVD(247)';
NET_NAME
'TP_CPU1_RSVD_248'
 '@BASEBOARD_FAB2_LIB.BASEBOARD_FAB2(SCH_1):TP_CPU1_RSVD_248':
 C_SIGNAL='@baseboard_fab2_lib.baseboard_fab2(sch_1):tp_cpu1_rsvd_248';
NODE_NAME     U2D1 AE52
 '@BASEBOARD_FAB2_LIB.BASEBOARD_FAB2(SCH_1):PAGE56_I169@CHPSET_LIB.SKX_EXT_B(CHIPS)':
 'RSVD'<248>: CDS_PINID='RSVD(248)';
NET_NAME
'TP_CPU1_RSVD_249'
 '@BASEBOARD_FAB2_LIB.BASEBOARD_FAB2(SCH_1):TP_CPU1_RSVD_249':
 C_SIGNAL='@baseboard_fab2_lib.baseboard_fab2(sch_1):tp_cpu1_rsvd_249';
NODE_NAME     U2D1 AE50
 '@BASEBOARD_FAB2_LIB.BASEBOARD_FAB2(SCH_1):PAGE56_I169@CHPSET_LIB.SKX_EXT_B(CHIPS)':
 'RSVD'<249>: CDS_PINID='RSVD(249)';
NET_NAME
'TP_CPU1_RSVD_25'
 '@BASEBOARD_FAB2_LIB.BASEBOARD_FAB2(SCH_1):TP_CPU1_RSVD_25':
 C_SIGNAL='@baseboard_fab2_lib.baseboard_fab2(sch_1):tp_cpu1_rsvd_25';
NODE_NAME     U2D1 DV61
 '@BASEBOARD_FAB2_LIB.BASEBOARD_FAB2(SCH_1):PAGE73_I107@CHPSET_LIB.SKX_EXT_B(CHIPS)':
 'RSVD'<25>: CDS_PINID='RSVD(25)';
NET_NAME
'TP_CPU1_RSVD_250'
 '@BASEBOARD_FAB2_LIB.BASEBOARD_FAB2(SCH_1):TP_CPU1_RSVD_250':
 C_SIGNAL='@baseboard_fab2_lib.baseboard_fab2(sch_1):tp_cpu1_rsvd_250';
NODE_NAME     U2D1 AE48
 '@BASEBOARD_FAB2_LIB.BASEBOARD_FAB2(SCH_1):PAGE56_I169@CHPSET_LIB.SKX_EXT_B(CHIPS)':
 'RSVD'<250>: CDS_PINID='RSVD(250)';
NET_NAME
'TP_CPU1_RSVD_251'
 '@BASEBOARD_FAB2_LIB.BASEBOARD_FAB2(SCH_1):TP_CPU1_RSVD_251':
 C_SIGNAL='@baseboard_fab2_lib.baseboard_fab2(sch_1):tp_cpu1_rsvd_251';
NODE_NAME     U2D1 AE46
 '@BASEBOARD_FAB2_LIB.BASEBOARD_FAB2(SCH_1):PAGE56_I169@CHPSET_LIB.SKX_EXT_B(CHIPS)':
 'RSVD'<251>: CDS_PINID='RSVD(251)';
NET_NAME
'TP_CPU1_RSVD_252'
 '@BASEBOARD_FAB2_LIB.BASEBOARD_FAB2(SCH_1):TP_CPU1_RSVD_252':
 C_SIGNAL='@baseboard_fab2_lib.baseboard_fab2(sch_1):tp_cpu1_rsvd_252';
NODE_NAME     U2D1 AD51
 '@BASEBOARD_FAB2_LIB.BASEBOARD_FAB2(SCH_1):PAGE56_I169@CHPSET_LIB.SKX_EXT_B(CHIPS)':
 'RSVD'<252>: CDS_PINID='RSVD(252)';
NET_NAME
'TP_CPU1_RSVD_253'
 '@BASEBOARD_FAB2_LIB.BASEBOARD_FAB2(SCH_1):TP_CPU1_RSVD_253':
 C_SIGNAL='@baseboard_fab2_lib.baseboard_fab2(sch_1):tp_cpu1_rsvd_253';
NODE_NAME     U2D1 AD49
 '@BASEBOARD_FAB2_LIB.BASEBOARD_FAB2(SCH_1):PAGE56_I169@CHPSET_LIB.SKX_EXT_B(CHIPS)':
 'RSVD'<253>: CDS_PINID='RSVD(253)';
NET_NAME
'TP_CPU1_RSVD_254'
 '@BASEBOARD_FAB2_LIB.BASEBOARD_FAB2(SCH_1):TP_CPU1_RSVD_254':
 C_SIGNAL='@baseboard_fab2_lib.baseboard_fab2(sch_1):tp_cpu1_rsvd_254';
NODE_NAME     U2D1 AD47
 '@BASEBOARD_FAB2_LIB.BASEBOARD_FAB2(SCH_1):PAGE56_I169@CHPSET_LIB.SKX_EXT_B(CHIPS)':
 'RSVD'<254>: CDS_PINID='RSVD(254)';
NET_NAME
'TP_CPU1_RSVD_255'
 '@BASEBOARD_FAB2_LIB.BASEBOARD_FAB2(SCH_1):TP_CPU1_RSVD_255':
 C_SIGNAL='@baseboard_fab2_lib.baseboard_fab2(sch_1):tp_cpu1_rsvd_255';
NODE_NAME     U2D1 AY83
 '@BASEBOARD_FAB2_LIB.BASEBOARD_FAB2(SCH_1):PAGE70_I9@CHPSET_LIB.SKX_EXT_B(CHIPS)':
 'RSVD'<255>: CDS_PINID='RSVD(255)';
NET_NAME
'TP_CPU1_RSVD_256'
 '@BASEBOARD_FAB2_LIB.BASEBOARD_FAB2(SCH_1):TP_CPU1_RSVD_256':
 C_SIGNAL='@baseboard_fab2_lib.baseboard_fab2(sch_1):tp_cpu1_rsvd_256';
NODE_NAME     U2D1 Y65
 '@BASEBOARD_FAB2_LIB.BASEBOARD_FAB2(SCH_1):PAGE56_I169@CHPSET_LIB.SKX_EXT_B(CHIPS)':
 'RSVD'<256>: CDS_PINID='RSVD(256)';
NET_NAME
'TP_CPU1_RSVD_258'
 '@BASEBOARD_FAB2_LIB.BASEBOARD_FAB2(SCH_1):TP_CPU1_RSVD_258':
 C_SIGNAL='@baseboard_fab2_lib.baseboard_fab2(sch_1):tp_cpu1_rsvd_258';
NODE_NAME     U2D1 W66
 '@BASEBOARD_FAB2_LIB.BASEBOARD_FAB2(SCH_1):PAGE56_I169@CHPSET_LIB.SKX_EXT_B(CHIPS)':
 'RSVD'<258>: CDS_PINID='RSVD(258)';
NET_NAME
'TP_CPU1_RSVD_259'
 '@BASEBOARD_FAB2_LIB.BASEBOARD_FAB2(SCH_1):TP_CPU1_RSVD_259':
 C_SIGNAL='@baseboard_fab2_lib.baseboard_fab2(sch_1):tp_cpu1_rsvd_259';
NODE_NAME     U2D1 V67
 '@BASEBOARD_FAB2_LIB.BASEBOARD_FAB2(SCH_1):PAGE56_I169@CHPSET_LIB.SKX_EXT_B(CHIPS)':
 'RSVD'<259>: CDS_PINID='RSVD(259)';
NET_NAME
'TP_CPU1_RSVD_26'
 '@BASEBOARD_FAB2_LIB.BASEBOARD_FAB2(SCH_1):TP_CPU1_RSVD_26':
 C_SIGNAL='@baseboard_fab2_lib.baseboard_fab2(sch_1):tp_cpu1_rsvd_26';
NODE_NAME     U2D1 DU44
 '@BASEBOARD_FAB2_LIB.BASEBOARD_FAB2(SCH_1):PAGE73_I107@CHPSET_LIB.SKX_EXT_B(CHIPS)':
 'RSVD'<26>: CDS_PINID='RSVD(26)';
NET_NAME
'TP_CPU1_RSVD_260'
 '@BASEBOARD_FAB2_LIB.BASEBOARD_FAB2(SCH_1):TP_CPU1_RSVD_260':
 C_SIGNAL='@baseboard_fab2_lib.baseboard_fab2(sch_1):tp_cpu1_rsvd_260';
NODE_NAME     U2D1 V65
 '@BASEBOARD_FAB2_LIB.BASEBOARD_FAB2(SCH_1):PAGE56_I169@CHPSET_LIB.SKX_EXT_B(CHIPS)':
 'RSVD'<260>: CDS_PINID='RSVD(260)';
NET_NAME
'TP_CPU1_RSVD_261'
 '@BASEBOARD_FAB2_LIB.BASEBOARD_FAB2(SCH_1):TP_CPU1_RSVD_261':
 C_SIGNAL='@baseboard_fab2_lib.baseboard_fab2(sch_1):tp_cpu1_rsvd_261';
NODE_NAME     U2D1 U66
 '@BASEBOARD_FAB2_LIB.BASEBOARD_FAB2(SCH_1):PAGE56_I169@CHPSET_LIB.SKX_EXT_B(CHIPS)':
 'RSVD'<261>: CDS_PINID='RSVD(261)';
NET_NAME
'TP_CPU1_RSVD_262'
 '@BASEBOARD_FAB2_LIB.BASEBOARD_FAB2(SCH_1):TP_CPU1_RSVD_262':
 C_SIGNAL='@baseboard_fab2_lib.baseboard_fab2(sch_1):tp_cpu1_rsvd_262';
NODE_NAME     U2D1 T67
 '@BASEBOARD_FAB2_LIB.BASEBOARD_FAB2(SCH_1):PAGE56_I169@CHPSET_LIB.SKX_EXT_B(CHIPS)':
 'RSVD'<262>: CDS_PINID='RSVD(262)';
NET_NAME
'TP_CPU1_RSVD_263'
 '@BASEBOARD_FAB2_LIB.BASEBOARD_FAB2(SCH_1):TP_CPU1_RSVD_263':
 C_SIGNAL='@baseboard_fab2_lib.baseboard_fab2(sch_1):tp_cpu1_rsvd_263';
NODE_NAME     U2D1 R66
 '@BASEBOARD_FAB2_LIB.BASEBOARD_FAB2(SCH_1):PAGE56_I169@CHPSET_LIB.SKX_EXT_B(CHIPS)':
 'RSVD'<263>: CDS_PINID='RSVD(263)';
NET_NAME
'TP_CPU1_RSVD_264'
 '@BASEBOARD_FAB2_LIB.BASEBOARD_FAB2(SCH_1):TP_CPU1_RSVD_264':
 C_SIGNAL='@baseboard_fab2_lib.baseboard_fab2(sch_1):tp_cpu1_rsvd_264';
NODE_NAME     U2D1 R62
 '@BASEBOARD_FAB2_LIB.BASEBOARD_FAB2(SCH_1):PAGE56_I169@CHPSET_LIB.SKX_EXT_B(CHIPS)':
 'RSVD'<264>: CDS_PINID='RSVD(264)';
NET_NAME
'TP_CPU1_RSVD_265'
 '@BASEBOARD_FAB2_LIB.BASEBOARD_FAB2(SCH_1):TP_CPU1_RSVD_265':
 C_SIGNAL='@baseboard_fab2_lib.baseboard_fab2(sch_1):tp_cpu1_rsvd_265';
NODE_NAME     U2D1 P65
 '@BASEBOARD_FAB2_LIB.BASEBOARD_FAB2(SCH_1):PAGE56_I169@CHPSET_LIB.SKX_EXT_B(CHIPS)':
 'RSVD'<265>: CDS_PINID='RSVD(265)';
NET_NAME
'TP_CPU1_RSVD_266'
 '@BASEBOARD_FAB2_LIB.BASEBOARD_FAB2(SCH_1):TP_CPU1_RSVD_266':
 C_SIGNAL='@baseboard_fab2_lib.baseboard_fab2(sch_1):tp_cpu1_rsvd_266';
NODE_NAME     U2D1 M63
 '@BASEBOARD_FAB2_LIB.BASEBOARD_FAB2(SCH_1):PAGE56_I169@CHPSET_LIB.SKX_EXT_B(CHIPS)':
 'RSVD'<266>: CDS_PINID='RSVD(266)';
NET_NAME
'TP_CPU1_RSVD_267'
 '@BASEBOARD_FAB2_LIB.BASEBOARD_FAB2(SCH_1):TP_CPU1_RSVD_267':
 C_SIGNAL='@baseboard_fab2_lib.baseboard_fab2(sch_1):tp_cpu1_rsvd_267';
NODE_NAME     U2D1 K61
 '@BASEBOARD_FAB2_LIB.BASEBOARD_FAB2(SCH_1):PAGE56_I169@CHPSET_LIB.SKX_EXT_B(CHIPS)':
 'RSVD'<267>: CDS_PINID='RSVD(267)';
NET_NAME
'TP_CPU1_RSVD_268'
 '@BASEBOARD_FAB2_LIB.BASEBOARD_FAB2(SCH_1):TP_CPU1_RSVD_268':
 C_SIGNAL='@baseboard_fab2_lib.baseboard_fab2(sch_1):tp_cpu1_rsvd_268';
NODE_NAME     U2D1 J62
 '@BASEBOARD_FAB2_LIB.BASEBOARD_FAB2(SCH_1):PAGE56_I169@CHPSET_LIB.SKX_EXT_B(CHIPS)':
 'RSVD'<268>: CDS_PINID='RSVD(268)';
NET_NAME
'TP_CPU1_RSVD_269'
 '@BASEBOARD_FAB2_LIB.BASEBOARD_FAB2(SCH_1):TP_CPU1_RSVD_269':
 C_SIGNAL='@baseboard_fab2_lib.baseboard_fab2(sch_1):tp_cpu1_rsvd_269';
NODE_NAME     U2D1 J46
 '@BASEBOARD_FAB2_LIB.BASEBOARD_FAB2(SCH_1):PAGE56_I169@CHPSET_LIB.SKX_EXT_B(CHIPS)':
 'RSVD'<269>: CDS_PINID='RSVD(269)';
NET_NAME
'TP_CPU1_RSVD_27'
 '@BASEBOARD_FAB2_LIB.BASEBOARD_FAB2(SCH_1):TP_CPU1_RSVD_27':
 C_SIGNAL='@baseboard_fab2_lib.baseboard_fab2(sch_1):tp_cpu1_rsvd_27';
NODE_NAME     U2D1 DT71
 '@BASEBOARD_FAB2_LIB.BASEBOARD_FAB2(SCH_1):PAGE73_I107@CHPSET_LIB.SKX_EXT_B(CHIPS)':
 'RSVD'<27>: CDS_PINID='RSVD(27)';
NET_NAME
'TP_CPU1_RSVD_270'
 '@BASEBOARD_FAB2_LIB.BASEBOARD_FAB2(SCH_1):TP_CPU1_RSVD_270':
 C_SIGNAL='@baseboard_fab2_lib.baseboard_fab2(sch_1):tp_cpu1_rsvd_270';
NODE_NAME     U2D1 H85
 '@BASEBOARD_FAB2_LIB.BASEBOARD_FAB2(SCH_1):PAGE56_I169@CHPSET_LIB.SKX_EXT_B(CHIPS)':
 'RSVD'<270>: CDS_PINID='RSVD(270)';
NET_NAME
'TP_CPU1_RSVD_271'
 '@BASEBOARD_FAB2_LIB.BASEBOARD_FAB2(SCH_1):TP_CPU1_RSVD_271':
 C_SIGNAL='@baseboard_fab2_lib.baseboard_fab2(sch_1):tp_cpu1_rsvd_271';
NODE_NAME     U2D1 H83
 '@BASEBOARD_FAB2_LIB.BASEBOARD_FAB2(SCH_1):PAGE56_I169@CHPSET_LIB.SKX_EXT_B(CHIPS)':
 'RSVD'<271>: CDS_PINID='RSVD(271)';
NET_NAME
'TP_CPU1_RSVD_272'
 '@BASEBOARD_FAB2_LIB.BASEBOARD_FAB2(SCH_1):TP_CPU1_RSVD_272':
 C_SIGNAL='@baseboard_fab2_lib.baseboard_fab2(sch_1):tp_cpu1_rsvd_272';
NODE_NAME     U2D1 H1
 '@BASEBOARD_FAB2_LIB.BASEBOARD_FAB2(SCH_1):PAGE56_I169@CHPSET_LIB.SKX_EXT_B(CHIPS)':
 'RSVD'<272>: CDS_PINID='RSVD(272)';
NET_NAME
'TP_CPU1_RSVD_273'
 '@BASEBOARD_FAB2_LIB.BASEBOARD_FAB2(SCH_1):TP_CPU1_RSVD_273':
 C_SIGNAL='@baseboard_fab2_lib.baseboard_fab2(sch_1):tp_cpu1_rsvd_273';
NODE_NAME     U2D1 G84
 '@BASEBOARD_FAB2_LIB.BASEBOARD_FAB2(SCH_1):PAGE56_I169@CHPSET_LIB.SKX_EXT_B(CHIPS)':
 'RSVD'<273>: CDS_PINID='RSVD(273)';
NET_NAME
'TP_CPU1_RSVD_274'
 '@BASEBOARD_FAB2_LIB.BASEBOARD_FAB2(SCH_1):TP_CPU1_RSVD_274':
 C_SIGNAL='@baseboard_fab2_lib.baseboard_fab2(sch_1):tp_cpu1_rsvd_274';
NODE_NAME     U2D1 G64
 '@BASEBOARD_FAB2_LIB.BASEBOARD_FAB2(SCH_1):PAGE56_I169@CHPSET_LIB.SKX_EXT_B(CHIPS)':
 'RSVD'<274>: CDS_PINID='RSVD(274)';
NET_NAME
'TP_CPU1_RSVD_275'
 '@BASEBOARD_FAB2_LIB.BASEBOARD_FAB2(SCH_1):TP_CPU1_RSVD_275':
 C_SIGNAL='@baseboard_fab2_lib.baseboard_fab2(sch_1):tp_cpu1_rsvd_275';
NODE_NAME     U2D1 G2
 '@BASEBOARD_FAB2_LIB.BASEBOARD_FAB2(SCH_1):PAGE56_I169@CHPSET_LIB.SKX_EXT_B(CHIPS)':
 'RSVD'<275>: CDS_PINID='RSVD(275)';
NET_NAME
'TP_CPU1_RSVD_276'
 '@BASEBOARD_FAB2_LIB.BASEBOARD_FAB2(SCH_1):TP_CPU1_RSVD_276':
 C_SIGNAL='@baseboard_fab2_lib.baseboard_fab2(sch_1):tp_cpu1_rsvd_276';
NODE_NAME     U2D1 F83
 '@BASEBOARD_FAB2_LIB.BASEBOARD_FAB2(SCH_1):PAGE56_I169@CHPSET_LIB.SKX_EXT_B(CHIPS)':
 'RSVD'<276>: CDS_PINID='RSVD(276)';
NET_NAME
'TP_CPU1_RSVD_277'
 '@BASEBOARD_FAB2_LIB.BASEBOARD_FAB2(SCH_1):TP_CPU1_RSVD_277':
 C_SIGNAL='@baseboard_fab2_lib.baseboard_fab2(sch_1):tp_cpu1_rsvd_277';
NODE_NAME     U2D1 F65
 '@BASEBOARD_FAB2_LIB.BASEBOARD_FAB2(SCH_1):PAGE56_I169@CHPSET_LIB.SKX_EXT_B(CHIPS)':
 'RSVD'<277>: CDS_PINID='RSVD(277)';
NET_NAME
'TP_CPU1_RSVD_278'
 '@BASEBOARD_FAB2_LIB.BASEBOARD_FAB2(SCH_1):TP_CPU1_RSVD_278':
 C_SIGNAL='@baseboard_fab2_lib.baseboard_fab2(sch_1):tp_cpu1_rsvd_278';
NODE_NAME     U2D1 F23
 '@BASEBOARD_FAB2_LIB.BASEBOARD_FAB2(SCH_1):PAGE56_I169@CHPSET_LIB.SKX_EXT_B(CHIPS)':
 'RSVD'<278>: CDS_PINID='RSVD(278)';
NET_NAME
'TP_CPU1_RSVD_279'
 '@BASEBOARD_FAB2_LIB.BASEBOARD_FAB2(SCH_1):TP_CPU1_RSVD_279':
 C_SIGNAL='@baseboard_fab2_lib.baseboard_fab2(sch_1):tp_cpu1_rsvd_279';
NODE_NAME     U2D1 F3
 '@BASEBOARD_FAB2_LIB.BASEBOARD_FAB2(SCH_1):PAGE56_I169@CHPSET_LIB.SKX_EXT_B(CHIPS)':
 'RSVD'<279>: CDS_PINID='RSVD(279)';
NET_NAME
'TP_CPU1_RSVD_28'
 '@BASEBOARD_FAB2_LIB.BASEBOARD_FAB2(SCH_1):TP_CPU1_RSVD_28':
 C_SIGNAL='@baseboard_fab2_lib.baseboard_fab2(sch_1):tp_cpu1_rsvd_28';
NODE_NAME     U2D1 DR44
 '@BASEBOARD_FAB2_LIB.BASEBOARD_FAB2(SCH_1):PAGE73_I107@CHPSET_LIB.SKX_EXT_B(CHIPS)':
 'RSVD'<28>: CDS_PINID='RSVD(28)';
NET_NAME
'TP_CPU1_RSVD_280'
 '@BASEBOARD_FAB2_LIB.BASEBOARD_FAB2(SCH_1):TP_CPU1_RSVD_280':
 C_SIGNAL='@baseboard_fab2_lib.baseboard_fab2(sch_1):tp_cpu1_rsvd_280';
NODE_NAME     U2D1 E84
 '@BASEBOARD_FAB2_LIB.BASEBOARD_FAB2(SCH_1):PAGE56_I169@CHPSET_LIB.SKX_EXT_B(CHIPS)':
 'RSVD'<280>: CDS_PINID='RSVD(280)';
NET_NAME
'TP_CPU1_RSVD_281'
 '@BASEBOARD_FAB2_LIB.BASEBOARD_FAB2(SCH_1):TP_CPU1_RSVD_281':
 C_SIGNAL='@baseboard_fab2_lib.baseboard_fab2(sch_1):tp_cpu1_rsvd_281';
NODE_NAME     U2D1 E24
 '@BASEBOARD_FAB2_LIB.BASEBOARD_FAB2(SCH_1):PAGE56_I169@CHPSET_LIB.SKX_EXT_B(CHIPS)':
 'RSVD'<281>: CDS_PINID='RSVD(281)';
NET_NAME
'TP_CPU1_RSVD_282'
 '@BASEBOARD_FAB2_LIB.BASEBOARD_FAB2(SCH_1):TP_CPU1_RSVD_282':
 C_SIGNAL='@baseboard_fab2_lib.baseboard_fab2(sch_1):tp_cpu1_rsvd_282';
NODE_NAME     U2D1 E4
 '@BASEBOARD_FAB2_LIB.BASEBOARD_FAB2(SCH_1):PAGE56_I169@CHPSET_LIB.SKX_EXT_B(CHIPS)':
 'RSVD'<282>: CDS_PINID='RSVD(282)';
NET_NAME
'TP_CPU1_RSVD_283'
 '@BASEBOARD_FAB2_LIB.BASEBOARD_FAB2(SCH_1):TP_CPU1_RSVD_283':
 C_SIGNAL='@baseboard_fab2_lib.baseboard_fab2(sch_1):tp_cpu1_rsvd_283';
NODE_NAME     U2D1 E2
 '@BASEBOARD_FAB2_LIB.BASEBOARD_FAB2(SCH_1):PAGE56_I169@CHPSET_LIB.SKX_EXT_B(CHIPS)':
 'RSVD'<283>: CDS_PINID='RSVD(283)';
NET_NAME
'TP_CPU1_RSVD_284'
 '@BASEBOARD_FAB2_LIB.BASEBOARD_FAB2(SCH_1):TP_CPU1_RSVD_284':
 C_SIGNAL='@baseboard_fab2_lib.baseboard_fab2(sch_1):tp_cpu1_rsvd_284';
NODE_NAME     U2D1 D83
 '@BASEBOARD_FAB2_LIB.BASEBOARD_FAB2(SCH_1):PAGE56_I169@CHPSET_LIB.SKX_EXT_B(CHIPS)':
 'RSVD'<284>: CDS_PINID='RSVD(284)';
NET_NAME
'TP_CPU1_RSVD_285'
 '@BASEBOARD_FAB2_LIB.BASEBOARD_FAB2(SCH_1):TP_CPU1_RSVD_285':
 C_SIGNAL='@baseboard_fab2_lib.baseboard_fab2(sch_1):tp_cpu1_rsvd_285';
NODE_NAME     U2D1 D65
 '@BASEBOARD_FAB2_LIB.BASEBOARD_FAB2(SCH_1):PAGE56_I169@CHPSET_LIB.SKX_EXT_B(CHIPS)':
 'RSVD'<285>: CDS_PINID='RSVD(285)';
NET_NAME
'TP_CPU1_RSVD_286'
 '@BASEBOARD_FAB2_LIB.BASEBOARD_FAB2(SCH_1):TP_CPU1_RSVD_286':
 C_SIGNAL='@baseboard_fab2_lib.baseboard_fab2(sch_1):tp_cpu1_rsvd_286';
NODE_NAME     U2D1 D17
 '@BASEBOARD_FAB2_LIB.BASEBOARD_FAB2(SCH_1):PAGE56_I169@CHPSET_LIB.SKX_EXT_B(CHIPS)':
 'RSVD'<286>: CDS_PINID='RSVD(286)';
NET_NAME
'TP_CPU1_RSVD_287'
 '@BASEBOARD_FAB2_LIB.BASEBOARD_FAB2(SCH_1):TP_CPU1_RSVD_287':
 C_SIGNAL='@baseboard_fab2_lib.baseboard_fab2(sch_1):tp_cpu1_rsvd_287';
NODE_NAME     U2D1 D5
 '@BASEBOARD_FAB2_LIB.BASEBOARD_FAB2(SCH_1):PAGE56_I169@CHPSET_LIB.SKX_EXT_B(CHIPS)':
 'RSVD'<287>: CDS_PINID='RSVD(287)';
NET_NAME
'TP_CPU1_RSVD_288'
 '@BASEBOARD_FAB2_LIB.BASEBOARD_FAB2(SCH_1):TP_CPU1_RSVD_288':
 C_SIGNAL='@baseboard_fab2_lib.baseboard_fab2(sch_1):tp_cpu1_rsvd_288';
NODE_NAME     U2D1 C82
 '@BASEBOARD_FAB2_LIB.BASEBOARD_FAB2(SCH_1):PAGE56_I169@CHPSET_LIB.SKX_EXT_B(CHIPS)':
 'RSVD'<288>: CDS_PINID='RSVD(288)';
NET_NAME
'TP_CPU1_RSVD_289'
 '@BASEBOARD_FAB2_LIB.BASEBOARD_FAB2(SCH_1):TP_CPU1_RSVD_289':
 C_SIGNAL='@baseboard_fab2_lib.baseboard_fab2(sch_1):tp_cpu1_rsvd_289';
NODE_NAME     U2D1 C24
 '@BASEBOARD_FAB2_LIB.BASEBOARD_FAB2(SCH_1):PAGE56_I169@CHPSET_LIB.SKX_EXT_B(CHIPS)':
 'RSVD'<289>: CDS_PINID='RSVD(289)';
NET_NAME
'TP_CPU1_RSVD_29'
 '@BASEBOARD_FAB2_LIB.BASEBOARD_FAB2(SCH_1):TP_CPU1_RSVD_29':
 C_SIGNAL='@baseboard_fab2_lib.baseboard_fab2(sch_1):tp_cpu1_rsvd_29';
NODE_NAME     U2D1 DP65
 '@BASEBOARD_FAB2_LIB.BASEBOARD_FAB2(SCH_1):PAGE73_I107@CHPSET_LIB.SKX_EXT_B(CHIPS)':
 'RSVD'<29>: CDS_PINID='RSVD(29)';
NET_NAME
'TP_CPU1_RSVD_290'
 '@BASEBOARD_FAB2_LIB.BASEBOARD_FAB2(SCH_1):TP_CPU1_RSVD_290':
 C_SIGNAL='@baseboard_fab2_lib.baseboard_fab2(sch_1):tp_cpu1_rsvd_290';
NODE_NAME     U2D1 C18
 '@BASEBOARD_FAB2_LIB.BASEBOARD_FAB2(SCH_1):PAGE56_I169@CHPSET_LIB.SKX_EXT_B(CHIPS)':
 'RSVD'<290>: CDS_PINID='RSVD(290)';
NET_NAME
'TP_CPU1_RSVD_291'
 '@BASEBOARD_FAB2_LIB.BASEBOARD_FAB2(SCH_1):TP_CPU1_RSVD_291':
 C_SIGNAL='@baseboard_fab2_lib.baseboard_fab2(sch_1):tp_cpu1_rsvd_291';
NODE_NAME     U2D1 C6
 '@BASEBOARD_FAB2_LIB.BASEBOARD_FAB2(SCH_1):PAGE56_I169@CHPSET_LIB.SKX_EXT_B(CHIPS)':
 'RSVD'<291>: CDS_PINID='RSVD(291)';
NET_NAME
'TP_CPU1_RSVD_292'
 '@BASEBOARD_FAB2_LIB.BASEBOARD_FAB2(SCH_1):TP_CPU1_RSVD_292':
 C_SIGNAL='@baseboard_fab2_lib.baseboard_fab2(sch_1):tp_cpu1_rsvd_292';
NODE_NAME     U2D1 B81
 '@BASEBOARD_FAB2_LIB.BASEBOARD_FAB2(SCH_1):PAGE56_I169@CHPSET_LIB.SKX_EXT_B(CHIPS)':
 'RSVD'<292>: CDS_PINID='RSVD(292)';
NET_NAME
'TP_CPU1_RSVD_293'
 '@BASEBOARD_FAB2_LIB.BASEBOARD_FAB2(SCH_1):TP_CPU1_RSVD_293':
 C_SIGNAL='@baseboard_fab2_lib.baseboard_fab2(sch_1):tp_cpu1_rsvd_293';
NODE_NAME     U2D1 B77
 '@BASEBOARD_FAB2_LIB.BASEBOARD_FAB2(SCH_1):PAGE56_I169@CHPSET_LIB.SKX_EXT_B(CHIPS)':
 'RSVD'<293>: CDS_PINID='RSVD(293)';
NET_NAME
'TP_CPU1_RSVD_298'
 '@BASEBOARD_FAB2_LIB.BASEBOARD_FAB2(SCH_1):TP_CPU1_RSVD_298':
 C_SIGNAL='@baseboard_fab2_lib.baseboard_fab2(sch_1):tp_cpu1_rsvd_298';
NODE_NAME     U2D1 B7
 '@BASEBOARD_FAB2_LIB.BASEBOARD_FAB2(SCH_1):PAGE56_I169@CHPSET_LIB.SKX_EXT_B(CHIPS)':
 'RSVD'<298>: CDS_PINID='RSVD(298)';
NET_NAME
'TP_CPU1_RSVD_299'
 '@BASEBOARD_FAB2_LIB.BASEBOARD_FAB2(SCH_1):TP_CPU1_RSVD_299':
 C_SIGNAL='@baseboard_fab2_lib.baseboard_fab2(sch_1):tp_cpu1_rsvd_299';
NODE_NAME     U2D1 B3
 '@BASEBOARD_FAB2_LIB.BASEBOARD_FAB2(SCH_1):PAGE56_I169@CHPSET_LIB.SKX_EXT_B(CHIPS)':
 'RSVD'<299>: CDS_PINID='RSVD(299)';
NET_NAME
'TP_CPU1_RSVD_3'
 '@BASEBOARD_FAB2_LIB.BASEBOARD_FAB2(SCH_1):TP_CPU1_RSVD_3':
 C_SIGNAL='@baseboard_fab2_lib.baseboard_fab2(sch_1):tp_cpu1_rsvd_3';
NODE_NAME     U2D1 EF47
 '@BASEBOARD_FAB2_LIB.BASEBOARD_FAB2(SCH_1):PAGE73_I107@CHPSET_LIB.SKX_EXT_B(CHIPS)':
 'RSVD'<3>: CDS_PINID='RSVD(3)';
NET_NAME
'TP_CPU1_RSVD_30'
 '@BASEBOARD_FAB2_LIB.BASEBOARD_FAB2(SCH_1):TP_CPU1_RSVD_30':
 C_SIGNAL='@baseboard_fab2_lib.baseboard_fab2(sch_1):tp_cpu1_rsvd_30';
NODE_NAME     U2D1 DP17
 '@BASEBOARD_FAB2_LIB.BASEBOARD_FAB2(SCH_1):PAGE73_I107@CHPSET_LIB.SKX_EXT_B(CHIPS)':
 'RSVD'<30>: CDS_PINID='RSVD(30)';
NET_NAME
'TP_CPU1_RSVD_300'
 '@BASEBOARD_FAB2_LIB.BASEBOARD_FAB2(SCH_1):TP_CPU1_RSVD_300':
 C_SIGNAL='@baseboard_fab2_lib.baseboard_fab2(sch_1):tp_cpu1_rsvd_300';
NODE_NAME     U2D1 A24
 '@BASEBOARD_FAB2_LIB.BASEBOARD_FAB2(SCH_1):PAGE56_I169@CHPSET_LIB.SKX_EXT_B(CHIPS)':
 'RSVD'<300>: CDS_PINID='RSVD(300)';
NET_NAME
'TP_CPU1_RSVD_303'
 '@BASEBOARD_FAB2_LIB.BASEBOARD_FAB2(SCH_1):TP_CPU1_RSVD_303':
 C_SIGNAL='@baseboard_fab2_lib.baseboard_fab2(sch_1):tp_cpu1_rsvd_303';
NODE_NAME     U2D1 A6
 '@BASEBOARD_FAB2_LIB.BASEBOARD_FAB2(SCH_1):PAGE56_I169@CHPSET_LIB.SKX_EXT_B(CHIPS)':
 'RSVD'<303>: CDS_PINID='RSVD(303)';
NET_NAME
'TP_CPU1_RSVD_304'
 '@BASEBOARD_FAB2_LIB.BASEBOARD_FAB2(SCH_1):TP_CPU1_RSVD_304':
 C_SIGNAL='@baseboard_fab2_lib.baseboard_fab2(sch_1):tp_cpu1_rsvd_304';
NODE_NAME     U2D1 A4
 '@BASEBOARD_FAB2_LIB.BASEBOARD_FAB2(SCH_1):PAGE56_I169@CHPSET_LIB.SKX_EXT_B(CHIPS)':
 'RSVD'<304>: CDS_PINID='RSVD(304)';
NET_NAME
'TP_CPU1_RSVD_31'
 '@BASEBOARD_FAB2_LIB.BASEBOARD_FAB2(SCH_1):TP_CPU1_RSVD_31':
 C_SIGNAL='@baseboard_fab2_lib.baseboard_fab2(sch_1):tp_cpu1_rsvd_31';
NODE_NAME     U2D1 DN66
 '@BASEBOARD_FAB2_LIB.BASEBOARD_FAB2(SCH_1):PAGE73_I107@CHPSET_LIB.SKX_EXT_B(CHIPS)':
 'RSVD'<31>: CDS_PINID='RSVD(31)';
NET_NAME
'TP_CPU1_RSVD_32'
 '@BASEBOARD_FAB2_LIB.BASEBOARD_FAB2(SCH_1):TP_CPU1_RSVD_32':
 C_SIGNAL='@baseboard_fab2_lib.baseboard_fab2(sch_1):tp_cpu1_rsvd_32';
NODE_NAME     U2D1 DN62
 '@BASEBOARD_FAB2_LIB.BASEBOARD_FAB2(SCH_1):PAGE73_I107@CHPSET_LIB.SKX_EXT_B(CHIPS)':
 'RSVD'<32>: CDS_PINID='RSVD(32)';
NET_NAME
'TP_CPU1_RSVD_33'
 '@BASEBOARD_FAB2_LIB.BASEBOARD_FAB2(SCH_1):TP_CPU1_RSVD_33':
 C_SIGNAL='@baseboard_fab2_lib.baseboard_fab2(sch_1):tp_cpu1_rsvd_33';
NODE_NAME     U2D1 DM67
 '@BASEBOARD_FAB2_LIB.BASEBOARD_FAB2(SCH_1):PAGE73_I107@CHPSET_LIB.SKX_EXT_B(CHIPS)':
 'RSVD'<33>: CDS_PINID='RSVD(33)';
NET_NAME
'TP_CPU1_RSVD_34'
 '@BASEBOARD_FAB2_LIB.BASEBOARD_FAB2(SCH_1):TP_CPU1_RSVD_34':
 C_SIGNAL='@baseboard_fab2_lib.baseboard_fab2(sch_1):tp_cpu1_rsvd_34';
NODE_NAME     U2D1 DL66
 '@BASEBOARD_FAB2_LIB.BASEBOARD_FAB2(SCH_1):PAGE73_I107@CHPSET_LIB.SKX_EXT_B(CHIPS)':
 'RSVD'<34>: CDS_PINID='RSVD(34)';
NET_NAME
'TP_CPU1_RSVD_35'
 '@BASEBOARD_FAB2_LIB.BASEBOARD_FAB2(SCH_1):TP_CPU1_RSVD_35':
 C_SIGNAL='@baseboard_fab2_lib.baseboard_fab2(sch_1):tp_cpu1_rsvd_35';
NODE_NAME     U2D1 DL38
 '@BASEBOARD_FAB2_LIB.BASEBOARD_FAB2(SCH_1):PAGE73_I107@CHPSET_LIB.SKX_EXT_B(CHIPS)':
 'RSVD'<35>: CDS_PINID='RSVD(35)';
NET_NAME
'TP_CPU1_RSVD_36'
 '@BASEBOARD_FAB2_LIB.BASEBOARD_FAB2(SCH_1):TP_CPU1_RSVD_36':
 C_SIGNAL='@baseboard_fab2_lib.baseboard_fab2(sch_1):tp_cpu1_rsvd_36';
NODE_NAME     U2D1 DK67
 '@BASEBOARD_FAB2_LIB.BASEBOARD_FAB2(SCH_1):PAGE73_I107@CHPSET_LIB.SKX_EXT_B(CHIPS)':
 'RSVD'<36>: CDS_PINID='RSVD(36)';
NET_NAME
'TP_CPU1_RSVD_37'
 '@BASEBOARD_FAB2_LIB.BASEBOARD_FAB2(SCH_1):TP_CPU1_RSVD_37':
 C_SIGNAL='@baseboard_fab2_lib.baseboard_fab2(sch_1):tp_cpu1_rsvd_37';
NODE_NAME     U2D1 DK65
 '@BASEBOARD_FAB2_LIB.BASEBOARD_FAB2(SCH_1):PAGE73_I107@CHPSET_LIB.SKX_EXT_B(CHIPS)':
 'RSVD'<37>: CDS_PINID='RSVD(37)';
NET_NAME
'TP_CPU1_RSVD_38'
 '@BASEBOARD_FAB2_LIB.BASEBOARD_FAB2(SCH_1):TP_CPU1_RSVD_38':
 C_SIGNAL='@baseboard_fab2_lib.baseboard_fab2(sch_1):tp_cpu1_rsvd_38';
NODE_NAME     U2D1 DK37
 '@BASEBOARD_FAB2_LIB.BASEBOARD_FAB2(SCH_1):PAGE73_I107@CHPSET_LIB.SKX_EXT_B(CHIPS)':
 'RSVD'<38>: CDS_PINID='RSVD(38)';
NET_NAME
'TP_CPU1_RSVD_39'
 '@BASEBOARD_FAB2_LIB.BASEBOARD_FAB2(SCH_1):TP_CPU1_RSVD_39':
 C_SIGNAL='@baseboard_fab2_lib.baseboard_fab2(sch_1):tp_cpu1_rsvd_39';
NODE_NAME     U2D1 DK15
 '@BASEBOARD_FAB2_LIB.BASEBOARD_FAB2(SCH_1):PAGE73_I107@CHPSET_LIB.SKX_EXT_B(CHIPS)':
 'RSVD'<39>: CDS_PINID='RSVD(39)';
NET_NAME
'TP_CPU1_RSVD_4'
 '@BASEBOARD_FAB2_LIB.BASEBOARD_FAB2(SCH_1):TP_CPU1_RSVD_4':
 C_SIGNAL='@baseboard_fab2_lib.baseboard_fab2(sch_1):tp_cpu1_rsvd_4';
NODE_NAME     U2D1 EE84
 '@BASEBOARD_FAB2_LIB.BASEBOARD_FAB2(SCH_1):PAGE73_I107@CHPSET_LIB.SKX_EXT_B(CHIPS)':
 'RSVD'<4>: CDS_PINID='RSVD(4)';
NET_NAME
'TP_CPU1_RSVD_40'
 '@BASEBOARD_FAB2_LIB.BASEBOARD_FAB2(SCH_1):TP_CPU1_RSVD_40':
 C_SIGNAL='@baseboard_fab2_lib.baseboard_fab2(sch_1):tp_cpu1_rsvd_40';
NODE_NAME     U2D1 DJ66
 '@BASEBOARD_FAB2_LIB.BASEBOARD_FAB2(SCH_1):PAGE73_I107@CHPSET_LIB.SKX_EXT_B(CHIPS)':
 'RSVD'<40>: CDS_PINID='RSVD(40)';
NET_NAME
'TP_CPU1_RSVD_41'
 '@BASEBOARD_FAB2_LIB.BASEBOARD_FAB2(SCH_1):TP_CPU1_RSVD_41':
 C_SIGNAL='@baseboard_fab2_lib.baseboard_fab2(sch_1):tp_cpu1_rsvd_41';
NODE_NAME     U2D1 DJ36
 '@BASEBOARD_FAB2_LIB.BASEBOARD_FAB2(SCH_1):PAGE73_I107@CHPSET_LIB.SKX_EXT_B(CHIPS)':
 'RSVD'<41>: CDS_PINID='RSVD(41)';
NET_NAME
'TP_CPU1_RSVD_42'
 '@BASEBOARD_FAB2_LIB.BASEBOARD_FAB2(SCH_1):TP_CPU1_RSVD_42':
 C_SIGNAL='@baseboard_fab2_lib.baseboard_fab2(sch_1):tp_cpu1_rsvd_42';
NODE_NAME     U2D1 DH65
 '@BASEBOARD_FAB2_LIB.BASEBOARD_FAB2(SCH_1):PAGE73_I107@CHPSET_LIB.SKX_EXT_B(CHIPS)':
 'RSVD'<42>: CDS_PINID='RSVD(42)';
NET_NAME
'TP_CPU1_RSVD_43'
 '@BASEBOARD_FAB2_LIB.BASEBOARD_FAB2(SCH_1):TP_CPU1_RSVD_43':
 C_SIGNAL='@baseboard_fab2_lib.baseboard_fab2(sch_1):tp_cpu1_rsvd_43';
NODE_NAME     U2D1 DG64
 '@BASEBOARD_FAB2_LIB.BASEBOARD_FAB2(SCH_1):PAGE73_I107@CHPSET_LIB.SKX_EXT_B(CHIPS)':
 'RSVD'<43>: CDS_PINID='RSVD(43)';
NET_NAME
'TP_CPU1_RSVD_44'
 '@BASEBOARD_FAB2_LIB.BASEBOARD_FAB2(SCH_1):TP_CPU1_RSVD_44':
 C_SIGNAL='@baseboard_fab2_lib.baseboard_fab2(sch_1):tp_cpu1_rsvd_44';
NODE_NAME     U2D1 DG36
 '@BASEBOARD_FAB2_LIB.BASEBOARD_FAB2(SCH_1):PAGE73_I107@CHPSET_LIB.SKX_EXT_B(CHIPS)':
 'RSVD'<44>: CDS_PINID='RSVD(44)';
NET_NAME
'TP_CPU1_RSVD_45'
 '@BASEBOARD_FAB2_LIB.BASEBOARD_FAB2(SCH_1):TP_CPU1_RSVD_45':
 C_SIGNAL='@baseboard_fab2_lib.baseboard_fab2(sch_1):tp_cpu1_rsvd_45';
NODE_NAME     U2D1 DD51
 '@BASEBOARD_FAB2_LIB.BASEBOARD_FAB2(SCH_1):PAGE73_I107@CHPSET_LIB.SKX_EXT_B(CHIPS)':
 'RSVD'<45>: CDS_PINID='RSVD(45)';
NET_NAME
'TP_CPU1_RSVD_46'
 '@BASEBOARD_FAB2_LIB.BASEBOARD_FAB2(SCH_1):TP_CPU1_RSVD_46':
 C_SIGNAL='@baseboard_fab2_lib.baseboard_fab2(sch_1):tp_cpu1_rsvd_46';
NODE_NAME     U2D1 DC52
 '@BASEBOARD_FAB2_LIB.BASEBOARD_FAB2(SCH_1):PAGE73_I107@CHPSET_LIB.SKX_EXT_B(CHIPS)':
 'RSVD'<46>: CDS_PINID='RSVD(46)';
NET_NAME
'TP_CPU1_RSVD_47'
 '@BASEBOARD_FAB2_LIB.BASEBOARD_FAB2(SCH_1):TP_CPU1_RSVD_47':
 C_SIGNAL='@baseboard_fab2_lib.baseboard_fab2(sch_1):tp_cpu1_rsvd_47';
NODE_NAME     U2D1 DC46
 '@BASEBOARD_FAB2_LIB.BASEBOARD_FAB2(SCH_1):PAGE73_I107@CHPSET_LIB.SKX_EXT_B(CHIPS)':
 'RSVD'<47>: CDS_PINID='RSVD(47)';
NET_NAME
'TP_CPU1_RSVD_48'
 '@BASEBOARD_FAB2_LIB.BASEBOARD_FAB2(SCH_1):TP_CPU1_RSVD_48':
 C_SIGNAL='@baseboard_fab2_lib.baseboard_fab2(sch_1):tp_cpu1_rsvd_48';
NODE_NAME     U2D1 DA56
 '@BASEBOARD_FAB2_LIB.BASEBOARD_FAB2(SCH_1):PAGE73_I107@CHPSET_LIB.SKX_EXT_B(CHIPS)':
 'RSVD'<48>: CDS_PINID='RSVD(48)';
NET_NAME
'TP_CPU1_RSVD_49'
 '@BASEBOARD_FAB2_LIB.BASEBOARD_FAB2(SCH_1):TP_CPU1_RSVD_49':
 C_SIGNAL='@baseboard_fab2_lib.baseboard_fab2(sch_1):tp_cpu1_rsvd_49';
NODE_NAME     U2D1 DA54
 '@BASEBOARD_FAB2_LIB.BASEBOARD_FAB2(SCH_1):PAGE73_I107@CHPSET_LIB.SKX_EXT_B(CHIPS)':
 'RSVD'<49>: CDS_PINID='RSVD(49)';
NET_NAME
'TP_CPU1_RSVD_5'
 '@BASEBOARD_FAB2_LIB.BASEBOARD_FAB2(SCH_1):TP_CPU1_RSVD_5':
 C_SIGNAL='@baseboard_fab2_lib.baseboard_fab2(sch_1):tp_cpu1_rsvd_5';
NODE_NAME     U2D1 EE82
 '@BASEBOARD_FAB2_LIB.BASEBOARD_FAB2(SCH_1):PAGE73_I107@CHPSET_LIB.SKX_EXT_B(CHIPS)':
 'RSVD'<5>: CDS_PINID='RSVD(5)';
NET_NAME
'TP_CPU1_RSVD_50'
 '@BASEBOARD_FAB2_LIB.BASEBOARD_FAB2(SCH_1):TP_CPU1_RSVD_50':
 C_SIGNAL='@baseboard_fab2_lib.baseboard_fab2(sch_1):tp_cpu1_rsvd_50';
NODE_NAME     U2D1 DA52
 '@BASEBOARD_FAB2_LIB.BASEBOARD_FAB2(SCH_1):PAGE73_I107@CHPSET_LIB.SKX_EXT_B(CHIPS)':
 'RSVD'<50>: CDS_PINID='RSVD(50)';
NET_NAME
'TP_CPU1_RSVD_51'
 '@BASEBOARD_FAB2_LIB.BASEBOARD_FAB2(SCH_1):TP_CPU1_RSVD_51':
 C_SIGNAL='@baseboard_fab2_lib.baseboard_fab2(sch_1):tp_cpu1_rsvd_51';
NODE_NAME     U2D1 DA40
 '@BASEBOARD_FAB2_LIB.BASEBOARD_FAB2(SCH_1):PAGE73_I107@CHPSET_LIB.SKX_EXT_B(CHIPS)':
 'RSVD'<51>: CDS_PINID='RSVD(51)';
NET_NAME
'TP_CPU1_RSVD_53'
 '@BASEBOARD_FAB2_LIB.BASEBOARD_FAB2(SCH_1):TP_CPU1_RSVD_53':
 C_SIGNAL='@baseboard_fab2_lib.baseboard_fab2(sch_1):tp_cpu1_rsvd_53';
NODE_NAME     U2D1 CY73
 '@BASEBOARD_FAB2_LIB.BASEBOARD_FAB2(SCH_1):PAGE73_I107@CHPSET_LIB.SKX_EXT_B(CHIPS)':
 'RSVD'<53>: CDS_PINID='RSVD(53)';
NET_NAME
'TP_CPU1_RSVD_54'
 '@BASEBOARD_FAB2_LIB.BASEBOARD_FAB2(SCH_1):TP_CPU1_RSVD_54':
 C_SIGNAL='@baseboard_fab2_lib.baseboard_fab2(sch_1):tp_cpu1_rsvd_54';
NODE_NAME     U2D1 CY63
 '@BASEBOARD_FAB2_LIB.BASEBOARD_FAB2(SCH_1):PAGE73_I107@CHPSET_LIB.SKX_EXT_B(CHIPS)':
 'RSVD'<54>: CDS_PINID='RSVD(54)';
NET_NAME
'TP_CPU1_RSVD_55'
 '@BASEBOARD_FAB2_LIB.BASEBOARD_FAB2(SCH_1):TP_CPU1_RSVD_55':
 C_SIGNAL='@baseboard_fab2_lib.baseboard_fab2(sch_1):tp_cpu1_rsvd_55';
NODE_NAME     U2D1 CY57
 '@BASEBOARD_FAB2_LIB.BASEBOARD_FAB2(SCH_1):PAGE73_I107@CHPSET_LIB.SKX_EXT_B(CHIPS)':
 'RSVD'<55>: CDS_PINID='RSVD(55)';
NET_NAME
'TP_CPU1_RSVD_56'
 '@BASEBOARD_FAB2_LIB.BASEBOARD_FAB2(SCH_1):TP_CPU1_RSVD_56':
 C_SIGNAL='@baseboard_fab2_lib.baseboard_fab2(sch_1):tp_cpu1_rsvd_56';
NODE_NAME     U2D1 CY53
 '@BASEBOARD_FAB2_LIB.BASEBOARD_FAB2(SCH_1):PAGE73_I107@CHPSET_LIB.SKX_EXT_B(CHIPS)':
 'RSVD'<56>: CDS_PINID='RSVD(56)';
NET_NAME
'TP_CPU1_RSVD_57'
 '@BASEBOARD_FAB2_LIB.BASEBOARD_FAB2(SCH_1):TP_CPU1_RSVD_57':
 C_SIGNAL='@baseboard_fab2_lib.baseboard_fab2(sch_1):tp_cpu1_rsvd_57';
NODE_NAME     U2D1 CY39
 '@BASEBOARD_FAB2_LIB.BASEBOARD_FAB2(SCH_1):PAGE73_I107@CHPSET_LIB.SKX_EXT_B(CHIPS)':
 'RSVD'<57>: CDS_PINID='RSVD(57)';
NET_NAME
'TP_CPU1_RSVD_59'
 '@BASEBOARD_FAB2_LIB.BASEBOARD_FAB2(SCH_1):TP_CPU1_RSVD_59':
 C_SIGNAL='@baseboard_fab2_lib.baseboard_fab2(sch_1):tp_cpu1_rsvd_59';
NODE_NAME     U2D1 CY23
 '@BASEBOARD_FAB2_LIB.BASEBOARD_FAB2(SCH_1):PAGE73_I107@CHPSET_LIB.SKX_EXT_B(CHIPS)':
 'RSVD'<59>: CDS_PINID='RSVD(59)';
NET_NAME
'TP_CPU1_RSVD_6'
 '@BASEBOARD_FAB2_LIB.BASEBOARD_FAB2(SCH_1):TP_CPU1_RSVD_6':
 C_SIGNAL='@baseboard_fab2_lib.baseboard_fab2(sch_1):tp_cpu1_rsvd_6';
NODE_NAME     U2D1 EE6
 '@BASEBOARD_FAB2_LIB.BASEBOARD_FAB2(SCH_1):PAGE73_I107@CHPSET_LIB.SKX_EXT_B(CHIPS)':
 'RSVD'<6>: CDS_PINID='RSVD(6)';
NET_NAME
'TP_CPU1_RSVD_60'
 '@BASEBOARD_FAB2_LIB.BASEBOARD_FAB2(SCH_1):TP_CPU1_RSVD_60':
 C_SIGNAL='@baseboard_fab2_lib.baseboard_fab2(sch_1):tp_cpu1_rsvd_60';
NODE_NAME     U2D1 CW62
 '@BASEBOARD_FAB2_LIB.BASEBOARD_FAB2(SCH_1):PAGE73_I107@CHPSET_LIB.SKX_EXT_B(CHIPS)':
 'RSVD'<60>: CDS_PINID='RSVD(60)';
NET_NAME
'TP_CPU1_RSVD_61'
 '@BASEBOARD_FAB2_LIB.BASEBOARD_FAB2(SCH_1):TP_CPU1_RSVD_61':
 C_SIGNAL='@baseboard_fab2_lib.baseboard_fab2(sch_1):tp_cpu1_rsvd_61';
NODE_NAME     U2D1 CW60
 '@BASEBOARD_FAB2_LIB.BASEBOARD_FAB2(SCH_1):PAGE73_I107@CHPSET_LIB.SKX_EXT_B(CHIPS)':
 'RSVD'<61>: CDS_PINID='RSVD(61)';
NET_NAME
'TP_CPU1_RSVD_64'
 '@BASEBOARD_FAB2_LIB.BASEBOARD_FAB2(SCH_1):TP_CPU1_RSVD_64':
 C_SIGNAL='@baseboard_fab2_lib.baseboard_fab2(sch_1):tp_cpu1_rsvd_64';
NODE_NAME     U2D1 CV69
 '@BASEBOARD_FAB2_LIB.BASEBOARD_FAB2(SCH_1):PAGE73_I107@CHPSET_LIB.SKX_EXT_B(CHIPS)':
 'RSVD'<64>: CDS_PINID='RSVD(64)';
NET_NAME
'TP_CPU1_RSVD_66'
 '@BASEBOARD_FAB2_LIB.BASEBOARD_FAB2(SCH_1):TP_CPU1_RSVD_66':
 C_SIGNAL='@baseboard_fab2_lib.baseboard_fab2(sch_1):tp_cpu1_rsvd_66';
NODE_NAME     U2D1 CU60
 '@BASEBOARD_FAB2_LIB.BASEBOARD_FAB2(SCH_1):PAGE73_I107@CHPSET_LIB.SKX_EXT_B(CHIPS)':
 'RSVD'<66>: CDS_PINID='RSVD(66)';
NET_NAME
'TP_CPU1_RSVD_67'
 '@BASEBOARD_FAB2_LIB.BASEBOARD_FAB2(SCH_1):TP_CPU1_RSVD_67':
 C_SIGNAL='@baseboard_fab2_lib.baseboard_fab2(sch_1):tp_cpu1_rsvd_67';
NODE_NAME     U2D1 CU6
 '@BASEBOARD_FAB2_LIB.BASEBOARD_FAB2(SCH_1):PAGE73_I107@CHPSET_LIB.SKX_EXT_B(CHIPS)':
 'RSVD'<67>: CDS_PINID='RSVD(67)';
NET_NAME
'TP_CPU1_RSVD_69'
 '@BASEBOARD_FAB2_LIB.BASEBOARD_FAB2(SCH_1):TP_CPU1_RSVD_69':
 C_SIGNAL='@baseboard_fab2_lib.baseboard_fab2(sch_1):tp_cpu1_rsvd_69';
NODE_NAME     U2D1 CT69
 '@BASEBOARD_FAB2_LIB.BASEBOARD_FAB2(SCH_1):PAGE73_I107@CHPSET_LIB.SKX_EXT_B(CHIPS)':
 'RSVD'<69>: CDS_PINID='RSVD(69)';
NET_NAME
'TP_CPU1_RSVD_7'
 '@BASEBOARD_FAB2_LIB.BASEBOARD_FAB2(SCH_1):TP_CPU1_RSVD_7':
 C_SIGNAL='@baseboard_fab2_lib.baseboard_fab2(sch_1):tp_cpu1_rsvd_7';
NODE_NAME     U2D1 EE46
 '@BASEBOARD_FAB2_LIB.BASEBOARD_FAB2(SCH_1):PAGE73_I107@CHPSET_LIB.SKX_EXT_B(CHIPS)':
 'RSVD'<7>: CDS_PINID='RSVD(7)';
NET_NAME
'TP_CPU1_RSVD_70'
 '@BASEBOARD_FAB2_LIB.BASEBOARD_FAB2(SCH_1):TP_CPU1_RSVD_70':
 C_SIGNAL='@baseboard_fab2_lib.baseboard_fab2(sch_1):tp_cpu1_rsvd_70';
NODE_NAME     U2D1 CT5
 '@BASEBOARD_FAB2_LIB.BASEBOARD_FAB2(SCH_1):PAGE73_I107@CHPSET_LIB.SKX_EXT_B(CHIPS)':
 'RSVD'<70>: CDS_PINID='RSVD(70)';
NET_NAME
'TP_CPU1_RSVD_72'
 '@BASEBOARD_FAB2_LIB.BASEBOARD_FAB2(SCH_1):TP_CPU1_RSVD_72':
 C_SIGNAL='@baseboard_fab2_lib.baseboard_fab2(sch_1):tp_cpu1_rsvd_72';
NODE_NAME     U2D1 CR60
 '@BASEBOARD_FAB2_LIB.BASEBOARD_FAB2(SCH_1):PAGE73_I107@CHPSET_LIB.SKX_EXT_B(CHIPS)':
 'RSVD'<72>: CDS_PINID='RSVD(72)';
NET_NAME
'TP_CPU1_RSVD_73'
 '@BASEBOARD_FAB2_LIB.BASEBOARD_FAB2(SCH_1):TP_CPU1_RSVD_73':
 C_SIGNAL='@baseboard_fab2_lib.baseboard_fab2(sch_1):tp_cpu1_rsvd_73';
NODE_NAME     U2D1 CP31
 '@BASEBOARD_FAB2_LIB.BASEBOARD_FAB2(SCH_1):PAGE73_I107@CHPSET_LIB.SKX_EXT_B(CHIPS)':
 'RSVD'<73>: CDS_PINID='RSVD(73)';
NET_NAME
'TP_CPU1_RSVD_8'
 '@BASEBOARD_FAB2_LIB.BASEBOARD_FAB2(SCH_1):TP_CPU1_RSVD_8':
 C_SIGNAL='@baseboard_fab2_lib.baseboard_fab2(sch_1):tp_cpu1_rsvd_8';
NODE_NAME     U2D1 EE16
 '@BASEBOARD_FAB2_LIB.BASEBOARD_FAB2(SCH_1):PAGE73_I107@CHPSET_LIB.SKX_EXT_B(CHIPS)':
 'RSVD'<8>: CDS_PINID='RSVD(8)';
NET_NAME
'TP_CPU1_RSVD_82'
 '@BASEBOARD_FAB2_LIB.BASEBOARD_FAB2(SCH_1):TP_CPU1_RSVD_82':
 C_SIGNAL='@baseboard_fab2_lib.baseboard_fab2(sch_1):tp_cpu1_rsvd_82';
NODE_NAME     U2D1 CK77
 '@BASEBOARD_FAB2_LIB.BASEBOARD_FAB2(SCH_1):PAGE70_I10@CHPSET_LIB.SKX_EXT_B(CHIPS)':
 'RSVD'<82>: CDS_PINID='RSVD(82)';
NET_NAME
'TP_CPU1_RSVD_85'
 '@BASEBOARD_FAB2_LIB.BASEBOARD_FAB2(SCH_1):TP_CPU1_RSVD_85':
 C_SIGNAL='@baseboard_fab2_lib.baseboard_fab2(sch_1):tp_cpu1_rsvd_85';
NODE_NAME     U2D1 CK19
 '@BASEBOARD_FAB2_LIB.BASEBOARD_FAB2(SCH_1):PAGE70_I10@CHPSET_LIB.SKX_EXT_B(CHIPS)':
 'RSVD'<85>: CDS_PINID='RSVD(85)';
NET_NAME
'TP_CPU1_RSVD_9'
 '@BASEBOARD_FAB2_LIB.BASEBOARD_FAB2(SCH_1):TP_CPU1_RSVD_9':
 C_SIGNAL='@baseboard_fab2_lib.baseboard_fab2(sch_1):tp_cpu1_rsvd_9';
NODE_NAME     U2D1 ED83
 '@BASEBOARD_FAB2_LIB.BASEBOARD_FAB2(SCH_1):PAGE73_I107@CHPSET_LIB.SKX_EXT_B(CHIPS)':
 'RSVD'<9>: CDS_PINID='RSVD(9)';
NET_NAME
'TP_CPU1_RSVD_90'
 '@BASEBOARD_FAB2_LIB.BASEBOARD_FAB2(SCH_1):TP_CPU1_RSVD_90':
 C_SIGNAL='@baseboard_fab2_lib.baseboard_fab2(sch_1):tp_cpu1_rsvd_90';
NODE_NAME     U2D1 CH77
 '@BASEBOARD_FAB2_LIB.BASEBOARD_FAB2(SCH_1):PAGE70_I10@CHPSET_LIB.SKX_EXT_B(CHIPS)':
 'RSVD'<90>: CDS_PINID='RSVD(90)';
NET_NAME
'TP_CPU1_RSVD_91'
 '@BASEBOARD_FAB2_LIB.BASEBOARD_FAB2(SCH_1):TP_CPU1_RSVD_91':
 C_SIGNAL='@baseboard_fab2_lib.baseboard_fab2(sch_1):tp_cpu1_rsvd_91';
NODE_NAME     U2D1 CH25
 '@BASEBOARD_FAB2_LIB.BASEBOARD_FAB2(SCH_1):PAGE70_I10@CHPSET_LIB.SKX_EXT_B(CHIPS)':
 'RSVD'<91>: CDS_PINID='RSVD(91)';
NET_NAME
'TP_CPU1_RSVD_94'
 '@BASEBOARD_FAB2_LIB.BASEBOARD_FAB2(SCH_1):TP_CPU1_RSVD_94':
 C_SIGNAL='@baseboard_fab2_lib.baseboard_fab2(sch_1):tp_cpu1_rsvd_94';
NODE_NAME     U2D1 CG82
 '@BASEBOARD_FAB2_LIB.BASEBOARD_FAB2(SCH_1):PAGE70_I9@CHPSET_LIB.SKX_EXT_B(CHIPS)':
 'RSVD'<94>: CDS_PINID='RSVD(94)';
NET_NAME
'TP_CPU1_RSVD_95'
 '@BASEBOARD_FAB2_LIB.BASEBOARD_FAB2(SCH_1):TP_CPU1_RSVD_95':
 C_SIGNAL='@baseboard_fab2_lib.baseboard_fab2(sch_1):tp_cpu1_rsvd_95';
NODE_NAME     U2D1 CG78
 '@BASEBOARD_FAB2_LIB.BASEBOARD_FAB2(SCH_1):PAGE70_I9@CHPSET_LIB.SKX_EXT_B(CHIPS)':
 'RSVD'<95>: CDS_PINID='RSVD(95)';
NET_NAME
'TP_CPU1_RSVD_97'
 '@BASEBOARD_FAB2_LIB.BASEBOARD_FAB2(SCH_1):TP_CPU1_RSVD_97':
 C_SIGNAL='@baseboard_fab2_lib.baseboard_fab2(sch_1):tp_cpu1_rsvd_97';
NODE_NAME     U2D1 CG24
 '@BASEBOARD_FAB2_LIB.BASEBOARD_FAB2(SCH_1):PAGE70_I9@CHPSET_LIB.SKX_EXT_B(CHIPS)':
 'RSVD'<97>: CDS_PINID='RSVD(97)';
NET_NAME
'TP_CPU1_RSVD_99'
 '@BASEBOARD_FAB2_LIB.BASEBOARD_FAB2(SCH_1):TP_CPU1_RSVD_99':
 C_SIGNAL='@baseboard_fab2_lib.baseboard_fab2(sch_1):tp_cpu1_rsvd_99';
NODE_NAME     U2D1 CG10
 '@BASEBOARD_FAB2_LIB.BASEBOARD_FAB2(SCH_1):PAGE70_I9@CHPSET_LIB.SKX_EXT_B(CHIPS)':
 'RSVD'<99>: CDS_PINID='RSVD(99)';
NET_NAME
'TP_CPU1_RSVD_TEST_11'
 '@BASEBOARD_FAB2_LIB.BASEBOARD_FAB2(SCH_1):TP_CPU1_RSVD_TEST_11':
 C_SIGNAL='@baseboard_fab2_lib.baseboard_fab2(sch_1):tp_cpu1_rsvd_test_11';
NODE_NAME     U2D1 AY13
 '@BASEBOARD_FAB2_LIB.BASEBOARD_FAB2(SCH_1):PAGE56_I169@CHPSET_LIB.SKX_EXT_B(CHIPS)':
 'TEST_11': CDS_PINID='TEST_11';
NET_NAME
'TP_CPU1_RSVD_TEST_3'
 '@BASEBOARD_FAB2_LIB.BASEBOARD_FAB2(SCH_1):TP_CPU1_RSVD_TEST_3':
 C_SIGNAL='@baseboard_fab2_lib.baseboard_fab2(sch_1):tp_cpu1_rsvd_test_3';
NODE_NAME     U2D1 AM13
 '@BASEBOARD_FAB2_LIB.BASEBOARD_FAB2(SCH_1):PAGE56_I169@CHPSET_LIB.SKX_EXT_B(CHIPS)':
 'TEST_3': CDS_PINID='TEST_3';
NET_NAME
'TP_CPU1_RSVD_TEST_4'
 '@BASEBOARD_FAB2_LIB.BASEBOARD_FAB2(SCH_1):TP_CPU1_RSVD_TEST_4':
 C_SIGNAL='@baseboard_fab2_lib.baseboard_fab2(sch_1):tp_cpu1_rsvd_test_4';
NODE_NAME     U2D1 AN12
 '@BASEBOARD_FAB2_LIB.BASEBOARD_FAB2(SCH_1):PAGE56_I169@CHPSET_LIB.SKX_EXT_B(CHIPS)':
 'TEST_4': CDS_PINID='TEST_4';
NET_NAME
'TP_CPU1_RSVD_TEST_5'
 '@BASEBOARD_FAB2_LIB.BASEBOARD_FAB2(SCH_1):TP_CPU1_RSVD_TEST_5':
 C_SIGNAL='@baseboard_fab2_lib.baseboard_fab2(sch_1):tp_cpu1_rsvd_test_5';
NODE_NAME     U2D1 AN14
 '@BASEBOARD_FAB2_LIB.BASEBOARD_FAB2(SCH_1):PAGE56_I169@CHPSET_LIB.SKX_EXT_B(CHIPS)':
 'TEST_5': CDS_PINID='TEST_5';
NET_NAME
'TP_CPU1_SOCKET_ID_2'
 '@BASEBOARD_FAB2_LIB.BASEBOARD_FAB2(SCH_1):TP_CPU1_SOCKET_ID_2':
 C_SIGNAL='@baseboard_fab2_lib.baseboard_fab2(sch_1):tp_cpu1_socket_id_2';
NODE_NAME     U2D1 AU20
 '@BASEBOARD_FAB2_LIB.BASEBOARD_FAB2(SCH_1):PAGE55_I172@CHPSET_LIB.SKX_EXT_B(CHIPS)':
 'SOCKET_ID'<2>: CDS_PINID='SOCKET_ID(2)';
NET_NAME
'TP_CPU1_TEST_10'
 '@BASEBOARD_FAB2_LIB.BASEBOARD_FAB2(SCH_1):TP_CPU1_TEST_10':
 C_SIGNAL='@baseboard_fab2_lib.baseboard_fab2(sch_1):tp_cpu1_test_10';
NODE_NAME     U2D1 AW22
 '@BASEBOARD_FAB2_LIB.BASEBOARD_FAB2(SCH_1):PAGE70_I10@CHPSET_LIB.SKX_EXT_B(CHIPS)':
 'TEST_10': CDS_PINID='TEST_10';
NET_NAME
'TP_CPU1_TEST_6'
 '@BASEBOARD_FAB2_LIB.BASEBOARD_FAB2(SCH_1):TP_CPU1_TEST_6':
 C_SIGNAL='@baseboard_fab2_lib.baseboard_fab2(sch_1):tp_cpu1_test_6';
NODE_NAME     U2D1 AR16
 '@BASEBOARD_FAB2_LIB.BASEBOARD_FAB2(SCH_1):PAGE70_I10@CHPSET_LIB.SKX_EXT_B(CHIPS)':
 'TEST_6': CDS_PINID='TEST_6';
NET_NAME
'TP_CPU1_TEST_7'
 '@BASEBOARD_FAB2_LIB.BASEBOARD_FAB2(SCH_1):TP_CPU1_TEST_7':
 C_SIGNAL='@baseboard_fab2_lib.baseboard_fab2(sch_1):tp_cpu1_test_7';
NODE_NAME     U2D1 AU18
 '@BASEBOARD_FAB2_LIB.BASEBOARD_FAB2(SCH_1):PAGE70_I10@CHPSET_LIB.SKX_EXT_B(CHIPS)':
 'TEST_7': CDS_PINID='TEST_7';
NET_NAME
'TP_CPU1_TEST_8'
 '@BASEBOARD_FAB2_LIB.BASEBOARD_FAB2(SCH_1):TP_CPU1_TEST_8':
 C_SIGNAL='@baseboard_fab2_lib.baseboard_fab2(sch_1):tp_cpu1_test_8';
NODE_NAME     U2D1 AW16
 '@BASEBOARD_FAB2_LIB.BASEBOARD_FAB2(SCH_1):PAGE70_I10@CHPSET_LIB.SKX_EXT_B(CHIPS)':
 'TEST_8': CDS_PINID='TEST_8';
NET_NAME
'TP_CPU1_TEST_9'
 '@BASEBOARD_FAB2_LIB.BASEBOARD_FAB2(SCH_1):TP_CPU1_TEST_9':
 C_SIGNAL='@baseboard_fab2_lib.baseboard_fab2(sch_1):tp_cpu1_test_9';
NODE_NAME     U2D1 AW20
 '@BASEBOARD_FAB2_LIB.BASEBOARD_FAB2(SCH_1):PAGE70_I10@CHPSET_LIB.SKX_EXT_B(CHIPS)':
 'TEST_9': CDS_PINID='TEST_9';
NET_NAME
'TP_CPU1_UPI2_RSVD_CA12'
 '@BASEBOARD_FAB2_LIB.BASEBOARD_FAB2(SCH_1):TP_CPU1_UPI2_RSVD_CA12':
 C_SIGNAL='@baseboard_fab2_lib.baseboard_fab2(sch_1):tp_cpu1_upi2_rsvd_ca12';
NODE_NAME     U2D1 DP21
 '@BASEBOARD_FAB2_LIB.BASEBOARD_FAB2(SCH_1):PAGE69_I1@CHPSET_LIB.SKX_EXT_B(CHIPS)':
 'UPI2_TX_DP'<0>: CDS_PINID='UPI2_TX_DP(0)';
NET_NAME
'TP_CPU1_UPI2_RSVD_CB11'
 '@BASEBOARD_FAB2_LIB.BASEBOARD_FAB2(SCH_1):TP_CPU1_UPI2_RSVD_CB11':
 C_SIGNAL='@baseboard_fab2_lib.baseboard_fab2(sch_1):tp_cpu1_upi2_rsvd_cb11';
NODE_NAME     U2D1 DN20
 '@BASEBOARD_FAB2_LIB.BASEBOARD_FAB2(SCH_1):PAGE69_I1@CHPSET_LIB.SKX_EXT_B(CHIPS)':
 'UPI2_TX_DP'<1>: CDS_PINID='UPI2_TX_DP(1)';
NET_NAME
'TP_CPU1_UPI2_RSVD_CC10'
 '@BASEBOARD_FAB2_LIB.BASEBOARD_FAB2(SCH_1):TP_CPU1_UPI2_RSVD_CC10':
 C_SIGNAL='@baseboard_fab2_lib.baseboard_fab2(sch_1):tp_cpu1_upi2_rsvd_cc10';
NODE_NAME     U2D1 DM21
 '@BASEBOARD_FAB2_LIB.BASEBOARD_FAB2(SCH_1):PAGE69_I1@CHPSET_LIB.SKX_EXT_B(CHIPS)':
 'UPI2_TX_DN'<1>: CDS_PINID='UPI2_TX_DN(1)';
NET_NAME
'TP_CPU1_UPI2_RSVD_CC12'
 '@BASEBOARD_FAB2_LIB.BASEBOARD_FAB2(SCH_1):TP_CPU1_UPI2_RSVD_CC12':
 C_SIGNAL='@baseboard_fab2_lib.baseboard_fab2(sch_1):tp_cpu1_upi2_rsvd_cc12';
NODE_NAME     U2D1 DT21
 '@BASEBOARD_FAB2_LIB.BASEBOARD_FAB2(SCH_1):PAGE69_I1@CHPSET_LIB.SKX_EXT_B(CHIPS)':
 'UPI2_TX_DN'<0>: CDS_PINID='UPI2_TX_DN(0)';
NET_NAME
'TP_CPU1_UPI2_RSVD_CD11'
 '@BASEBOARD_FAB2_LIB.BASEBOARD_FAB2(SCH_1):TP_CPU1_UPI2_RSVD_CD11':
 C_SIGNAL='@baseboard_fab2_lib.baseboard_fab2(sch_1):tp_cpu1_upi2_rsvd_cd11';
NODE_NAME     U2D1 DK19
 '@BASEBOARD_FAB2_LIB.BASEBOARD_FAB2(SCH_1):PAGE69_I1@CHPSET_LIB.SKX_EXT_B(CHIPS)':
 'UPI2_TX_DP'<2>: CDS_PINID='UPI2_TX_DP(2)';
NET_NAME
'TP_CPU1_UPI2_RSVD_CE12'
 '@BASEBOARD_FAB2_LIB.BASEBOARD_FAB2(SCH_1):TP_CPU1_UPI2_RSVD_CE12':
 C_SIGNAL='@baseboard_fab2_lib.baseboard_fab2(sch_1):tp_cpu1_upi2_rsvd_ce12';
NODE_NAME     U2D1 DL20
 '@BASEBOARD_FAB2_LIB.BASEBOARD_FAB2(SCH_1):PAGE69_I1@CHPSET_LIB.SKX_EXT_B(CHIPS)':
 'UPI2_TX_DN'<2>: CDS_PINID='UPI2_TX_DN(2)';
NET_NAME
'TP_CPU1_UPI2_RSVD_CF11'
 '@BASEBOARD_FAB2_LIB.BASEBOARD_FAB2(SCH_1):TP_CPU1_UPI2_RSVD_CF11':
 C_SIGNAL='@baseboard_fab2_lib.baseboard_fab2(sch_1):tp_cpu1_upi2_rsvd_cf11';
NODE_NAME     U2D1 DJ20
 '@BASEBOARD_FAB2_LIB.BASEBOARD_FAB2(SCH_1):PAGE69_I1@CHPSET_LIB.SKX_EXT_B(CHIPS)':
 'UPI2_TX_DP'<3>: CDS_PINID='UPI2_TX_DP(3)';
NET_NAME
'TP_CPU1_UPI2_RSVD_CF13'
 '@BASEBOARD_FAB2_LIB.BASEBOARD_FAB2(SCH_1):TP_CPU1_UPI2_RSVD_CF13':
 C_SIGNAL='@baseboard_fab2_lib.baseboard_fab2(sch_1):tp_cpu1_upi2_rsvd_cf13';
NODE_NAME     U2D1 DH19
 '@BASEBOARD_FAB2_LIB.BASEBOARD_FAB2(SCH_1):PAGE69_I1@CHPSET_LIB.SKX_EXT_B(CHIPS)':
 'UPI2_TX_DN'<4>: CDS_PINID='UPI2_TX_DN(4)';
NET_NAME
'TP_CPU1_UPI2_RSVD_CG12'
 '@BASEBOARD_FAB2_LIB.BASEBOARD_FAB2(SCH_1):TP_CPU1_UPI2_RSVD_CG12':
 C_SIGNAL='@baseboard_fab2_lib.baseboard_fab2(sch_1):tp_cpu1_upi2_rsvd_cg12';
NODE_NAME     U2D1 DJ18
 '@BASEBOARD_FAB2_LIB.BASEBOARD_FAB2(SCH_1):PAGE69_I1@CHPSET_LIB.SKX_EXT_B(CHIPS)':
 'UPI2_TX_DP'<4>: CDS_PINID='UPI2_TX_DP(4)';
NET_NAME
'TP_CPU1_UPI2_RSVD_CH11'
 '@BASEBOARD_FAB2_LIB.BASEBOARD_FAB2(SCH_1):TP_CPU1_UPI2_RSVD_CH11':
 C_SIGNAL='@baseboard_fab2_lib.baseboard_fab2(sch_1):tp_cpu1_upi2_rsvd_ch11';
NODE_NAME     U2D1 DG20
 '@BASEBOARD_FAB2_LIB.BASEBOARD_FAB2(SCH_1):PAGE69_I1@CHPSET_LIB.SKX_EXT_B(CHIPS)':
 'UPI2_TX_DN'<3>: CDS_PINID='UPI2_TX_DN(3)';
NET_NAME
'TP_CPU1_UPI2_RSVD_CH13'
 '@BASEBOARD_FAB2_LIB.BASEBOARD_FAB2(SCH_1):TP_CPU1_UPI2_RSVD_CH13':
 C_SIGNAL='@baseboard_fab2_lib.baseboard_fab2(sch_1):tp_cpu1_upi2_rsvd_ch13';
NODE_NAME     U2D1 DH17
 '@BASEBOARD_FAB2_LIB.BASEBOARD_FAB2(SCH_1):PAGE69_I1@CHPSET_LIB.SKX_EXT_B(CHIPS)':
 'UPI2_TX_DP'<5>: CDS_PINID='UPI2_TX_DP(5)';
NET_NAME
'TP_CPU1_UPI2_RSVD_CJ14'
 '@BASEBOARD_FAB2_LIB.BASEBOARD_FAB2(SCH_1):TP_CPU1_UPI2_RSVD_CJ14':
 C_SIGNAL='@baseboard_fab2_lib.baseboard_fab2(sch_1):tp_cpu1_upi2_rsvd_cj14';
NODE_NAME     U2D1 DK17
 '@BASEBOARD_FAB2_LIB.BASEBOARD_FAB2(SCH_1):PAGE69_I1@CHPSET_LIB.SKX_EXT_B(CHIPS)':
 'UPI2_TX_DN'<5>: CDS_PINID='UPI2_TX_DN(5)';
NET_NAME
'TP_CPU1_UPI2_RSVD_CK13'
 '@BASEBOARD_FAB2_LIB.BASEBOARD_FAB2(SCH_1):TP_CPU1_UPI2_RSVD_CK13':
 C_SIGNAL='@baseboard_fab2_lib.baseboard_fab2(sch_1):tp_cpu1_upi2_rsvd_ck13';
NODE_NAME     U2D1 DF17
 '@BASEBOARD_FAB2_LIB.BASEBOARD_FAB2(SCH_1):PAGE69_I1@CHPSET_LIB.SKX_EXT_B(CHIPS)':
 'UPI2_TX_DP'<6>: CDS_PINID='UPI2_TX_DP(6)';
NET_NAME
'TP_CPU1_UPI2_RSVD_CM13'
 '@BASEBOARD_FAB2_LIB.BASEBOARD_FAB2(SCH_1):TP_CPU1_UPI2_RSVD_CM13':
 C_SIGNAL='@baseboard_fab2_lib.baseboard_fab2(sch_1):tp_cpu1_upi2_rsvd_cm13';
NODE_NAME     U2D1 DG18
 '@BASEBOARD_FAB2_LIB.BASEBOARD_FAB2(SCH_1):PAGE69_I1@CHPSET_LIB.SKX_EXT_B(CHIPS)':
 'UPI2_TX_DN'<6>: CDS_PINID='UPI2_TX_DN(6)';
NET_NAME
'TP_CPU1_UPI2_RSVD_CR14'
 '@BASEBOARD_FAB2_LIB.BASEBOARD_FAB2(SCH_1):TP_CPU1_UPI2_RSVD_CR14':
 C_SIGNAL='@baseboard_fab2_lib.baseboard_fab2(sch_1):tp_cpu1_upi2_rsvd_cr14';
NODE_NAME     U2D1 DE16
 '@BASEBOARD_FAB2_LIB.BASEBOARD_FAB2(SCH_1):PAGE69_I1@CHPSET_LIB.SKX_EXT_B(CHIPS)':
 'UPI2_TX_DP'<7>: CDS_PINID='UPI2_TX_DP(7)';
NET_NAME
'TP_CPU1_UPI2_RSVD_CU14'
 '@BASEBOARD_FAB2_LIB.BASEBOARD_FAB2(SCH_1):TP_CPU1_UPI2_RSVD_CU14':
 C_SIGNAL='@baseboard_fab2_lib.baseboard_fab2(sch_1):tp_cpu1_upi2_rsvd_cu14';
NODE_NAME     U2D1 DD17
 '@BASEBOARD_FAB2_LIB.BASEBOARD_FAB2(SCH_1):PAGE69_I1@CHPSET_LIB.SKX_EXT_B(CHIPS)':
 'UPI2_TX_DN'<7>: CDS_PINID='UPI2_TX_DN(7)';
NET_NAME
'TP_CPU1_UPI2_RSVD_CV13'
 '@BASEBOARD_FAB2_LIB.BASEBOARD_FAB2(SCH_1):TP_CPU1_UPI2_RSVD_CV13':
 C_SIGNAL='@baseboard_fab2_lib.baseboard_fab2(sch_1):tp_cpu1_upi2_rsvd_cv13';
NODE_NAME     U2D1 DD15
 '@BASEBOARD_FAB2_LIB.BASEBOARD_FAB2(SCH_1):PAGE69_I1@CHPSET_LIB.SKX_EXT_B(CHIPS)':
 'UPI2_TX_DP'<8>: CDS_PINID='UPI2_TX_DP(8)';
NET_NAME
'TP_CPU1_UPI2_RSVD_CW14'
 '@BASEBOARD_FAB2_LIB.BASEBOARD_FAB2(SCH_1):TP_CPU1_UPI2_RSVD_CW14':
 C_SIGNAL='@baseboard_fab2_lib.baseboard_fab2(sch_1):tp_cpu1_upi2_rsvd_cw14';
NODE_NAME     U2D1 DF15
 '@BASEBOARD_FAB2_LIB.BASEBOARD_FAB2(SCH_1):PAGE69_I1@CHPSET_LIB.SKX_EXT_B(CHIPS)':
 'UPI2_TX_DN'<8>: CDS_PINID='UPI2_TX_DN(8)';
NET_NAME
'TP_CPU1_UPI2_RSVD_CW16'
 '@BASEBOARD_FAB2_LIB.BASEBOARD_FAB2(SCH_1):TP_CPU1_UPI2_RSVD_CW16':
 C_SIGNAL='@baseboard_fab2_lib.baseboard_fab2(sch_1):tp_cpu1_upi2_rsvd_cw16';
NODE_NAME     U2D1 DB15
 '@BASEBOARD_FAB2_LIB.BASEBOARD_FAB2(SCH_1):PAGE69_I1@CHPSET_LIB.SKX_EXT_B(CHIPS)':
 'UPI2_TX_DP'<9>: CDS_PINID='UPI2_TX_DP(9)';
NET_NAME
'TP_CPU1_UPI2_RSVD_DA16'
 '@BASEBOARD_FAB2_LIB.BASEBOARD_FAB2(SCH_1):TP_CPU1_UPI2_RSVD_DA16':
 C_SIGNAL='@baseboard_fab2_lib.baseboard_fab2(sch_1):tp_cpu1_upi2_rsvd_da16';
NODE_NAME     U2D1 DC16
 '@BASEBOARD_FAB2_LIB.BASEBOARD_FAB2(SCH_1):PAGE69_I1@CHPSET_LIB.SKX_EXT_B(CHIPS)':
 'UPI2_TX_DN'<9>: CDS_PINID='UPI2_TX_DN(9)';
NET_NAME
'TP_CPU1_UPI2_RSVD_DB15'
 '@BASEBOARD_FAB2_LIB.BASEBOARD_FAB2(SCH_1):TP_CPU1_UPI2_RSVD_DB15':
 C_SIGNAL='@baseboard_fab2_lib.baseboard_fab2(sch_1):tp_cpu1_upi2_rsvd_db15';
NODE_NAME     U2D1 CW16
 '@BASEBOARD_FAB2_LIB.BASEBOARD_FAB2(SCH_1):PAGE69_I1@CHPSET_LIB.SKX_EXT_B(CHIPS)':
 'UPI2_TX_DP'<10>: CDS_PINID='UPI2_TX_DP(10)';
NET_NAME
'TP_CPU1_UPI2_RSVD_DC16'
 '@BASEBOARD_FAB2_LIB.BASEBOARD_FAB2(SCH_1):TP_CPU1_UPI2_RSVD_DC16':
 C_SIGNAL='@baseboard_fab2_lib.baseboard_fab2(sch_1):tp_cpu1_upi2_rsvd_dc16';
NODE_NAME     U2D1 DA16
 '@BASEBOARD_FAB2_LIB.BASEBOARD_FAB2(SCH_1):PAGE69_I1@CHPSET_LIB.SKX_EXT_B(CHIPS)':
 'UPI2_TX_DN'<10>: CDS_PINID='UPI2_TX_DN(10)';
NET_NAME
'TP_CPU1_UPI2_RSVD_DD15'
 '@BASEBOARD_FAB2_LIB.BASEBOARD_FAB2(SCH_1):TP_CPU1_UPI2_RSVD_DD15':
 C_SIGNAL='@baseboard_fab2_lib.baseboard_fab2(sch_1):tp_cpu1_upi2_rsvd_dd15';
NODE_NAME     U2D1 CV13
 '@BASEBOARD_FAB2_LIB.BASEBOARD_FAB2(SCH_1):PAGE69_I1@CHPSET_LIB.SKX_EXT_B(CHIPS)':
 'UPI2_TX_DP'<11>: CDS_PINID='UPI2_TX_DP(11)';
NET_NAME
'TP_CPU1_UPI2_RSVD_DD17'
 '@BASEBOARD_FAB2_LIB.BASEBOARD_FAB2(SCH_1):TP_CPU1_UPI2_RSVD_DD17':
 C_SIGNAL='@baseboard_fab2_lib.baseboard_fab2(sch_1):tp_cpu1_upi2_rsvd_dd17';
NODE_NAME     U2D1 CU14
 '@BASEBOARD_FAB2_LIB.BASEBOARD_FAB2(SCH_1):PAGE69_I1@CHPSET_LIB.SKX_EXT_B(CHIPS)':
 'UPI2_TX_DN'<12>: CDS_PINID='UPI2_TX_DN(12)';
NET_NAME
'TP_CPU1_UPI2_RSVD_DE16'
 '@BASEBOARD_FAB2_LIB.BASEBOARD_FAB2(SCH_1):TP_CPU1_UPI2_RSVD_DE16':
 C_SIGNAL='@baseboard_fab2_lib.baseboard_fab2(sch_1):tp_cpu1_upi2_rsvd_de16';
NODE_NAME     U2D1 CR14
 '@BASEBOARD_FAB2_LIB.BASEBOARD_FAB2(SCH_1):PAGE69_I1@CHPSET_LIB.SKX_EXT_B(CHIPS)':
 'UPI2_TX_DP'<12>: CDS_PINID='UPI2_TX_DP(12)';
NET_NAME
'TP_CPU1_UPI2_RSVD_DF15'
 '@BASEBOARD_FAB2_LIB.BASEBOARD_FAB2(SCH_1):TP_CPU1_UPI2_RSVD_DF15':
 C_SIGNAL='@baseboard_fab2_lib.baseboard_fab2(sch_1):tp_cpu1_upi2_rsvd_df15';
NODE_NAME     U2D1 CW14
 '@BASEBOARD_FAB2_LIB.BASEBOARD_FAB2(SCH_1):PAGE69_I1@CHPSET_LIB.SKX_EXT_B(CHIPS)':
 'UPI2_TX_DN'<11>: CDS_PINID='UPI2_TX_DN(11)';
NET_NAME
'TP_CPU1_UPI2_RSVD_DF17'
 '@BASEBOARD_FAB2_LIB.BASEBOARD_FAB2(SCH_1):TP_CPU1_UPI2_RSVD_DF17':
 C_SIGNAL='@baseboard_fab2_lib.baseboard_fab2(sch_1):tp_cpu1_upi2_rsvd_df17';
NODE_NAME     U2D1 CK13
 '@BASEBOARD_FAB2_LIB.BASEBOARD_FAB2(SCH_1):PAGE69_I1@CHPSET_LIB.SKX_EXT_B(CHIPS)':
 'UPI2_TX_DP'<13>: CDS_PINID='UPI2_TX_DP(13)';
NET_NAME
'TP_CPU1_UPI2_RSVD_DG18'
 '@BASEBOARD_FAB2_LIB.BASEBOARD_FAB2(SCH_1):TP_CPU1_UPI2_RSVD_DG18':
 C_SIGNAL='@baseboard_fab2_lib.baseboard_fab2(sch_1):tp_cpu1_upi2_rsvd_dg18';
NODE_NAME     U2D1 CM13
 '@BASEBOARD_FAB2_LIB.BASEBOARD_FAB2(SCH_1):PAGE69_I1@CHPSET_LIB.SKX_EXT_B(CHIPS)':
 'UPI2_TX_DN'<13>: CDS_PINID='UPI2_TX_DN(13)';
NET_NAME
'TP_CPU1_UPI2_RSVD_DG20'
 '@BASEBOARD_FAB2_LIB.BASEBOARD_FAB2(SCH_1):TP_CPU1_UPI2_RSVD_DG20':
 C_SIGNAL='@baseboard_fab2_lib.baseboard_fab2(sch_1):tp_cpu1_upi2_rsvd_dg20';
NODE_NAME     U2D1 CH11
 '@BASEBOARD_FAB2_LIB.BASEBOARD_FAB2(SCH_1):PAGE69_I1@CHPSET_LIB.SKX_EXT_B(CHIPS)':
 'UPI2_TX_DN'<16>: CDS_PINID='UPI2_TX_DN(16)';
NET_NAME
'TP_CPU1_UPI2_RSVD_DH17'
 '@BASEBOARD_FAB2_LIB.BASEBOARD_FAB2(SCH_1):TP_CPU1_UPI2_RSVD_DH17':
 C_SIGNAL='@baseboard_fab2_lib.baseboard_fab2(sch_1):tp_cpu1_upi2_rsvd_dh17';
NODE_NAME     U2D1 CH13
 '@BASEBOARD_FAB2_LIB.BASEBOARD_FAB2(SCH_1):PAGE69_I1@CHPSET_LIB.SKX_EXT_B(CHIPS)':
 'UPI2_TX_DP'<14>: CDS_PINID='UPI2_TX_DP(14)';
NET_NAME
'TP_CPU1_UPI2_RSVD_DH19'
 '@BASEBOARD_FAB2_LIB.BASEBOARD_FAB2(SCH_1):TP_CPU1_UPI2_RSVD_DH19':
 C_SIGNAL='@baseboard_fab2_lib.baseboard_fab2(sch_1):tp_cpu1_upi2_rsvd_dh19';
NODE_NAME     U2D1 CF13
 '@BASEBOARD_FAB2_LIB.BASEBOARD_FAB2(SCH_1):PAGE69_I1@CHPSET_LIB.SKX_EXT_B(CHIPS)':
 'UPI2_TX_DN'<15>: CDS_PINID='UPI2_TX_DN(15)';
NET_NAME
'TP_CPU1_UPI2_RSVD_DJ18'
 '@BASEBOARD_FAB2_LIB.BASEBOARD_FAB2(SCH_1):TP_CPU1_UPI2_RSVD_DJ18':
 C_SIGNAL='@baseboard_fab2_lib.baseboard_fab2(sch_1):tp_cpu1_upi2_rsvd_dj18';
NODE_NAME     U2D1 CG12
 '@BASEBOARD_FAB2_LIB.BASEBOARD_FAB2(SCH_1):PAGE69_I1@CHPSET_LIB.SKX_EXT_B(CHIPS)':
 'UPI2_TX_DP'<15>: CDS_PINID='UPI2_TX_DP(15)';
NET_NAME
'TP_CPU1_UPI2_RSVD_DJ20'
 '@BASEBOARD_FAB2_LIB.BASEBOARD_FAB2(SCH_1):TP_CPU1_UPI2_RSVD_DJ20':
 C_SIGNAL='@baseboard_fab2_lib.baseboard_fab2(sch_1):tp_cpu1_upi2_rsvd_dj20';
NODE_NAME     U2D1 CF11
 '@BASEBOARD_FAB2_LIB.BASEBOARD_FAB2(SCH_1):PAGE69_I1@CHPSET_LIB.SKX_EXT_B(CHIPS)':
 'UPI2_TX_DP'<16>: CDS_PINID='UPI2_TX_DP(16)';
NET_NAME
'TP_CPU1_UPI2_RSVD_DK17'
 '@BASEBOARD_FAB2_LIB.BASEBOARD_FAB2(SCH_1):TP_CPU1_UPI2_RSVD_DK17':
 C_SIGNAL='@baseboard_fab2_lib.baseboard_fab2(sch_1):tp_cpu1_upi2_rsvd_dk17';
NODE_NAME     U2D1 CJ14
 '@BASEBOARD_FAB2_LIB.BASEBOARD_FAB2(SCH_1):PAGE69_I1@CHPSET_LIB.SKX_EXT_B(CHIPS)':
 'UPI2_TX_DN'<14>: CDS_PINID='UPI2_TX_DN(14)';
NET_NAME
'TP_CPU1_UPI2_RSVD_DK19'
 '@BASEBOARD_FAB2_LIB.BASEBOARD_FAB2(SCH_1):TP_CPU1_UPI2_RSVD_DK19':
 C_SIGNAL='@baseboard_fab2_lib.baseboard_fab2(sch_1):tp_cpu1_upi2_rsvd_dk19';
NODE_NAME     U2D1 CD11
 '@BASEBOARD_FAB2_LIB.BASEBOARD_FAB2(SCH_1):PAGE69_I1@CHPSET_LIB.SKX_EXT_B(CHIPS)':
 'UPI2_TX_DP'<17>: CDS_PINID='UPI2_TX_DP(17)';
NET_NAME
'TP_CPU1_UPI2_RSVD_DL20'
 '@BASEBOARD_FAB2_LIB.BASEBOARD_FAB2(SCH_1):TP_CPU1_UPI2_RSVD_DL20':
 C_SIGNAL='@baseboard_fab2_lib.baseboard_fab2(sch_1):tp_cpu1_upi2_rsvd_dl20';
NODE_NAME     U2D1 CE12
 '@BASEBOARD_FAB2_LIB.BASEBOARD_FAB2(SCH_1):PAGE69_I1@CHPSET_LIB.SKX_EXT_B(CHIPS)':
 'UPI2_TX_DN'<17>: CDS_PINID='UPI2_TX_DN(17)';
NET_NAME
'TP_CPU1_UPI2_RSVD_DM21'
 '@BASEBOARD_FAB2_LIB.BASEBOARD_FAB2(SCH_1):TP_CPU1_UPI2_RSVD_DM21':
 C_SIGNAL='@baseboard_fab2_lib.baseboard_fab2(sch_1):tp_cpu1_upi2_rsvd_dm21';
NODE_NAME     U2D1 CC10
 '@BASEBOARD_FAB2_LIB.BASEBOARD_FAB2(SCH_1):PAGE69_I1@CHPSET_LIB.SKX_EXT_B(CHIPS)':
 'UPI2_TX_DN'<18>: CDS_PINID='UPI2_TX_DN(18)';
NET_NAME
'TP_CPU1_UPI2_RSVD_DN20'
 '@BASEBOARD_FAB2_LIB.BASEBOARD_FAB2(SCH_1):TP_CPU1_UPI2_RSVD_DN20':
 C_SIGNAL='@baseboard_fab2_lib.baseboard_fab2(sch_1):tp_cpu1_upi2_rsvd_dn20';
NODE_NAME     U2D1 CB11
 '@BASEBOARD_FAB2_LIB.BASEBOARD_FAB2(SCH_1):PAGE69_I1@CHPSET_LIB.SKX_EXT_B(CHIPS)':
 'UPI2_TX_DP'<18>: CDS_PINID='UPI2_TX_DP(18)';
NET_NAME
'TP_CPU1_UPI2_RSVD_DP21'
 '@BASEBOARD_FAB2_LIB.BASEBOARD_FAB2(SCH_1):TP_CPU1_UPI2_RSVD_DP21':
 C_SIGNAL='@baseboard_fab2_lib.baseboard_fab2(sch_1):tp_cpu1_upi2_rsvd_dp21';
NODE_NAME     U2D1 CA12
 '@BASEBOARD_FAB2_LIB.BASEBOARD_FAB2(SCH_1):PAGE69_I1@CHPSET_LIB.SKX_EXT_B(CHIPS)':
 'UPI2_TX_DP'<19>: CDS_PINID='UPI2_TX_DP(19)';
NET_NAME
'TP_CPU1_UPI2_RSVD_DT21'
 '@BASEBOARD_FAB2_LIB.BASEBOARD_FAB2(SCH_1):TP_CPU1_UPI2_RSVD_DT21':
 C_SIGNAL='@baseboard_fab2_lib.baseboard_fab2(sch_1):tp_cpu1_upi2_rsvd_dt21';
NODE_NAME     U2D1 CC12
 '@BASEBOARD_FAB2_LIB.BASEBOARD_FAB2(SCH_1):PAGE69_I1@CHPSET_LIB.SKX_EXT_B(CHIPS)':
 'UPI2_TX_DN'<19>: CDS_PINID='UPI2_TX_DN(19)';
NET_NAME
'TP_CPU_PCH_TRIGGER_IN'
 '@BASEBOARD_FAB2_LIB.BASEBOARD_FAB2(SCH_1):TP_CPU_PCH_TRIGGER_IN':
 C_SIGNAL='@baseboard_fab2_lib.baseboard_fab2(sch_1):tp_cpu_pch_trigger_in';
NODE_NAME     U7C1 M7
 '@BASEBOARD_FAB2_LIB.BASEBOARD_FAB2(SCH_1):PAGE118_I73@MSTR_U_PROC.LBG_CORE_QAT_EXT_D(CHIPS)':
 'TRIGGER_IN': CDS_PINID='TRIGGER_IN';
NET_NAME
'TP_CPU_PCH_TRIGGER_OUT'
 '@BASEBOARD_FAB2_LIB.BASEBOARD_FAB2(SCH_1):TP_CPU_PCH_TRIGGER_OUT':
 C_SIGNAL='@baseboard_fab2_lib.baseboard_fab2(sch_1):tp_cpu_pch_trigger_out';
NODE_NAME     U7C1 R13
 '@BASEBOARD_FAB2_LIB.BASEBOARD_FAB2(SCH_1):PAGE118_I73@MSTR_U_PROC.LBG_CORE_QAT_EXT_D(CHIPS)':
 'TRIGGER_OUT': CDS_PINID='TRIGGER_OUT';
NET_NAME
'TP_FET_Q56_3'
 '@BASEBOARD_FAB2_LIB.BASEBOARD_FAB2(SCH_1):TP_FET_Q56_3':
 C_SIGNAL='@baseboard_fab2_lib.baseboard_fab2(sch_1):tp_fet_q56_3';
NODE_NAME     Q1L4 3
 '@BASEBOARD_FAB2_LIB.BASEBOARD_FAB2(SCH_1):PAGE168_I18@MSTR_DISCRETE.FET_N_DUAL(CHIPS)':
 'DRAIN'<0>: CDS_PINID='DRAIN(0)';
NET_NAME
'TP_FET_Q56_4'
 '@BASEBOARD_FAB2_LIB.BASEBOARD_FAB2(SCH_1):TP_FET_Q56_4':
 C_SIGNAL='@baseboard_fab2_lib.baseboard_fab2(sch_1):tp_fet_q56_4';
NODE_NAME     Q1L4 5
 '@BASEBOARD_FAB2_LIB.BASEBOARD_FAB2(SCH_1):PAGE168_I18@MSTR_DISCRETE.FET_N_DUAL(CHIPS)':
 'GATE'<0>: CDS_PINID='GATE(0)';
NODE_NAME     Q1L4 4
 '@BASEBOARD_FAB2_LIB.BASEBOARD_FAB2(SCH_1):PAGE168_I18@MSTR_DISCRETE.FET_N_DUAL(CHIPS)':
 'SOURCE'<0>: CDS_PINID='SOURCE(0)';
NET_NAME
'TP_FM_CPU1_CD_HFI0_MODPRST_N'
 '@BASEBOARD_FAB2_LIB.BASEBOARD_FAB2(SCH_1):TP_FM_CPU1_CD_HFI0_MODPRST_N':
 C_SIGNAL='@baseboard_fab2_lib.baseboard_fab2(sch_1):tp_fm_cpu1_cd_hfi0_modprst_~
n';
NODE_NAME     U2D1 BR20
 '@BASEBOARD_FAB2_LIB.BASEBOARD_FAB2(SCH_1):PAGE63_I23@CHPSET_LIB.SKX_EXT_B(CHIPS)':
 'CD_HFI0_MODPRST_N': CDS_PINID='CD_HFI0_MODPRST_N';
NET_NAME
'TP_FM_QAT_CBL_PRSNT0_R_N'
 '@BASEBOARD_FAB2_LIB.BASEBOARD_FAB2(SCH_1):TP_FM_QAT_CBL_PRSNT0_R_N':
 C_SIGNAL='@baseboard_fab2_lib.baseboard_fab2(sch_1):tp_fm_qat_cbl_prsnt0_r_n';
NODE_NAME     J8A1 1A1
 '@BASEBOARD_FAB2_LIB.BASEBOARD_FAB2(SCH_1):PAGE173_I163@MSTR_CONN.CONN72_G97614002_A(CHIPS)':
 'SIDEBANDA_7': CDS_PINID='SIDEBANDA_7';
NET_NAME
'TP_FM_QAT_CBL_PRSNT1_N_R'
 '@BASEBOARD_FAB2_LIB.BASEBOARD_FAB2(SCH_1):TP_FM_QAT_CBL_PRSNT1_N_R':
 C_SIGNAL='@baseboard_fab2_lib.baseboard_fab2(sch_1):tp_fm_qat_cbl_prsnt1_n_r';
NODE_NAME     J8A1 2A1
 '@BASEBOARD_FAB2_LIB.BASEBOARD_FAB2(SCH_1):PAGE173_I163@MSTR_CONN.CONN72_G97614002_A(CHIPS)':
 'SIDEBANDB_7': CDS_PINID='SIDEBANDB_7';
NET_NAME
'TP_FM_WAKE_N'
 '@BASEBOARD_FAB2_LIB.BASEBOARD_FAB2(SCH_1):TP_FM_WAKE_N':
 C_SIGNAL='@baseboard_fab2_lib.baseboard_fab2(sch_1):tp_fm_wake_n';
NODE_NAME     J1C1 B4
 '@BASEBOARD_FAB2_LIB.BASEBOARD_FAB2(SCH_1):PAGE182_I79@W_HDL.DM-FCI-CONN76-8R-GP-U-01(CHIPS)':
 'FAN_TACH2': CDS_PINID='FAN_TACH2';
NET_NAME
'TP_GTL2014_6_A0'
 '@BASEBOARD_FAB2_LIB.BASEBOARD_FAB2(SCH_1):TP_GTL2014_6_A0':
 C_SIGNAL='@baseboard_fab2_lib.baseboard_fab2(sch_1):tp_gtl2014_6_a0';
NODE_NAME     U25W11 13
 '@BASEBOARD_FAB2_LIB.BASEBOARD_FAB2(SCH_1):PAGE268_I33@MSTR_DIGITAL.GTL2014(CHIPS)':
 'A0': CDS_PINID='A0';
NET_NAME
'TP_GTL2014_6_A2'
 '@BASEBOARD_FAB2_LIB.BASEBOARD_FAB2(SCH_1):TP_GTL2014_6_A2':
 C_SIGNAL='@baseboard_fab2_lib.baseboard_fab2(sch_1):tp_gtl2014_6_a2';
NODE_NAME     U25W11 10
 '@BASEBOARD_FAB2_LIB.BASEBOARD_FAB2(SCH_1):PAGE268_I33@MSTR_DIGITAL.GTL2014(CHIPS)':
 'A2': CDS_PINID='A2';
NET_NAME
'TP_HFI_IO_CONN0_RSVD_17'
 '@BASEBOARD_FAB2_LIB.BASEBOARD_FAB2(SCH_1):TP_HFI_IO_CONN0_RSVD_17':
 C_SIGNAL='@baseboard_fab2_lib.baseboard_fab2(sch_1):tp_hfi_io_conn0_rsvd_17';
NODE_NAME     J8B1 17
 '@BASEBOARD_FAB2_LIB.BASEBOARD_FAB2(SCH_1):PAGE91_I1@MSTR_SCONN.SCONN24_H46321001(CHIPS)':
 'IO17': CDS_PINID='IO17';
NET_NAME
'TP_HSC_ALERT2_N'
 '@BASEBOARD_FAB2_LIB.BASEBOARD_FAB2(SCH_1):TP_HSC_ALERT2_N':
 C_SIGNAL='@baseboard_fab2_lib.baseboard_fab2(sch_1):tp_hsc_alert2_n';
NODE_NAME     EU1D2 14
 '@BASEBOARD_FAB2_LIB.BASEBOARD_FAB2(SCH_1):PAGE199_I10@MSTR_CONTROLLER.ADM1278(CHIPS)':
 'GPO2_ALERT2_N': CDS_PINID='GPO2_ALERT2_N';
NET_NAME
'TP_HSC_MCLK'
 '@BASEBOARD_FAB2_LIB.BASEBOARD_FAB2(SCH_1):TP_HSC_MCLK':
 C_SIGNAL='@baseboard_fab2_lib.baseboard_fab2(sch_1):tp_hsc_mclk';
NODE_NAME     EU1D2 10
 '@BASEBOARD_FAB2_LIB.BASEBOARD_FAB2(SCH_1):PAGE199_I10@MSTR_CONTROLLER.ADM1278(CHIPS)':
 'MCLK': CDS_PINID='MCLK';
NET_NAME
'TP_HSC_MDAT'
 '@BASEBOARD_FAB2_LIB.BASEBOARD_FAB2(SCH_1):TP_HSC_MDAT':
 C_SIGNAL='@baseboard_fab2_lib.baseboard_fab2(sch_1):tp_hsc_mdat';
NODE_NAME     EU1D2 11
 '@BASEBOARD_FAB2_LIB.BASEBOARD_FAB2(SCH_1):PAGE199_I10@MSTR_CONTROLLER.ADM1278(CHIPS)':
 'MDAT': CDS_PINID='MDAT';
NET_NAME
'TP_HSC_SPISSN'
 '@BASEBOARD_FAB2_LIB.BASEBOARD_FAB2(SCH_1):TP_HSC_SPISSN':
 C_SIGNAL='@baseboard_fab2_lib.baseboard_fab2(sch_1):tp_hsc_spissn';
NODE_NAME     EU1D2 9
 '@BASEBOARD_FAB2_LIB.BASEBOARD_FAB2(SCH_1):PAGE199_I10@MSTR_CONTROLLER.ADM1278(CHIPS)':
 'SPISS_N': CDS_PINID='SPISS_N';
NET_NAME
'TP_IE_DEBUG_MODE'
 '@BASEBOARD_FAB2_LIB.BASEBOARD_FAB2(SCH_1):TP_IE_DEBUG_MODE':
 C_SIGNAL='@baseboard_fab2_lib.baseboard_fab2(sch_1):tp_ie_debug_mode';
NODE_NAME     J9G1 7
 '@BASEBOARD_FAB2_LIB.BASEBOARD_FAB2(SCH_1):PAGE137_I128@MSTR_CONN.CONN12_C73564003(CHIPS)':
 'IO7': CDS_PINID='IO7';
NET_NAME
'TP_IOA5'
 '@BASEBOARD_FAB2_LIB.BASEBOARD_FAB2(SCH_1):TP_IOA5':
 C_SIGNAL='@baseboard_fab2_lib.baseboard_fab2(sch_1):tp_ioa5';
NODE_NAME     J1C1 A5
 '@BASEBOARD_FAB2_LIB.BASEBOARD_FAB2(SCH_1):PAGE182_I79@W_HDL.DM-FCI-CONN76-8R-GP-U-01(CHIPS)':
 'MNG_TX_DP': CDS_PINID='MNG_TX_DP';
NET_NAME
'TP_IOE4'
 '@BASEBOARD_FAB2_LIB.BASEBOARD_FAB2(SCH_1):TP_IOE4':
 C_SIGNAL='@baseboard_fab2_lib.baseboard_fab2(sch_1):tp_ioe4';
NODE_NAME     J1C1 E4
 '@BASEBOARD_FAB2_LIB.BASEBOARD_FAB2(SCH_1):PAGE182_I79@W_HDL.DM-FCI-CONN76-8R-GP-U-01(CHIPS)':
 'MATED_IN#': CDS_PINID='\mated_in#\';
NET_NAME
'TP_IOF4'
 '@BASEBOARD_FAB2_LIB.BASEBOARD_FAB2(SCH_1):TP_IOF4':
 C_SIGNAL='@baseboard_fab2_lib.baseboard_fab2(sch_1):tp_iof4';
NODE_NAME     J1C1 F4
 '@BASEBOARD_FAB2_LIB.BASEBOARD_FAB2(SCH_1):PAGE182_I79@W_HDL.DM-FCI-CONN76-8R-GP-U-01(CHIPS)':
 'FAN_PWM0': CDS_PINID='FAN_PWM0';
NET_NAME
'TP_IOG3'
 '@BASEBOARD_FAB2_LIB.BASEBOARD_FAB2(SCH_1):TP_IOG3':
 C_SIGNAL='@baseboard_fab2_lib.baseboard_fab2(sch_1):tp_iog3';
NODE_NAME     J1C1 G3
 '@BASEBOARD_FAB2_LIB.BASEBOARD_FAB2(SCH_1):PAGE182_I79@W_HDL.DM-FCI-CONN76-8R-GP-U-01(CHIPS)':
 'COM_TX': CDS_PINID='COM_TX';
NET_NAME
'TP_IOH3'
 '@BASEBOARD_FAB2_LIB.BASEBOARD_FAB2(SCH_1):TP_IOH3':
 C_SIGNAL='@baseboard_fab2_lib.baseboard_fab2(sch_1):tp_ioh3';
NODE_NAME     J1C1 H3
 '@BASEBOARD_FAB2_LIB.BASEBOARD_FAB2(SCH_1):PAGE182_I79@W_HDL.DM-FCI-CONN76-8R-GP-U-01(CHIPS)':
 'COM_RX': CDS_PINID='COM_RX';
NET_NAME
'TP_IOH4'
 '@BASEBOARD_FAB2_LIB.BASEBOARD_FAB2(SCH_1):TP_IOH4':
 C_SIGNAL='@baseboard_fab2_lib.baseboard_fab2(sch_1):tp_ioh4';
NODE_NAME     J1C1 H4
 '@BASEBOARD_FAB2_LIB.BASEBOARD_FAB2(SCH_1):PAGE182_I79@W_HDL.DM-FCI-CONN76-8R-GP-U-01(CHIPS)':
 'PCIE_CLK_100M_DP': CDS_PINID='PCIE_CLK_100M_DP';
NET_NAME
'TP_IOI4'
 '@BASEBOARD_FAB2_LIB.BASEBOARD_FAB2(SCH_1):TP_IOI4':
 C_SIGNAL='@baseboard_fab2_lib.baseboard_fab2(sch_1):tp_ioi4';
NODE_NAME     J1C1 I4
 '@BASEBOARD_FAB2_LIB.BASEBOARD_FAB2(SCH_1):PAGE182_I79@W_HDL.DM-FCI-CONN76-8R-GP-U-01(CHIPS)':
 'PCIE_CLK_100M_DN': CDS_PINID='PCIE_CLK_100M_DN';
NET_NAME
'TP_IRQ_CPU1_CD_HFI0_N'
 '@BASEBOARD_FAB2_LIB.BASEBOARD_FAB2(SCH_1):TP_IRQ_CPU1_CD_HFI0_N':
 C_SIGNAL='@baseboard_fab2_lib.baseboard_fab2(sch_1):tp_irq_cpu1_cd_hfi0_n';
NODE_NAME     U2D1 BP19
 '@BASEBOARD_FAB2_LIB.BASEBOARD_FAB2(SCH_1):PAGE63_I23@CHPSET_LIB.SKX_EXT_B(CHIPS)':
 'CD_HFI0_INT_N': CDS_PINID='CD_HFI0_INT_N';
NET_NAME
'TP_JTAG_MCP_IO8_RSVD'
 '@BASEBOARD_FAB2_LIB.BASEBOARD_FAB2(SCH_1):TP_JTAG_MCP_IO8_RSVD':
 C_SIGNAL='@baseboard_fab2_lib.baseboard_fab2(sch_1):tp_jtag_mcp_io8_rsvd';
NODE_NAME     J9B4 8
 '@BASEBOARD_FAB2_LIB.BASEBOARD_FAB2(SCH_1):PAGE113_I175@MSTR_SCONN.SCONN10_C12536004(CHIPS)':
 'IO8': CDS_PINID='IO8';
NET_NAME
'TP_JUMPER_BLOCK_1_1'
 '@BASEBOARD_FAB2_LIB.BASEBOARD_FAB2(SCH_1):TP_JUMPER_BLOCK_1_1':
 C_SIGNAL='@baseboard_fab2_lib.baseboard_fab2(sch_1):tp_jumper_block_1_1';
NODE_NAME     J8G2 1
 '@BASEBOARD_FAB2_LIB.BASEBOARD_FAB2(SCH_1):PAGE135_I124@MSTR_CONN.CONN12_C73564003(CHIPS)':
 'IO1': CDS_PINID='IO1';
NET_NAME
'TP_JUMPER_BLOCK_1_2'
 '@BASEBOARD_FAB2_LIB.BASEBOARD_FAB2(SCH_1):TP_JUMPER_BLOCK_1_2':
 C_SIGNAL='@baseboard_fab2_lib.baseboard_fab2(sch_1):tp_jumper_block_1_2';
NODE_NAME     J8G2 2
 '@BASEBOARD_FAB2_LIB.BASEBOARD_FAB2(SCH_1):PAGE135_I124@MSTR_CONN.CONN12_C73564003(CHIPS)':
 'IO2': CDS_PINID='IO2';
NET_NAME
'TP_JUMPER_BLOCK_1_7'
 '@BASEBOARD_FAB2_LIB.BASEBOARD_FAB2(SCH_1):TP_JUMPER_BLOCK_ 1_7':
 C_SIGNAL='@baseboard_fab2_lib.baseboard_fab2(sch_1):\tp_jumper_block_ 1_7\';
NODE_NAME     J8G2 7
 '@BASEBOARD_FAB2_LIB.BASEBOARD_FAB2(SCH_1):PAGE135_I124@MSTR_CONN.CONN12_C73564003(CHIPS)':
 'IO7': CDS_PINID='IO7';
NET_NAME
'TP_JUMPER_BLOCK_1_8'
 '@BASEBOARD_FAB2_LIB.BASEBOARD_FAB2(SCH_1):TP_JUMPER_BLOCK_1_8':
 C_SIGNAL='@baseboard_fab2_lib.baseboard_fab2(sch_1):tp_jumper_block_1_8';
NODE_NAME     J8G2 8
 '@BASEBOARD_FAB2_LIB.BASEBOARD_FAB2(SCH_1):PAGE135_I124@MSTR_CONN.CONN12_C73564003(CHIPS)':
 'IO8': CDS_PINID='IO8';
NET_NAME
'TP_LED_CPU1_CD_HFI0_N'
 '@BASEBOARD_FAB2_LIB.BASEBOARD_FAB2(SCH_1):TP_LED_CPU1_CD_HFI0_N':
 C_SIGNAL='@baseboard_fab2_lib.baseboard_fab2(sch_1):tp_led_cpu1_cd_hfi0_n';
NODE_NAME     U2D1 BK21
 '@BASEBOARD_FAB2_LIB.BASEBOARD_FAB2(SCH_1):PAGE63_I23@CHPSET_LIB.SKX_EXT_B(CHIPS)':
 'CD_HFI0_LED_N': CDS_PINID='CD_HFI0_LED_N';
NET_NAME
'TP_LED_M2_ACT_N'
 '@BASEBOARD_FAB2_LIB.BASEBOARD_FAB2(SCH_1):TP_LED_M2_ACT_N':
 C_SIGNAL='@baseboard_fab2_lib.baseboard_fab2(sch_1):tp_led_m2_act_n';
NODE_NAME     J8F1 10
 '@BASEBOARD_FAB2_LIB.BASEBOARD_FAB2(SCH_1):PAGE185_I143@W_HDL.SKT-MINI67P-41-GP(CHIPS)':
 '10': CDS_PINID='\10\';
NET_NAME
'TP_M2_32M_SUSCLK'
 '@BASEBOARD_FAB2_LIB.BASEBOARD_FAB2(SCH_1):TP_M2_32M_SUSCLK':
 C_SIGNAL='@baseboard_fab2_lib.baseboard_fab2(sch_1):tp_m2_32m_susclk';
NODE_NAME     J8F1 68
 '@BASEBOARD_FAB2_LIB.BASEBOARD_FAB2(SCH_1):PAGE185_I143@W_HDL.SKT-MINI67P-41-GP(CHIPS)':
 '68': CDS_PINID='\68\';
NET_NAME
'TP_M2_DEVSLP'
 '@BASEBOARD_FAB2_LIB.BASEBOARD_FAB2(SCH_1):TP_M2_DEVSLP':
 C_SIGNAL='@baseboard_fab2_lib.baseboard_fab2(sch_1):tp_m2_devslp';
NODE_NAME     J8F1 38
 '@BASEBOARD_FAB2_LIB.BASEBOARD_FAB2(SCH_1):PAGE185_I143@W_HDL.SKT-MINI67P-41-GP(CHIPS)':
 '38': CDS_PINID='\38\';
NET_NAME
'TP_ME_RCVR_BOOT'
 '@BASEBOARD_FAB2_LIB.BASEBOARD_FAB2(SCH_1):TP_ME_RCVR_BOOT':
 C_SIGNAL='@baseboard_fab2_lib.baseboard_fab2(sch_1):tp_me_rcvr_boot';
NODE_NAME     J7G3 1
 '@BASEBOARD_FAB2_LIB.BASEBOARD_FAB2(SCH_1):PAGE136_I174@MSTR_CONN.CONN12_C73564003(CHIPS)':
 'IO1': CDS_PINID='IO1';
NET_NAME
'TP_NMI_CPU0'
 '@BASEBOARD_FAB2_LIB.BASEBOARD_FAB2(SCH_1):TP_NMI_CPU0':
 C_SIGNAL='@baseboard_fab2_lib.baseboard_fab2(sch_1):tp_nmi_cpu0';
NODE_NAME     U5D1 AP11
 '@BASEBOARD_FAB2_LIB.BASEBOARD_FAB2(SCH_1):PAGE21_I259@CHPSET_LIB.SKX_EXT_B(CHIPS)':
 'NMI': CDS_PINID='NMI';
NET_NAME
'TP_P1V05_PCH_GL_0'
 '@BASEBOARD_FAB2_LIB.BASEBOARD_FAB2(SCH_1):TP_P1V05_PCH_GL_0':
 C_SIGNAL='@baseboard_fab2_lib.baseboard_fab2(sch_1):tp_p1v05_pch_gl_0';
NODE_NAME     EU7A2 6
 '@BASEBOARD_FAB2_LIB.BASEBOARD_FAB2(SCH_1):PAGE236_I117@MSTR_DISCRETE.IR354XX(CHIPS)':
 'GL'<0>: CDS_PINID='GL(0)';
NET_NAME
'TP_P1V05_PCH_GL_1'
 '@BASEBOARD_FAB2_LIB.BASEBOARD_FAB2(SCH_1):TP_P1V05_PCH_GL_1':
 C_SIGNAL='@baseboard_fab2_lib.baseboard_fab2(sch_1):tp_p1v05_pch_gl_1';
NODE_NAME     EU7A2 41
 '@BASEBOARD_FAB2_LIB.BASEBOARD_FAB2(SCH_1):PAGE236_I117@MSTR_DISCRETE.IR354XX(CHIPS)':
 'GL'<1>: CDS_PINID='GL(1)';
NET_NAME
'TP_P3E_CPU1_PE1_MP_RXN<0>'
 '@BASEBOARD_FAB2_LIB.BASEBOARD_FAB2(SCH_1):TP_P3E_CPU1_PE1_MP_RXN'<0>:
 C_SIGNAL='@baseboard_fab2_lib.baseboard_fab2(sch_1):tp_p3e_cpu1_pe1_mp_rxn(0)';
NODE_NAME     U2D1 CW8
 '@BASEBOARD_FAB2_LIB.BASEBOARD_FAB2(SCH_1):PAGE64_I68@CHPSET_LIB.SKX_EXT_B(CHIPS)':
 'PE1_RX_DN'<0>: CDS_PINID='PE1_RX_DN(0)';
NET_NAME
'TP_P3E_CPU1_PE1_MP_RXN<1>'
 '@BASEBOARD_FAB2_LIB.BASEBOARD_FAB2(SCH_1):TP_P3E_CPU1_PE1_MP_RXN'<1>:
 C_SIGNAL='@baseboard_fab2_lib.baseboard_fab2(sch_1):tp_p3e_cpu1_pe1_mp_rxn(1)';
NODE_NAME     U2D1 DA8
 '@BASEBOARD_FAB2_LIB.BASEBOARD_FAB2(SCH_1):PAGE64_I68@CHPSET_LIB.SKX_EXT_B(CHIPS)':
 'PE1_RX_DN'<1>: CDS_PINID='PE1_RX_DN(1)';
NET_NAME
'TP_P3E_CPU1_PE1_MP_RXN<2>'
 '@BASEBOARD_FAB2_LIB.BASEBOARD_FAB2(SCH_1):TP_P3E_CPU1_PE1_MP_RXN'<2>:
 C_SIGNAL='@baseboard_fab2_lib.baseboard_fab2(sch_1):tp_p3e_cpu1_pe1_mp_rxn(2)';
NODE_NAME     U2D1 DC8
 '@BASEBOARD_FAB2_LIB.BASEBOARD_FAB2(SCH_1):PAGE64_I68@CHPSET_LIB.SKX_EXT_B(CHIPS)':
 'PE1_RX_DN'<2>: CDS_PINID='PE1_RX_DN(2)';
NET_NAME
'TP_P3E_CPU1_PE1_MP_RXN<3>'
 '@BASEBOARD_FAB2_LIB.BASEBOARD_FAB2(SCH_1):TP_P3E_CPU1_PE1_MP_RXN'<3>:
 C_SIGNAL='@baseboard_fab2_lib.baseboard_fab2(sch_1):tp_p3e_cpu1_pe1_mp_rxn(3)';
NODE_NAME     U2D1 DC10
 '@BASEBOARD_FAB2_LIB.BASEBOARD_FAB2(SCH_1):PAGE64_I68@CHPSET_LIB.SKX_EXT_B(CHIPS)':
 'PE1_RX_DN'<3>: CDS_PINID='PE1_RX_DN(3)';
NET_NAME
'TP_P3E_CPU1_PE1_MP_RXN<4>'
 '@BASEBOARD_FAB2_LIB.BASEBOARD_FAB2(SCH_1):TP_P3E_CPU1_PE1_MP_RXN'<4>:
 C_SIGNAL='@baseboard_fab2_lib.baseboard_fab2(sch_1):tp_p3e_cpu1_pe1_mp_rxn(4)';
NODE_NAME     U2D1 DE10
 '@BASEBOARD_FAB2_LIB.BASEBOARD_FAB2(SCH_1):PAGE64_I68@CHPSET_LIB.SKX_EXT_B(CHIPS)':
 'PE1_RX_DN'<4>: CDS_PINID='PE1_RX_DN(4)';
NET_NAME
'TP_P3E_CPU1_PE1_MP_RXN<5>'
 '@BASEBOARD_FAB2_LIB.BASEBOARD_FAB2(SCH_1):TP_P3E_CPU1_PE1_MP_RXN'<5>:
 C_SIGNAL='@baseboard_fab2_lib.baseboard_fab2(sch_1):tp_p3e_cpu1_pe1_mp_rxn(5)';
NODE_NAME     U2D1 DH9
 '@BASEBOARD_FAB2_LIB.BASEBOARD_FAB2(SCH_1):PAGE64_I68@CHPSET_LIB.SKX_EXT_B(CHIPS)':
 'PE1_RX_DN'<5>: CDS_PINID='PE1_RX_DN(5)';
NET_NAME
'TP_P3E_CPU1_PE1_MP_RXN<6>'
 '@BASEBOARD_FAB2_LIB.BASEBOARD_FAB2(SCH_1):TP_P3E_CPU1_PE1_MP_RXN'<6>:
 C_SIGNAL='@baseboard_fab2_lib.baseboard_fab2(sch_1):tp_p3e_cpu1_pe1_mp_rxn(6)';
NODE_NAME     U2D1 DK9
 '@BASEBOARD_FAB2_LIB.BASEBOARD_FAB2(SCH_1):PAGE64_I68@CHPSET_LIB.SKX_EXT_B(CHIPS)':
 'PE1_RX_DN'<6>: CDS_PINID='PE1_RX_DN(6)';
NET_NAME
'TP_P3E_CPU1_PE1_MP_RXN<7>'
 '@BASEBOARD_FAB2_LIB.BASEBOARD_FAB2(SCH_1):TP_P3E_CPU1_PE1_MP_RXN'<7>:
 C_SIGNAL='@baseboard_fab2_lib.baseboard_fab2(sch_1):tp_p3e_cpu1_pe1_mp_rxn(7)';
NODE_NAME     U2D1 DM9
 '@BASEBOARD_FAB2_LIB.BASEBOARD_FAB2(SCH_1):PAGE64_I68@CHPSET_LIB.SKX_EXT_B(CHIPS)':
 'PE1_RX_DN'<7>: CDS_PINID='PE1_RX_DN(7)';
NET_NAME
'TP_P3E_CPU1_PE1_MP_RXP<0>'
 '@BASEBOARD_FAB2_LIB.BASEBOARD_FAB2(SCH_1):TP_P3E_CPU1_PE1_MP_RXP'<0>:
 C_SIGNAL='@baseboard_fab2_lib.baseboard_fab2(sch_1):tp_p3e_cpu1_pe1_mp_rxp(0)';
NODE_NAME     U2D1 CU8
 '@BASEBOARD_FAB2_LIB.BASEBOARD_FAB2(SCH_1):PAGE64_I68@CHPSET_LIB.SKX_EXT_B(CHIPS)':
 'PE1_RX_DP'<0>: CDS_PINID='PE1_RX_DP(0)';
NET_NAME
'TP_P3E_CPU1_PE1_MP_RXP<1>'
 '@BASEBOARD_FAB2_LIB.BASEBOARD_FAB2(SCH_1):TP_P3E_CPU1_PE1_MP_RXP'<1>:
 C_SIGNAL='@baseboard_fab2_lib.baseboard_fab2(sch_1):tp_p3e_cpu1_pe1_mp_rxp(1)';
NODE_NAME     U2D1 CY7
 '@BASEBOARD_FAB2_LIB.BASEBOARD_FAB2(SCH_1):PAGE64_I68@CHPSET_LIB.SKX_EXT_B(CHIPS)':
 'PE1_RX_DP'<1>: CDS_PINID='PE1_RX_DP(1)';
NET_NAME
'TP_P3E_CPU1_PE1_MP_RXP<2>'
 '@BASEBOARD_FAB2_LIB.BASEBOARD_FAB2(SCH_1):TP_P3E_CPU1_PE1_MP_RXP'<2>:
 C_SIGNAL='@baseboard_fab2_lib.baseboard_fab2(sch_1):tp_p3e_cpu1_pe1_mp_rxp(2)';
NODE_NAME     U2D1 DB9
 '@BASEBOARD_FAB2_LIB.BASEBOARD_FAB2(SCH_1):PAGE64_I68@CHPSET_LIB.SKX_EXT_B(CHIPS)':
 'PE1_RX_DP'<2>: CDS_PINID='PE1_RX_DP(2)';
NET_NAME
'TP_P3E_CPU1_PE1_MP_RXP<3>'
 '@BASEBOARD_FAB2_LIB.BASEBOARD_FAB2(SCH_1):TP_P3E_CPU1_PE1_MP_RXP'<3>:
 C_SIGNAL='@baseboard_fab2_lib.baseboard_fab2(sch_1):tp_p3e_cpu1_pe1_mp_rxp(3)';
NODE_NAME     U2D1 DA10
 '@BASEBOARD_FAB2_LIB.BASEBOARD_FAB2(SCH_1):PAGE64_I68@CHPSET_LIB.SKX_EXT_B(CHIPS)':
 'PE1_RX_DP'<3>: CDS_PINID='PE1_RX_DP(3)';
NET_NAME
'TP_P3E_CPU1_PE1_MP_RXP<4>'
 '@BASEBOARD_FAB2_LIB.BASEBOARD_FAB2(SCH_1):TP_P3E_CPU1_PE1_MP_RXP'<4>:
 C_SIGNAL='@baseboard_fab2_lib.baseboard_fab2(sch_1):tp_p3e_cpu1_pe1_mp_rxp(4)';
NODE_NAME     U2D1 DD9
 '@BASEBOARD_FAB2_LIB.BASEBOARD_FAB2(SCH_1):PAGE64_I68@CHPSET_LIB.SKX_EXT_B(CHIPS)':
 'PE1_RX_DP'<4>: CDS_PINID='PE1_RX_DP(4)';
NET_NAME
'TP_P3E_CPU1_PE1_MP_RXP<5>'
 '@BASEBOARD_FAB2_LIB.BASEBOARD_FAB2(SCH_1):TP_P3E_CPU1_PE1_MP_RXP'<5>:
 C_SIGNAL='@baseboard_fab2_lib.baseboard_fab2(sch_1):tp_p3e_cpu1_pe1_mp_rxp(5)';
NODE_NAME     U2D1 DF9
 '@BASEBOARD_FAB2_LIB.BASEBOARD_FAB2(SCH_1):PAGE64_I68@CHPSET_LIB.SKX_EXT_B(CHIPS)':
 'PE1_RX_DP'<5>: CDS_PINID='PE1_RX_DP(5)';
NET_NAME
'TP_P3E_CPU1_PE1_MP_RXP<6>'
 '@BASEBOARD_FAB2_LIB.BASEBOARD_FAB2(SCH_1):TP_P3E_CPU1_PE1_MP_RXP'<6>:
 C_SIGNAL='@baseboard_fab2_lib.baseboard_fab2(sch_1):tp_p3e_cpu1_pe1_mp_rxp(6)';
NODE_NAME     U2D1 DJ8
 '@BASEBOARD_FAB2_LIB.BASEBOARD_FAB2(SCH_1):PAGE64_I68@CHPSET_LIB.SKX_EXT_B(CHIPS)':
 'PE1_RX_DP'<6>: CDS_PINID='PE1_RX_DP(6)';
NET_NAME
'TP_P3E_CPU1_PE1_MP_RXP<7>'
 '@BASEBOARD_FAB2_LIB.BASEBOARD_FAB2(SCH_1):TP_P3E_CPU1_PE1_MP_RXP'<7>:
 C_SIGNAL='@baseboard_fab2_lib.baseboard_fab2(sch_1):tp_p3e_cpu1_pe1_mp_rxp(7)';
NODE_NAME     U2D1 DL10
 '@BASEBOARD_FAB2_LIB.BASEBOARD_FAB2(SCH_1):PAGE64_I68@CHPSET_LIB.SKX_EXT_B(CHIPS)':
 'PE1_RX_DP'<7>: CDS_PINID='PE1_RX_DP(7)';
NET_NAME
'TP_P3E_CPU1_PE1_MP_TXN<0>'
 '@BASEBOARD_FAB2_LIB.BASEBOARD_FAB2(SCH_1):TP_P3E_CPU1_PE1_MP_TXN'<0>:
 C_SIGNAL='@baseboard_fab2_lib.baseboard_fab2(sch_1):tp_p3e_cpu1_pe1_mp_txn(0)';
NODE_NAME     U2D1 DA2
 '@BASEBOARD_FAB2_LIB.BASEBOARD_FAB2(SCH_1):PAGE64_I68@CHPSET_LIB.SKX_EXT_B(CHIPS)':
 'PE1_TX_DN'<0>: CDS_PINID='PE1_TX_DN(0)';
NET_NAME
'TP_P3E_CPU1_PE1_MP_TXN<1>'
 '@BASEBOARD_FAB2_LIB.BASEBOARD_FAB2(SCH_1):TP_P3E_CPU1_PE1_MP_TXN'<1>:
 C_SIGNAL='@baseboard_fab2_lib.baseboard_fab2(sch_1):tp_p3e_cpu1_pe1_mp_txn(1)';
NODE_NAME     U2D1 DC2
 '@BASEBOARD_FAB2_LIB.BASEBOARD_FAB2(SCH_1):PAGE64_I68@CHPSET_LIB.SKX_EXT_B(CHIPS)':
 'PE1_TX_DN'<1>: CDS_PINID='PE1_TX_DN(1)';
NET_NAME
'TP_P3E_CPU1_PE1_MP_TXN<2>'
 '@BASEBOARD_FAB2_LIB.BASEBOARD_FAB2(SCH_1):TP_P3E_CPU1_PE1_MP_TXN'<2>:
 C_SIGNAL='@baseboard_fab2_lib.baseboard_fab2(sch_1):tp_p3e_cpu1_pe1_mp_txn(2)';
NODE_NAME     U2D1 DE2
 '@BASEBOARD_FAB2_LIB.BASEBOARD_FAB2(SCH_1):PAGE64_I68@CHPSET_LIB.SKX_EXT_B(CHIPS)':
 'PE1_TX_DN'<2>: CDS_PINID='PE1_TX_DN(2)';
NET_NAME
'TP_P3E_CPU1_PE1_MP_TXN<3>'
 '@BASEBOARD_FAB2_LIB.BASEBOARD_FAB2(SCH_1):TP_P3E_CPU1_PE1_MP_TXN'<3>:
 C_SIGNAL='@baseboard_fab2_lib.baseboard_fab2(sch_1):tp_p3e_cpu1_pe1_mp_txn(3)';
NODE_NAME     U2D1 DE4
 '@BASEBOARD_FAB2_LIB.BASEBOARD_FAB2(SCH_1):PAGE64_I68@CHPSET_LIB.SKX_EXT_B(CHIPS)':
 'PE1_TX_DN'<3>: CDS_PINID='PE1_TX_DN(3)';
NET_NAME
'TP_P3E_CPU1_PE1_MP_TXN<4>'
 '@BASEBOARD_FAB2_LIB.BASEBOARD_FAB2(SCH_1):TP_P3E_CPU1_PE1_MP_TXN'<4>:
 C_SIGNAL='@baseboard_fab2_lib.baseboard_fab2(sch_1):tp_p3e_cpu1_pe1_mp_txn(4)';
NODE_NAME     U2D1 DG4
 '@BASEBOARD_FAB2_LIB.BASEBOARD_FAB2(SCH_1):PAGE64_I68@CHPSET_LIB.SKX_EXT_B(CHIPS)':
 'PE1_TX_DN'<4>: CDS_PINID='PE1_TX_DN(4)';
NET_NAME
'TP_P3E_CPU1_PE1_MP_TXN<5>'
 '@BASEBOARD_FAB2_LIB.BASEBOARD_FAB2(SCH_1):TP_P3E_CPU1_PE1_MP_TXN'<5>:
 C_SIGNAL='@baseboard_fab2_lib.baseboard_fab2(sch_1):tp_p3e_cpu1_pe1_mp_txn(5)';
NODE_NAME     U2D1 DK3
 '@BASEBOARD_FAB2_LIB.BASEBOARD_FAB2(SCH_1):PAGE64_I68@CHPSET_LIB.SKX_EXT_B(CHIPS)':
 'PE1_TX_DN'<5>: CDS_PINID='PE1_TX_DN(5)';
NET_NAME
'TP_P3E_CPU1_PE1_MP_TXN<6>'
 '@BASEBOARD_FAB2_LIB.BASEBOARD_FAB2(SCH_1):TP_P3E_CPU1_PE1_MP_TXN'<6>:
 C_SIGNAL='@baseboard_fab2_lib.baseboard_fab2(sch_1):tp_p3e_cpu1_pe1_mp_txn(6)';
NODE_NAME     U2D1 DM3
 '@BASEBOARD_FAB2_LIB.BASEBOARD_FAB2(SCH_1):PAGE64_I68@CHPSET_LIB.SKX_EXT_B(CHIPS)':
 'PE1_TX_DN'<6>: CDS_PINID='PE1_TX_DN(6)';
NET_NAME
'TP_P3E_CPU1_PE1_MP_TXN<7>'
 '@BASEBOARD_FAB2_LIB.BASEBOARD_FAB2(SCH_1):TP_P3E_CPU1_PE1_MP_TXN'<7>:
 C_SIGNAL='@baseboard_fab2_lib.baseboard_fab2(sch_1):tp_p3e_cpu1_pe1_mp_txn(7)';
NODE_NAME     U2D1 DN4
 '@BASEBOARD_FAB2_LIB.BASEBOARD_FAB2(SCH_1):PAGE64_I68@CHPSET_LIB.SKX_EXT_B(CHIPS)':
 'PE1_TX_DN'<7>: CDS_PINID='PE1_TX_DN(7)';
NET_NAME
'TP_P3E_CPU1_PE1_MP_TXP<0>'
 '@BASEBOARD_FAB2_LIB.BASEBOARD_FAB2(SCH_1):TP_P3E_CPU1_PE1_MP_TXP'<0>:
 C_SIGNAL='@baseboard_fab2_lib.baseboard_fab2(sch_1):tp_p3e_cpu1_pe1_mp_txp(0)';
NODE_NAME     U2D1 CW2
 '@BASEBOARD_FAB2_LIB.BASEBOARD_FAB2(SCH_1):PAGE64_I68@CHPSET_LIB.SKX_EXT_B(CHIPS)':
 'PE1_TX_DP'<0>: CDS_PINID='PE1_TX_DP(0)';
NET_NAME
'TP_P3E_CPU1_PE1_MP_TXP<1>'
 '@BASEBOARD_FAB2_LIB.BASEBOARD_FAB2(SCH_1):TP_P3E_CPU1_PE1_MP_TXP'<1>:
 C_SIGNAL='@baseboard_fab2_lib.baseboard_fab2(sch_1):tp_p3e_cpu1_pe1_mp_txp(1)';
NODE_NAME     U2D1 DB1
 '@BASEBOARD_FAB2_LIB.BASEBOARD_FAB2(SCH_1):PAGE64_I68@CHPSET_LIB.SKX_EXT_B(CHIPS)':
 'PE1_TX_DP'<1>: CDS_PINID='PE1_TX_DP(1)';
NET_NAME
'TP_P3E_CPU1_PE1_MP_TXP<2>'
 '@BASEBOARD_FAB2_LIB.BASEBOARD_FAB2(SCH_1):TP_P3E_CPU1_PE1_MP_TXP'<2>:
 C_SIGNAL='@baseboard_fab2_lib.baseboard_fab2(sch_1):tp_p3e_cpu1_pe1_mp_txp(2)';
NODE_NAME     U2D1 DD3
 '@BASEBOARD_FAB2_LIB.BASEBOARD_FAB2(SCH_1):PAGE64_I68@CHPSET_LIB.SKX_EXT_B(CHIPS)':
 'PE1_TX_DP'<2>: CDS_PINID='PE1_TX_DP(2)';
NET_NAME
'TP_P3E_CPU1_PE1_MP_TXP<3>'
 '@BASEBOARD_FAB2_LIB.BASEBOARD_FAB2(SCH_1):TP_P3E_CPU1_PE1_MP_TXP'<3>:
 C_SIGNAL='@baseboard_fab2_lib.baseboard_fab2(sch_1):tp_p3e_cpu1_pe1_mp_txp(3)';
NODE_NAME     U2D1 DC4
 '@BASEBOARD_FAB2_LIB.BASEBOARD_FAB2(SCH_1):PAGE64_I68@CHPSET_LIB.SKX_EXT_B(CHIPS)':
 'PE1_TX_DP'<3>: CDS_PINID='PE1_TX_DP(3)';
NET_NAME
'TP_P3E_CPU1_PE1_MP_TXP<4>'
 '@BASEBOARD_FAB2_LIB.BASEBOARD_FAB2(SCH_1):TP_P3E_CPU1_PE1_MP_TXP'<4>:
 C_SIGNAL='@baseboard_fab2_lib.baseboard_fab2(sch_1):tp_p3e_cpu1_pe1_mp_txp(4)';
NODE_NAME     U2D1 DF3
 '@BASEBOARD_FAB2_LIB.BASEBOARD_FAB2(SCH_1):PAGE64_I68@CHPSET_LIB.SKX_EXT_B(CHIPS)':
 'PE1_TX_DP'<4>: CDS_PINID='PE1_TX_DP(4)';
NET_NAME
'TP_P3E_CPU1_PE1_MP_TXP<5>'
 '@BASEBOARD_FAB2_LIB.BASEBOARD_FAB2(SCH_1):TP_P3E_CPU1_PE1_MP_TXP'<5>:
 C_SIGNAL='@baseboard_fab2_lib.baseboard_fab2(sch_1):tp_p3e_cpu1_pe1_mp_txp(5)';
NODE_NAME     U2D1 DH3
 '@BASEBOARD_FAB2_LIB.BASEBOARD_FAB2(SCH_1):PAGE64_I68@CHPSET_LIB.SKX_EXT_B(CHIPS)':
 'PE1_TX_DP'<5>: CDS_PINID='PE1_TX_DP(5)';
NET_NAME
'TP_P3E_CPU1_PE1_MP_TXP<6>'
 '@BASEBOARD_FAB2_LIB.BASEBOARD_FAB2(SCH_1):TP_P3E_CPU1_PE1_MP_TXP'<6>:
 C_SIGNAL='@baseboard_fab2_lib.baseboard_fab2(sch_1):tp_p3e_cpu1_pe1_mp_txp(6)';
NODE_NAME     U2D1 DL2
 '@BASEBOARD_FAB2_LIB.BASEBOARD_FAB2(SCH_1):PAGE64_I68@CHPSET_LIB.SKX_EXT_B(CHIPS)':
 'PE1_TX_DP'<6>: CDS_PINID='PE1_TX_DP(6)';
NET_NAME
'TP_P3E_CPU1_PE1_MP_TXP<7>'
 '@BASEBOARD_FAB2_LIB.BASEBOARD_FAB2(SCH_1):TP_P3E_CPU1_PE1_MP_TXP'<7>:
 C_SIGNAL='@baseboard_fab2_lib.baseboard_fab2(sch_1):tp_p3e_cpu1_pe1_mp_txp(7)';
NODE_NAME     U2D1 DP3
 '@BASEBOARD_FAB2_LIB.BASEBOARD_FAB2(SCH_1):PAGE64_I68@CHPSET_LIB.SKX_EXT_B(CHIPS)':
 'PE1_TX_DP'<7>: CDS_PINID='PE1_TX_DP(7)';
NET_NAME
'TP_P3E_CPU1_PE1_RSR3_RXN<10>'
 '@BASEBOARD_FAB2_LIB.BASEBOARD_FAB2(SCH_1):TP_P3E_CPU1_PE1_RSR3_RXN'<10>:
 C_SIGNAL='@baseboard_fab2_lib.baseboard_fab2(sch_1):tp_p3e_cpu1_pe1_rsr3_rxn(10~
)';
NODE_NAME     U2D1 DT11
 '@BASEBOARD_FAB2_LIB.BASEBOARD_FAB2(SCH_1):PAGE64_I68@CHPSET_LIB.SKX_EXT_B(CHIPS)':
 'PE1_RX_DN'<10>: CDS_PINID='PE1_RX_DN(10)';
NET_NAME
'TP_P3E_CPU1_PE1_RSR3_RXN<11>'
 '@BASEBOARD_FAB2_LIB.BASEBOARD_FAB2(SCH_1):TP_P3E_CPU1_PE1_RSR3_RXN'<11>:
 C_SIGNAL='@baseboard_fab2_lib.baseboard_fab2(sch_1):tp_p3e_cpu1_pe1_rsr3_rxn(11~
)';
NODE_NAME     U2D1 DT13
 '@BASEBOARD_FAB2_LIB.BASEBOARD_FAB2(SCH_1):PAGE64_I68@CHPSET_LIB.SKX_EXT_B(CHIPS)':
 'PE1_RX_DN'<11>: CDS_PINID='PE1_RX_DN(11)';
NET_NAME
'TP_P3E_CPU1_PE1_RSR3_RXN<12>'
 '@BASEBOARD_FAB2_LIB.BASEBOARD_FAB2(SCH_1):TP_P3E_CPU1_PE1_RSR3_RXN'<12>:
 C_SIGNAL='@baseboard_fab2_lib.baseboard_fab2(sch_1):tp_p3e_cpu1_pe1_rsr3_rxn(12~
)';
NODE_NAME     U2D1 DV13
 '@BASEBOARD_FAB2_LIB.BASEBOARD_FAB2(SCH_1):PAGE64_I68@CHPSET_LIB.SKX_EXT_B(CHIPS)':
 'PE1_RX_DN'<12>: CDS_PINID='PE1_RX_DN(12)';
NET_NAME
'TP_P3E_CPU1_PE1_RSR3_RXN<13>'
 '@BASEBOARD_FAB2_LIB.BASEBOARD_FAB2(SCH_1):TP_P3E_CPU1_PE1_RSR3_RXN'<13>:
 C_SIGNAL='@baseboard_fab2_lib.baseboard_fab2(sch_1):tp_p3e_cpu1_pe1_rsr3_rxn(13~
)';
NODE_NAME     U2D1 DW14
 '@BASEBOARD_FAB2_LIB.BASEBOARD_FAB2(SCH_1):PAGE64_I68@CHPSET_LIB.SKX_EXT_B(CHIPS)':
 'PE1_RX_DN'<13>: CDS_PINID='PE1_RX_DN(13)';
NET_NAME
'TP_P3E_CPU1_PE1_RSR3_RXN<14>'
 '@BASEBOARD_FAB2_LIB.BASEBOARD_FAB2(SCH_1):TP_P3E_CPU1_PE1_RSR3_RXN'<14>:
 C_SIGNAL='@baseboard_fab2_lib.baseboard_fab2(sch_1):tp_p3e_cpu1_pe1_rsr3_rxn(14~
)';
NODE_NAME     U2D1 DY15
 '@BASEBOARD_FAB2_LIB.BASEBOARD_FAB2(SCH_1):PAGE64_I68@CHPSET_LIB.SKX_EXT_B(CHIPS)':
 'PE1_RX_DN'<14>: CDS_PINID='PE1_RX_DN(14)';
NET_NAME
'TP_P3E_CPU1_PE1_RSR3_RXN<15>'
 '@BASEBOARD_FAB2_LIB.BASEBOARD_FAB2(SCH_1):TP_P3E_CPU1_PE1_RSR3_RXN'<15>:
 C_SIGNAL='@baseboard_fab2_lib.baseboard_fab2(sch_1):tp_p3e_cpu1_pe1_rsr3_rxn(15~
)';
NODE_NAME     U2D1 DU16
 '@BASEBOARD_FAB2_LIB.BASEBOARD_FAB2(SCH_1):PAGE64_I68@CHPSET_LIB.SKX_EXT_B(CHIPS)':
 'PE1_RX_DN'<15>: CDS_PINID='PE1_RX_DN(15)';
NET_NAME
'TP_P3E_CPU1_PE1_RSR3_RXN<8>'
 '@BASEBOARD_FAB2_LIB.BASEBOARD_FAB2(SCH_1):TP_P3E_CPU1_PE1_RSR3_RXN'<8>:
 C_SIGNAL='@baseboard_fab2_lib.baseboard_fab2(sch_1):tp_p3e_cpu1_pe1_rsr3_rxn(8)~
';
NODE_NAME     U2D1 DM11
 '@BASEBOARD_FAB2_LIB.BASEBOARD_FAB2(SCH_1):PAGE64_I68@CHPSET_LIB.SKX_EXT_B(CHIPS)':
 'PE1_RX_DN'<8>: CDS_PINID='PE1_RX_DN(8)';
NET_NAME
'TP_P3E_CPU1_PE1_RSR3_RXN<9>'
 '@BASEBOARD_FAB2_LIB.BASEBOARD_FAB2(SCH_1):TP_P3E_CPU1_PE1_RSR3_RXN'<9>:
 C_SIGNAL='@baseboard_fab2_lib.baseboard_fab2(sch_1):tp_p3e_cpu1_pe1_rsr3_rxn(9)~
';
NODE_NAME     U2D1 DP11
 '@BASEBOARD_FAB2_LIB.BASEBOARD_FAB2(SCH_1):PAGE64_I68@CHPSET_LIB.SKX_EXT_B(CHIPS)':
 'PE1_RX_DN'<9>: CDS_PINID='PE1_RX_DN(9)';
NET_NAME
'TP_P3E_CPU1_PE1_RSR3_RXP<10>'
 '@BASEBOARD_FAB2_LIB.BASEBOARD_FAB2(SCH_1):TP_P3E_CPU1_PE1_RSR3_RXP'<10>:
 C_SIGNAL='@baseboard_fab2_lib.baseboard_fab2(sch_1):tp_p3e_cpu1_pe1_rsr3_rxp(10~
)';
NODE_NAME     U2D1 DR12
 '@BASEBOARD_FAB2_LIB.BASEBOARD_FAB2(SCH_1):PAGE64_I68@CHPSET_LIB.SKX_EXT_B(CHIPS)':
 'PE1_RX_DP'<10>: CDS_PINID='PE1_RX_DP(10)';
NET_NAME
'TP_P3E_CPU1_PE1_RSR3_RXP<11>'
 '@BASEBOARD_FAB2_LIB.BASEBOARD_FAB2(SCH_1):TP_P3E_CPU1_PE1_RSR3_RXP'<11>:
 C_SIGNAL='@baseboard_fab2_lib.baseboard_fab2(sch_1):tp_p3e_cpu1_pe1_rsr3_rxp(11~
)';
NODE_NAME     U2D1 DP13
 '@BASEBOARD_FAB2_LIB.BASEBOARD_FAB2(SCH_1):PAGE64_I68@CHPSET_LIB.SKX_EXT_B(CHIPS)':
 'PE1_RX_DP'<11>: CDS_PINID='PE1_RX_DP(11)';
NET_NAME
'TP_P3E_CPU1_PE1_RSR3_RXP<12>'
 '@BASEBOARD_FAB2_LIB.BASEBOARD_FAB2(SCH_1):TP_P3E_CPU1_PE1_RSR3_RXP'<12>:
 C_SIGNAL='@baseboard_fab2_lib.baseboard_fab2(sch_1):tp_p3e_cpu1_pe1_rsr3_rxp(12~
)';
NODE_NAME     U2D1 DU12
 '@BASEBOARD_FAB2_LIB.BASEBOARD_FAB2(SCH_1):PAGE64_I68@CHPSET_LIB.SKX_EXT_B(CHIPS)':
 'PE1_RX_DP'<12>: CDS_PINID='PE1_RX_DP(12)';
NET_NAME
'TP_P3E_CPU1_PE1_RSR3_RXP<13>'
 '@BASEBOARD_FAB2_LIB.BASEBOARD_FAB2(SCH_1):TP_P3E_CPU1_PE1_RSR3_RXP'<13>:
 C_SIGNAL='@baseboard_fab2_lib.baseboard_fab2(sch_1):tp_p3e_cpu1_pe1_rsr3_rxp(13~
)';
NODE_NAME     U2D1 DY13
 '@BASEBOARD_FAB2_LIB.BASEBOARD_FAB2(SCH_1):PAGE64_I68@CHPSET_LIB.SKX_EXT_B(CHIPS)':
 'PE1_RX_DP'<13>: CDS_PINID='PE1_RX_DP(13)';
NET_NAME
'TP_P3E_CPU1_PE1_RSR3_RXP<14>'
 '@BASEBOARD_FAB2_LIB.BASEBOARD_FAB2(SCH_1):TP_P3E_CPU1_PE1_RSR3_RXP'<14>:
 C_SIGNAL='@baseboard_fab2_lib.baseboard_fab2(sch_1):tp_p3e_cpu1_pe1_rsr3_rxp(14~
)';
NODE_NAME     U2D1 DV15
 '@BASEBOARD_FAB2_LIB.BASEBOARD_FAB2(SCH_1):PAGE64_I68@CHPSET_LIB.SKX_EXT_B(CHIPS)':
 'PE1_RX_DP'<14>: CDS_PINID='PE1_RX_DP(14)';
NET_NAME
'TP_P3E_CPU1_PE1_RSR3_RXP<15>'
 '@BASEBOARD_FAB2_LIB.BASEBOARD_FAB2(SCH_1):TP_P3E_CPU1_PE1_RSR3_RXP'<15>:
 C_SIGNAL='@baseboard_fab2_lib.baseboard_fab2(sch_1):tp_p3e_cpu1_pe1_rsr3_rxp(15~
)';
NODE_NAME     U2D1 DT15
 '@BASEBOARD_FAB2_LIB.BASEBOARD_FAB2(SCH_1):PAGE64_I68@CHPSET_LIB.SKX_EXT_B(CHIPS)':
 'PE1_RX_DP'<15>: CDS_PINID='PE1_RX_DP(15)';
NET_NAME
'TP_P3E_CPU1_PE1_RSR3_RXP<8>'
 '@BASEBOARD_FAB2_LIB.BASEBOARD_FAB2(SCH_1):TP_P3E_CPU1_PE1_RSR3_RXP'<8>:
 C_SIGNAL='@baseboard_fab2_lib.baseboard_fab2(sch_1):tp_p3e_cpu1_pe1_rsr3_rxp(8)~
';
NODE_NAME     U2D1 DK11
 '@BASEBOARD_FAB2_LIB.BASEBOARD_FAB2(SCH_1):PAGE64_I68@CHPSET_LIB.SKX_EXT_B(CHIPS)':
 'PE1_RX_DP'<8>: CDS_PINID='PE1_RX_DP(8)';
NET_NAME
'TP_P3E_CPU1_PE1_RSR3_RXP<9>'
 '@BASEBOARD_FAB2_LIB.BASEBOARD_FAB2(SCH_1):TP_P3E_CPU1_PE1_RSR3_RXP'<9>:
 C_SIGNAL='@baseboard_fab2_lib.baseboard_fab2(sch_1):tp_p3e_cpu1_pe1_rsr3_rxp(9)~
';
NODE_NAME     U2D1 DN10
 '@BASEBOARD_FAB2_LIB.BASEBOARD_FAB2(SCH_1):PAGE64_I68@CHPSET_LIB.SKX_EXT_B(CHIPS)':
 'PE1_RX_DP'<9>: CDS_PINID='PE1_RX_DP(9)';
NET_NAME
'TP_P3E_CPU1_PE1_RSR3_TXN<10>'
 '@BASEBOARD_FAB2_LIB.BASEBOARD_FAB2(SCH_1):TP_P3E_CPU1_PE1_RSR3_TXN'<10>:
 C_SIGNAL='@baseboard_fab2_lib.baseboard_fab2(sch_1):tp_p3e_cpu1_pe1_rsr3_txn(10~
)';
NODE_NAME     U2D1 DW4
 '@BASEBOARD_FAB2_LIB.BASEBOARD_FAB2(SCH_1):PAGE64_I68@CHPSET_LIB.SKX_EXT_B(CHIPS)':
 'PE1_TX_DN'<10>: CDS_PINID='PE1_TX_DN(10)';
NET_NAME
'TP_P3E_CPU1_PE1_RSR3_TXN<11>'
 '@BASEBOARD_FAB2_LIB.BASEBOARD_FAB2(SCH_1):TP_P3E_CPU1_PE1_RSR3_TXN'<11>:
 C_SIGNAL='@baseboard_fab2_lib.baseboard_fab2(sch_1):tp_p3e_cpu1_pe1_rsr3_txn(11~
)';
NODE_NAME     U2D1 DU6
 '@BASEBOARD_FAB2_LIB.BASEBOARD_FAB2(SCH_1):PAGE64_I68@CHPSET_LIB.SKX_EXT_B(CHIPS)':
 'PE1_TX_DN'<11>: CDS_PINID='PE1_TX_DN(11)';
NET_NAME
'TP_P3E_CPU1_PE1_RSR3_TXN<12>'
 '@BASEBOARD_FAB2_LIB.BASEBOARD_FAB2(SCH_1):TP_P3E_CPU1_PE1_RSR3_TXN'<12>:
 C_SIGNAL='@baseboard_fab2_lib.baseboard_fab2(sch_1):tp_p3e_cpu1_pe1_rsr3_txn(12~
)';
NODE_NAME     U2D1 DV7
 '@BASEBOARD_FAB2_LIB.BASEBOARD_FAB2(SCH_1):PAGE64_I68@CHPSET_LIB.SKX_EXT_B(CHIPS)':
 'PE1_TX_DN'<12>: CDS_PINID='PE1_TX_DN(12)';
NET_NAME
'TP_P3E_CPU1_PE1_RSR3_TXN<13>'
 '@BASEBOARD_FAB2_LIB.BASEBOARD_FAB2(SCH_1):TP_P3E_CPU1_PE1_RSR3_TXN'<13>:
 C_SIGNAL='@baseboard_fab2_lib.baseboard_fab2(sch_1):tp_p3e_cpu1_pe1_rsr3_txn(13~
)';
NODE_NAME     U2D1 DY7
 '@BASEBOARD_FAB2_LIB.BASEBOARD_FAB2(SCH_1):PAGE64_I68@CHPSET_LIB.SKX_EXT_B(CHIPS)':
 'PE1_TX_DN'<13>: CDS_PINID='PE1_TX_DN(13)';
NET_NAME
'TP_P3E_CPU1_PE1_RSR3_TXN<14>'
 '@BASEBOARD_FAB2_LIB.BASEBOARD_FAB2(SCH_1):TP_P3E_CPU1_PE1_RSR3_TXN'<14>:
 C_SIGNAL='@baseboard_fab2_lib.baseboard_fab2(sch_1):tp_p3e_cpu1_pe1_rsr3_txn(14~
)';
NODE_NAME     U2D1 EA8
 '@BASEBOARD_FAB2_LIB.BASEBOARD_FAB2(SCH_1):PAGE64_I68@CHPSET_LIB.SKX_EXT_B(CHIPS)':
 'PE1_TX_DN'<14>: CDS_PINID='PE1_TX_DN(14)';
NET_NAME
'TP_P3E_CPU1_PE1_RSR3_TXN<15>'
 '@BASEBOARD_FAB2_LIB.BASEBOARD_FAB2(SCH_1):TP_P3E_CPU1_PE1_RSR3_TXN'<15>:
 C_SIGNAL='@baseboard_fab2_lib.baseboard_fab2(sch_1):tp_p3e_cpu1_pe1_rsr3_txn(15~
)';
NODE_NAME     U2D1 ED9
 '@BASEBOARD_FAB2_LIB.BASEBOARD_FAB2(SCH_1):PAGE64_I68@CHPSET_LIB.SKX_EXT_B(CHIPS)':
 'PE1_TX_DN'<15>: CDS_PINID='PE1_TX_DN(15)';
NET_NAME
'TP_P3E_CPU1_PE1_RSR3_TXN<8>'
 '@BASEBOARD_FAB2_LIB.BASEBOARD_FAB2(SCH_1):TP_P3E_CPU1_PE1_RSR3_TXN'<8>:
 C_SIGNAL='@baseboard_fab2_lib.baseboard_fab2(sch_1):tp_p3e_cpu1_pe1_rsr3_txn(8)~
';
NODE_NAME     U2D1 DT5
 '@BASEBOARD_FAB2_LIB.BASEBOARD_FAB2(SCH_1):PAGE64_I68@CHPSET_LIB.SKX_EXT_B(CHIPS)':
 'PE1_TX_DN'<8>: CDS_PINID='PE1_TX_DN(8)';
NET_NAME
'TP_P3E_CPU1_PE1_RSR3_TXN<9>'
 '@BASEBOARD_FAB2_LIB.BASEBOARD_FAB2(SCH_1):TP_P3E_CPU1_PE1_RSR3_TXN'<9>:
 C_SIGNAL='@baseboard_fab2_lib.baseboard_fab2(sch_1):tp_p3e_cpu1_pe1_rsr3_txn(9)~
';
NODE_NAME     U2D1 DV3
 '@BASEBOARD_FAB2_LIB.BASEBOARD_FAB2(SCH_1):PAGE64_I68@CHPSET_LIB.SKX_EXT_B(CHIPS)':
 'PE1_TX_DN'<9>: CDS_PINID='PE1_TX_DN(9)';
NET_NAME
'TP_P3E_CPU1_PE1_RSR3_TXP<10>'
 '@BASEBOARD_FAB2_LIB.BASEBOARD_FAB2(SCH_1):TP_P3E_CPU1_PE1_RSR3_TXP'<10>:
 C_SIGNAL='@baseboard_fab2_lib.baseboard_fab2(sch_1):tp_p3e_cpu1_pe1_rsr3_txp(10~
)';
NODE_NAME     U2D1 DU4
 '@BASEBOARD_FAB2_LIB.BASEBOARD_FAB2(SCH_1):PAGE64_I68@CHPSET_LIB.SKX_EXT_B(CHIPS)':
 'PE1_TX_DP'<10>: CDS_PINID='PE1_TX_DP(10)';
NET_NAME
'TP_P3E_CPU1_PE1_RSR3_TXP<11>'
 '@BASEBOARD_FAB2_LIB.BASEBOARD_FAB2(SCH_1):TP_P3E_CPU1_PE1_RSR3_TXP'<11>:
 C_SIGNAL='@baseboard_fab2_lib.baseboard_fab2(sch_1):tp_p3e_cpu1_pe1_rsr3_txp(11~
)';
NODE_NAME     U2D1 DV5
 '@BASEBOARD_FAB2_LIB.BASEBOARD_FAB2(SCH_1):PAGE64_I68@CHPSET_LIB.SKX_EXT_B(CHIPS)':
 'PE1_TX_DP'<11>: CDS_PINID='PE1_TX_DP(11)';
NET_NAME
'TP_P3E_CPU1_PE1_RSR3_TXP<12>'
 '@BASEBOARD_FAB2_LIB.BASEBOARD_FAB2(SCH_1):TP_P3E_CPU1_PE1_RSR3_TXP'<12>:
 C_SIGNAL='@baseboard_fab2_lib.baseboard_fab2(sch_1):tp_p3e_cpu1_pe1_rsr3_txp(12~
)';
NODE_NAME     U2D1 DT7
 '@BASEBOARD_FAB2_LIB.BASEBOARD_FAB2(SCH_1):PAGE64_I68@CHPSET_LIB.SKX_EXT_B(CHIPS)':
 'PE1_TX_DP'<12>: CDS_PINID='PE1_TX_DP(12)';
NET_NAME
'TP_P3E_CPU1_PE1_RSR3_TXP<13>'
 '@BASEBOARD_FAB2_LIB.BASEBOARD_FAB2(SCH_1):TP_P3E_CPU1_PE1_RSR3_TXP'<13>:
 C_SIGNAL='@baseboard_fab2_lib.baseboard_fab2(sch_1):tp_p3e_cpu1_pe1_rsr3_txp(13~
)';
NODE_NAME     U2D1 DW6
 '@BASEBOARD_FAB2_LIB.BASEBOARD_FAB2(SCH_1):PAGE64_I68@CHPSET_LIB.SKX_EXT_B(CHIPS)':
 'PE1_TX_DP'<13>: CDS_PINID='PE1_TX_DP(13)';
NET_NAME
'TP_P3E_CPU1_PE1_RSR3_TXP<14>'
 '@BASEBOARD_FAB2_LIB.BASEBOARD_FAB2(SCH_1):TP_P3E_CPU1_PE1_RSR3_TXP'<14>:
 C_SIGNAL='@baseboard_fab2_lib.baseboard_fab2(sch_1):tp_p3e_cpu1_pe1_rsr3_txp(14~
)';
NODE_NAME     U2D1 EB7
 '@BASEBOARD_FAB2_LIB.BASEBOARD_FAB2(SCH_1):PAGE64_I68@CHPSET_LIB.SKX_EXT_B(CHIPS)':
 'PE1_TX_DP'<14>: CDS_PINID='PE1_TX_DP(14)';
NET_NAME
'TP_P3E_CPU1_PE1_RSR3_TXP<15>'
 '@BASEBOARD_FAB2_LIB.BASEBOARD_FAB2(SCH_1):TP_P3E_CPU1_PE1_RSR3_TXP'<15>:
 C_SIGNAL='@baseboard_fab2_lib.baseboard_fab2(sch_1):tp_p3e_cpu1_pe1_rsr3_txp(15~
)';
NODE_NAME     U2D1 EC8
 '@BASEBOARD_FAB2_LIB.BASEBOARD_FAB2(SCH_1):PAGE64_I68@CHPSET_LIB.SKX_EXT_B(CHIPS)':
 'PE1_TX_DP'<15>: CDS_PINID='PE1_TX_DP(15)';
NET_NAME
'TP_P3E_CPU1_PE1_RSR3_TXP<8>'
 '@BASEBOARD_FAB2_LIB.BASEBOARD_FAB2(SCH_1):TP_P3E_CPU1_PE1_RSR3_TXP'<8>:
 C_SIGNAL='@baseboard_fab2_lib.baseboard_fab2(sch_1):tp_p3e_cpu1_pe1_rsr3_txp(8)~
';
NODE_NAME     U2D1 DR4
 '@BASEBOARD_FAB2_LIB.BASEBOARD_FAB2(SCH_1):PAGE64_I68@CHPSET_LIB.SKX_EXT_B(CHIPS)':
 'PE1_TX_DP'<8>: CDS_PINID='PE1_TX_DP(8)';
NET_NAME
'TP_P3E_CPU1_PE1_RSR3_TXP<9>'
 '@BASEBOARD_FAB2_LIB.BASEBOARD_FAB2(SCH_1):TP_P3E_CPU1_PE1_RSR3_TXP'<9>:
 C_SIGNAL='@baseboard_fab2_lib.baseboard_fab2(sch_1):tp_p3e_cpu1_pe1_rsr3_txp(9)~
';
NODE_NAME     U2D1 DU2
 '@BASEBOARD_FAB2_LIB.BASEBOARD_FAB2(SCH_1):PAGE64_I68@CHPSET_LIB.SKX_EXT_B(CHIPS)':
 'PE1_TX_DP'<9>: CDS_PINID='PE1_TX_DP(9)';
NET_NAME
'TP_P3E_CPU1_PE2_RSR_RXN<0>'
 '@BASEBOARD_FAB2_LIB.BASEBOARD_FAB2(SCH_1):TP_P3E_CPU1_PE2_RSR_RXN'<0>:
 C_SIGNAL='@baseboard_fab2_lib.baseboard_fab2(sch_1):tp_p3e_cpu1_pe2_rsr_rxn(0)';
NODE_NAME     U2D1 CT9
 '@BASEBOARD_FAB2_LIB.BASEBOARD_FAB2(SCH_1):PAGE65_I68@CHPSET_LIB.SKX_EXT_B(CHIPS)':
 'PE2_RX_DN'<0>: CDS_PINID='PE2_RX_DN(0)';
NET_NAME
'TP_P3E_CPU1_PE2_RSR_RXN<10>'
 '@BASEBOARD_FAB2_LIB.BASEBOARD_FAB2(SCH_1):TP_P3E_CPU1_PE2_RSR_RXN'<10>:
 C_SIGNAL='@baseboard_fab2_lib.baseboard_fab2(sch_1):tp_p3e_cpu1_pe2_rsr_rxn(10)~
';
NODE_NAME     U2D1 BV7
 '@BASEBOARD_FAB2_LIB.BASEBOARD_FAB2(SCH_1):PAGE65_I68@CHPSET_LIB.SKX_EXT_B(CHIPS)':
 'PE2_RX_DN'<10>: CDS_PINID='PE2_RX_DN(10)';
NET_NAME
'TP_P3E_CPU1_PE2_RSR_RXN<11>'
 '@BASEBOARD_FAB2_LIB.BASEBOARD_FAB2(SCH_1):TP_P3E_CPU1_PE2_RSR_RXN'<11>:
 C_SIGNAL='@baseboard_fab2_lib.baseboard_fab2(sch_1):tp_p3e_cpu1_pe2_rsr_rxn(11)~
';
NODE_NAME     U2D1 BT7
 '@BASEBOARD_FAB2_LIB.BASEBOARD_FAB2(SCH_1):PAGE65_I68@CHPSET_LIB.SKX_EXT_B(CHIPS)':
 'PE2_RX_DN'<11>: CDS_PINID='PE2_RX_DN(11)';
NET_NAME
'TP_P3E_CPU1_PE2_RSR_RXN<12>'
 '@BASEBOARD_FAB2_LIB.BASEBOARD_FAB2(SCH_1):TP_P3E_CPU1_PE2_RSR_RXN'<12>:
 C_SIGNAL='@baseboard_fab2_lib.baseboard_fab2(sch_1):tp_p3e_cpu1_pe2_rsr_rxn(12)~
';
NODE_NAME     U2D1 BR8
 '@BASEBOARD_FAB2_LIB.BASEBOARD_FAB2(SCH_1):PAGE65_I68@CHPSET_LIB.SKX_EXT_B(CHIPS)':
 'PE2_RX_DN'<12>: CDS_PINID='PE2_RX_DN(12)';
NET_NAME
'TP_P3E_CPU1_PE2_RSR_RXN<13>'
 '@BASEBOARD_FAB2_LIB.BASEBOARD_FAB2(SCH_1):TP_P3E_CPU1_PE2_RSR_RXN'<13>:
 C_SIGNAL='@baseboard_fab2_lib.baseboard_fab2(sch_1):tp_p3e_cpu1_pe2_rsr_rxn(13)~
';
NODE_NAME     U2D1 BN8
 '@BASEBOARD_FAB2_LIB.BASEBOARD_FAB2(SCH_1):PAGE65_I68@CHPSET_LIB.SKX_EXT_B(CHIPS)':
 'PE2_RX_DN'<13>: CDS_PINID='PE2_RX_DN(13)';
NET_NAME
'TP_P3E_CPU1_PE2_RSR_RXN<14>'
 '@BASEBOARD_FAB2_LIB.BASEBOARD_FAB2(SCH_1):TP_P3E_CPU1_PE2_RSR_RXN'<14>:
 C_SIGNAL='@baseboard_fab2_lib.baseboard_fab2(sch_1):tp_p3e_cpu1_pe2_rsr_rxn(14)~
';
NODE_NAME     U2D1 BL8
 '@BASEBOARD_FAB2_LIB.BASEBOARD_FAB2(SCH_1):PAGE65_I68@CHPSET_LIB.SKX_EXT_B(CHIPS)':
 'PE2_RX_DN'<14>: CDS_PINID='PE2_RX_DN(14)';
NET_NAME
'TP_P3E_CPU1_PE2_RSR_RXN<15>'
 '@BASEBOARD_FAB2_LIB.BASEBOARD_FAB2(SCH_1):TP_P3E_CPU1_PE2_RSR_RXN'<15>:
 C_SIGNAL='@baseboard_fab2_lib.baseboard_fab2(sch_1):tp_p3e_cpu1_pe2_rsr_rxn(15)~
';
NODE_NAME     U2D1 BK9
 '@BASEBOARD_FAB2_LIB.BASEBOARD_FAB2(SCH_1):PAGE65_I68@CHPSET_LIB.SKX_EXT_B(CHIPS)':
 'PE2_RX_DN'<15>: CDS_PINID='PE2_RX_DN(15)';
NET_NAME
'TP_P3E_CPU1_PE2_RSR_RXN<1>'
 '@BASEBOARD_FAB2_LIB.BASEBOARD_FAB2(SCH_1):TP_P3E_CPU1_PE2_RSR_RXN'<1>:
 C_SIGNAL='@baseboard_fab2_lib.baseboard_fab2(sch_1):tp_p3e_cpu1_pe2_rsr_rxn(1)';
NODE_NAME     U2D1 CP9
 '@BASEBOARD_FAB2_LIB.BASEBOARD_FAB2(SCH_1):PAGE65_I68@CHPSET_LIB.SKX_EXT_B(CHIPS)':
 'PE2_RX_DN'<1>: CDS_PINID='PE2_RX_DN(1)';
NET_NAME
'TP_P3E_CPU1_PE2_RSR_RXN<2>'
 '@BASEBOARD_FAB2_LIB.BASEBOARD_FAB2(SCH_1):TP_P3E_CPU1_PE2_RSR_RXN'<2>:
 C_SIGNAL='@baseboard_fab2_lib.baseboard_fab2(sch_1):tp_p3e_cpu1_pe2_rsr_rxn(2)';
NODE_NAME     U2D1 CP7
 '@BASEBOARD_FAB2_LIB.BASEBOARD_FAB2(SCH_1):PAGE65_I68@CHPSET_LIB.SKX_EXT_B(CHIPS)':
 'PE2_RX_DN'<2>: CDS_PINID='PE2_RX_DN(2)';
NET_NAME
'TP_P3E_CPU1_PE2_RSR_RXN<3>'
 '@BASEBOARD_FAB2_LIB.BASEBOARD_FAB2(SCH_1):TP_P3E_CPU1_PE2_RSR_RXN'<3>:
 C_SIGNAL='@baseboard_fab2_lib.baseboard_fab2(sch_1):tp_p3e_cpu1_pe2_rsr_rxn(3)';
NODE_NAME     U2D1 CM7
 '@BASEBOARD_FAB2_LIB.BASEBOARD_FAB2(SCH_1):PAGE65_I68@CHPSET_LIB.SKX_EXT_B(CHIPS)':
 'PE2_RX_DN'<3>: CDS_PINID='PE2_RX_DN(3)';
NET_NAME
'TP_P3E_CPU1_PE2_RSR_RXN<4>'
 '@BASEBOARD_FAB2_LIB.BASEBOARD_FAB2(SCH_1):TP_P3E_CPU1_PE2_RSR_RXN'<4>:
 C_SIGNAL='@baseboard_fab2_lib.baseboard_fab2(sch_1):tp_p3e_cpu1_pe2_rsr_rxn(4)';
NODE_NAME     U2D1 CK7
 '@BASEBOARD_FAB2_LIB.BASEBOARD_FAB2(SCH_1):PAGE65_I68@CHPSET_LIB.SKX_EXT_B(CHIPS)':
 'PE2_RX_DN'<4>: CDS_PINID='PE2_RX_DN(4)';
NET_NAME
'TP_P3E_CPU1_PE2_RSR_RXN<5>'
 '@BASEBOARD_FAB2_LIB.BASEBOARD_FAB2(SCH_1):TP_P3E_CPU1_PE2_RSR_RXN'<5>:
 C_SIGNAL='@baseboard_fab2_lib.baseboard_fab2(sch_1):tp_p3e_cpu1_pe2_rsr_rxn(5)';
NODE_NAME     U2D1 CG8
 '@BASEBOARD_FAB2_LIB.BASEBOARD_FAB2(SCH_1):PAGE65_I68@CHPSET_LIB.SKX_EXT_B(CHIPS)':
 'PE2_RX_DN'<5>: CDS_PINID='PE2_RX_DN(5)';
NET_NAME
'TP_P3E_CPU1_PE2_RSR_RXN<6>'
 '@BASEBOARD_FAB2_LIB.BASEBOARD_FAB2(SCH_1):TP_P3E_CPU1_PE2_RSR_RXN'<6>:
 C_SIGNAL='@baseboard_fab2_lib.baseboard_fab2(sch_1):tp_p3e_cpu1_pe2_rsr_rxn(6)';
NODE_NAME     U2D1 CE6
 '@BASEBOARD_FAB2_LIB.BASEBOARD_FAB2(SCH_1):PAGE65_I68@CHPSET_LIB.SKX_EXT_B(CHIPS)':
 'PE2_RX_DN'<6>: CDS_PINID='PE2_RX_DN(6)';
NET_NAME
'TP_P3E_CPU1_PE2_RSR_RXN<7>'
 '@BASEBOARD_FAB2_LIB.BASEBOARD_FAB2(SCH_1):TP_P3E_CPU1_PE2_RSR_RXN'<7>:
 C_SIGNAL='@baseboard_fab2_lib.baseboard_fab2(sch_1):tp_p3e_cpu1_pe2_rsr_rxn(7)';
NODE_NAME     U2D1 CE8
 '@BASEBOARD_FAB2_LIB.BASEBOARD_FAB2(SCH_1):PAGE65_I68@CHPSET_LIB.SKX_EXT_B(CHIPS)':
 'PE2_RX_DN'<7>: CDS_PINID='PE2_RX_DN(7)';
NET_NAME
'TP_P3E_CPU1_PE2_RSR_RXN<8>'
 '@BASEBOARD_FAB2_LIB.BASEBOARD_FAB2(SCH_1):TP_P3E_CPU1_PE2_RSR_RXN'<8>:
 C_SIGNAL='@baseboard_fab2_lib.baseboard_fab2(sch_1):tp_p3e_cpu1_pe2_rsr_rxn(8)';
NODE_NAME     U2D1 BY9
 '@BASEBOARD_FAB2_LIB.BASEBOARD_FAB2(SCH_1):PAGE65_I68@CHPSET_LIB.SKX_EXT_B(CHIPS)':
 'PE2_RX_DN'<8>: CDS_PINID='PE2_RX_DN(8)';
NET_NAME
'TP_P3E_CPU1_PE2_RSR_RXN<9>'
 '@BASEBOARD_FAB2_LIB.BASEBOARD_FAB2(SCH_1):TP_P3E_CPU1_PE2_RSR_RXN'<9>:
 C_SIGNAL='@baseboard_fab2_lib.baseboard_fab2(sch_1):tp_p3e_cpu1_pe2_rsr_rxn(9)';
NODE_NAME     U2D1 BY7
 '@BASEBOARD_FAB2_LIB.BASEBOARD_FAB2(SCH_1):PAGE65_I68@CHPSET_LIB.SKX_EXT_B(CHIPS)':
 'PE2_RX_DN'<9>: CDS_PINID='PE2_RX_DN(9)';
NET_NAME
'TP_P3E_CPU1_PE2_RSR_RXP<0>'
 '@BASEBOARD_FAB2_LIB.BASEBOARD_FAB2(SCH_1):TP_P3E_CPU1_PE2_RSR_RXP'<0>:
 C_SIGNAL='@baseboard_fab2_lib.baseboard_fab2(sch_1):tp_p3e_cpu1_pe2_rsr_rxp(0)';
NODE_NAME     U2D1 CR8
 '@BASEBOARD_FAB2_LIB.BASEBOARD_FAB2(SCH_1):PAGE65_I68@CHPSET_LIB.SKX_EXT_B(CHIPS)':
 'PE2_RX_DP'<0>: CDS_PINID='PE2_RX_DP(0)';
NET_NAME
'TP_P3E_CPU1_PE2_RSR_RXP<10>'
 '@BASEBOARD_FAB2_LIB.BASEBOARD_FAB2(SCH_1):TP_P3E_CPU1_PE2_RSR_RXP'<10>:
 C_SIGNAL='@baseboard_fab2_lib.baseboard_fab2(sch_1):tp_p3e_cpu1_pe2_rsr_rxp(10)~
';
NODE_NAME     U2D1 BU6
 '@BASEBOARD_FAB2_LIB.BASEBOARD_FAB2(SCH_1):PAGE65_I68@CHPSET_LIB.SKX_EXT_B(CHIPS)':
 'PE2_RX_DP'<10>: CDS_PINID='PE2_RX_DP(10)';
NET_NAME
'TP_P3E_CPU1_PE2_RSR_RXP<11>'
 '@BASEBOARD_FAB2_LIB.BASEBOARD_FAB2(SCH_1):TP_P3E_CPU1_PE2_RSR_RXP'<11>:
 C_SIGNAL='@baseboard_fab2_lib.baseboard_fab2(sch_1):tp_p3e_cpu1_pe2_rsr_rxp(11)~
';
NODE_NAME     U2D1 BP7
 '@BASEBOARD_FAB2_LIB.BASEBOARD_FAB2(SCH_1):PAGE65_I68@CHPSET_LIB.SKX_EXT_B(CHIPS)':
 'PE2_RX_DP'<11>: CDS_PINID='PE2_RX_DP(11)';
NET_NAME
'TP_P3E_CPU1_PE2_RSR_RXP<12>'
 '@BASEBOARD_FAB2_LIB.BASEBOARD_FAB2(SCH_1):TP_P3E_CPU1_PE2_RSR_RXP'<12>:
 C_SIGNAL='@baseboard_fab2_lib.baseboard_fab2(sch_1):tp_p3e_cpu1_pe2_rsr_rxp(12)~
';
NODE_NAME     U2D1 BP9
 '@BASEBOARD_FAB2_LIB.BASEBOARD_FAB2(SCH_1):PAGE65_I68@CHPSET_LIB.SKX_EXT_B(CHIPS)':
 'PE2_RX_DP'<12>: CDS_PINID='PE2_RX_DP(12)';
NET_NAME
'TP_P3E_CPU1_PE2_RSR_RXP<13>'
 '@BASEBOARD_FAB2_LIB.BASEBOARD_FAB2(SCH_1):TP_P3E_CPU1_PE2_RSR_RXP'<13>:
 C_SIGNAL='@baseboard_fab2_lib.baseboard_fab2(sch_1):tp_p3e_cpu1_pe2_rsr_rxp(13)~
';
NODE_NAME     U2D1 BM7
 '@BASEBOARD_FAB2_LIB.BASEBOARD_FAB2(SCH_1):PAGE65_I68@CHPSET_LIB.SKX_EXT_B(CHIPS)':
 'PE2_RX_DP'<13>: CDS_PINID='PE2_RX_DP(13)';
NET_NAME
'TP_P3E_CPU1_PE2_RSR_RXP<14>'
 '@BASEBOARD_FAB2_LIB.BASEBOARD_FAB2(SCH_1):TP_P3E_CPU1_PE2_RSR_RXP'<14>:
 C_SIGNAL='@baseboard_fab2_lib.baseboard_fab2(sch_1):tp_p3e_cpu1_pe2_rsr_rxp(14)~
';
NODE_NAME     U2D1 BJ8
 '@BASEBOARD_FAB2_LIB.BASEBOARD_FAB2(SCH_1):PAGE65_I68@CHPSET_LIB.SKX_EXT_B(CHIPS)':
 'PE2_RX_DP'<14>: CDS_PINID='PE2_RX_DP(14)';
NET_NAME
'TP_P3E_CPU1_PE2_RSR_RXP<15>'
 '@BASEBOARD_FAB2_LIB.BASEBOARD_FAB2(SCH_1):TP_P3E_CPU1_PE2_RSR_RXP'<15>:
 C_SIGNAL='@baseboard_fab2_lib.baseboard_fab2(sch_1):tp_p3e_cpu1_pe2_rsr_rxp(15)~
';
NODE_NAME     U2D1 BJ10
 '@BASEBOARD_FAB2_LIB.BASEBOARD_FAB2(SCH_1):PAGE65_I68@CHPSET_LIB.SKX_EXT_B(CHIPS)':
 'PE2_RX_DP'<15>: CDS_PINID='PE2_RX_DP(15)';
NET_NAME
'TP_P3E_CPU1_PE2_RSR_RXP<1>'
 '@BASEBOARD_FAB2_LIB.BASEBOARD_FAB2(SCH_1):TP_P3E_CPU1_PE2_RSR_RXP'<1>:
 C_SIGNAL='@baseboard_fab2_lib.baseboard_fab2(sch_1):tp_p3e_cpu1_pe2_rsr_rxp(1)';
NODE_NAME     U2D1 CM9
 '@BASEBOARD_FAB2_LIB.BASEBOARD_FAB2(SCH_1):PAGE65_I68@CHPSET_LIB.SKX_EXT_B(CHIPS)':
 'PE2_RX_DP'<1>: CDS_PINID='PE2_RX_DP(1)';
NET_NAME
'TP_P3E_CPU1_PE2_RSR_RXP<2>'
 '@BASEBOARD_FAB2_LIB.BASEBOARD_FAB2(SCH_1):TP_P3E_CPU1_PE2_RSR_RXP'<2>:
 C_SIGNAL='@baseboard_fab2_lib.baseboard_fab2(sch_1):tp_p3e_cpu1_pe2_rsr_rxp(2)';
NODE_NAME     U2D1 CN8
 '@BASEBOARD_FAB2_LIB.BASEBOARD_FAB2(SCH_1):PAGE65_I68@CHPSET_LIB.SKX_EXT_B(CHIPS)':
 'PE2_RX_DP'<2>: CDS_PINID='PE2_RX_DP(2)';
NET_NAME
'TP_P3E_CPU1_PE2_RSR_RXP<3>'
 '@BASEBOARD_FAB2_LIB.BASEBOARD_FAB2(SCH_1):TP_P3E_CPU1_PE2_RSR_RXP'<3>:
 C_SIGNAL='@baseboard_fab2_lib.baseboard_fab2(sch_1):tp_p3e_cpu1_pe2_rsr_rxp(3)';
NODE_NAME     U2D1 CL6
 '@BASEBOARD_FAB2_LIB.BASEBOARD_FAB2(SCH_1):PAGE65_I68@CHPSET_LIB.SKX_EXT_B(CHIPS)':
 'PE2_RX_DP'<3>: CDS_PINID='PE2_RX_DP(3)';
NET_NAME
'TP_P3E_CPU1_PE2_RSR_RXP<4>'
 '@BASEBOARD_FAB2_LIB.BASEBOARD_FAB2(SCH_1):TP_P3E_CPU1_PE2_RSR_RXP'<4>:
 C_SIGNAL='@baseboard_fab2_lib.baseboard_fab2(sch_1):tp_p3e_cpu1_pe2_rsr_rxp(4)';
NODE_NAME     U2D1 CH7
 '@BASEBOARD_FAB2_LIB.BASEBOARD_FAB2(SCH_1):PAGE65_I68@CHPSET_LIB.SKX_EXT_B(CHIPS)':
 'PE2_RX_DP'<4>: CDS_PINID='PE2_RX_DP(4)';
NET_NAME
'TP_P3E_CPU1_PE2_RSR_RXP<5>'
 '@BASEBOARD_FAB2_LIB.BASEBOARD_FAB2(SCH_1):TP_P3E_CPU1_PE2_RSR_RXP'<5>:
 C_SIGNAL='@baseboard_fab2_lib.baseboard_fab2(sch_1):tp_p3e_cpu1_pe2_rsr_rxp(5)';
NODE_NAME     U2D1 CF7
 '@BASEBOARD_FAB2_LIB.BASEBOARD_FAB2(SCH_1):PAGE65_I68@CHPSET_LIB.SKX_EXT_B(CHIPS)':
 'PE2_RX_DP'<5>: CDS_PINID='PE2_RX_DP(5)';
NET_NAME
'TP_P3E_CPU1_PE2_RSR_RXP<6>'
 '@BASEBOARD_FAB2_LIB.BASEBOARD_FAB2(SCH_1):TP_P3E_CPU1_PE2_RSR_RXP'<6>:
 C_SIGNAL='@baseboard_fab2_lib.baseboard_fab2(sch_1):tp_p3e_cpu1_pe2_rsr_rxp(6)';
NODE_NAME     U2D1 CD7
 '@BASEBOARD_FAB2_LIB.BASEBOARD_FAB2(SCH_1):PAGE65_I68@CHPSET_LIB.SKX_EXT_B(CHIPS)':
 'PE2_RX_DP'<6>: CDS_PINID='PE2_RX_DP(6)';
NET_NAME
'TP_P3E_CPU1_PE2_RSR_RXP<7>'
 '@BASEBOARD_FAB2_LIB.BASEBOARD_FAB2(SCH_1):TP_P3E_CPU1_PE2_RSR_RXP'<7>:
 C_SIGNAL='@baseboard_fab2_lib.baseboard_fab2(sch_1):tp_p3e_cpu1_pe2_rsr_rxp(7)';
NODE_NAME     U2D1 CC8
 '@BASEBOARD_FAB2_LIB.BASEBOARD_FAB2(SCH_1):PAGE65_I68@CHPSET_LIB.SKX_EXT_B(CHIPS)':
 'PE2_RX_DP'<7>: CDS_PINID='PE2_RX_DP(7)';
NET_NAME
'TP_P3E_CPU1_PE2_RSR_RXP<8>'
 '@BASEBOARD_FAB2_LIB.BASEBOARD_FAB2(SCH_1):TP_P3E_CPU1_PE2_RSR_RXP'<8>:
 C_SIGNAL='@baseboard_fab2_lib.baseboard_fab2(sch_1):tp_p3e_cpu1_pe2_rsr_rxp(8)';
NODE_NAME     U2D1 BV9
 '@BASEBOARD_FAB2_LIB.BASEBOARD_FAB2(SCH_1):PAGE65_I68@CHPSET_LIB.SKX_EXT_B(CHIPS)':
 'PE2_RX_DP'<8>: CDS_PINID='PE2_RX_DP(8)';
NET_NAME
'TP_P3E_CPU1_PE2_RSR_RXP<9>'
 '@BASEBOARD_FAB2_LIB.BASEBOARD_FAB2(SCH_1):TP_P3E_CPU1_PE2_RSR_RXP'<9>:
 C_SIGNAL='@baseboard_fab2_lib.baseboard_fab2(sch_1):tp_p3e_cpu1_pe2_rsr_rxp(9)';
NODE_NAME     U2D1 BW8
 '@BASEBOARD_FAB2_LIB.BASEBOARD_FAB2(SCH_1):PAGE65_I68@CHPSET_LIB.SKX_EXT_B(CHIPS)':
 'PE2_RX_DP'<9>: CDS_PINID='PE2_RX_DP(9)';
NET_NAME
'TP_P3E_CPU1_PE2_RSR_TXN<0>'
 '@BASEBOARD_FAB2_LIB.BASEBOARD_FAB2(SCH_1):TP_P3E_CPU1_PE2_RSR_TXN'<0>:
 C_SIGNAL='@baseboard_fab2_lib.baseboard_fab2(sch_1):tp_p3e_cpu1_pe2_rsr_txn(0)';
NODE_NAME     U2D1 CY3
 '@BASEBOARD_FAB2_LIB.BASEBOARD_FAB2(SCH_1):PAGE65_I68@CHPSET_LIB.SKX_EXT_B(CHIPS)':
 'PE2_TX_DN'<0>: CDS_PINID='PE2_TX_DN(0)';
NET_NAME
'TP_P3E_CPU1_PE2_RSR_TXN<10>'
 '@BASEBOARD_FAB2_LIB.BASEBOARD_FAB2(SCH_1):TP_P3E_CPU1_PE2_RSR_TXN'<10>:
 C_SIGNAL='@baseboard_fab2_lib.baseboard_fab2(sch_1):tp_p3e_cpu1_pe2_rsr_txn(10)~
';
NODE_NAME     U2D1 CA4
 '@BASEBOARD_FAB2_LIB.BASEBOARD_FAB2(SCH_1):PAGE65_I68@CHPSET_LIB.SKX_EXT_B(CHIPS)':
 'PE2_TX_DN'<10>: CDS_PINID='PE2_TX_DN(10)';
NET_NAME
'TP_P3E_CPU1_PE2_RSR_TXN<11>'
 '@BASEBOARD_FAB2_LIB.BASEBOARD_FAB2(SCH_1):TP_P3E_CPU1_PE2_RSR_TXN'<11>:
 C_SIGNAL='@baseboard_fab2_lib.baseboard_fab2(sch_1):tp_p3e_cpu1_pe2_rsr_txn(11)~
';
NODE_NAME     U2D1 BW4
 '@BASEBOARD_FAB2_LIB.BASEBOARD_FAB2(SCH_1):PAGE65_I68@CHPSET_LIB.SKX_EXT_B(CHIPS)':
 'PE2_TX_DN'<11>: CDS_PINID='PE2_TX_DN(11)';
NET_NAME
'TP_P3E_CPU1_PE2_RSR_TXN<12>'
 '@BASEBOARD_FAB2_LIB.BASEBOARD_FAB2(SCH_1):TP_P3E_CPU1_PE2_RSR_TXN'<12>:
 C_SIGNAL='@baseboard_fab2_lib.baseboard_fab2(sch_1):tp_p3e_cpu1_pe2_rsr_txn(12)~
';
NODE_NAME     U2D1 BU4
 '@BASEBOARD_FAB2_LIB.BASEBOARD_FAB2(SCH_1):PAGE65_I68@CHPSET_LIB.SKX_EXT_B(CHIPS)':
 'PE2_TX_DN'<12>: CDS_PINID='PE2_TX_DN(12)';
NET_NAME
'TP_P3E_CPU1_PE2_RSR_TXN<13>'
 '@BASEBOARD_FAB2_LIB.BASEBOARD_FAB2(SCH_1):TP_P3E_CPU1_PE2_RSR_TXN'<13>:
 C_SIGNAL='@baseboard_fab2_lib.baseboard_fab2(sch_1):tp_p3e_cpu1_pe2_rsr_txn(13)~
';
NODE_NAME     U2D1 BP5
 '@BASEBOARD_FAB2_LIB.BASEBOARD_FAB2(SCH_1):PAGE65_I68@CHPSET_LIB.SKX_EXT_B(CHIPS)':
 'PE2_TX_DN'<13>: CDS_PINID='PE2_TX_DN(13)';
NET_NAME
'TP_P3E_CPU1_PE2_RSR_TXN<14>'
 '@BASEBOARD_FAB2_LIB.BASEBOARD_FAB2(SCH_1):TP_P3E_CPU1_PE2_RSR_TXN'<14>:
 C_SIGNAL='@baseboard_fab2_lib.baseboard_fab2(sch_1):tp_p3e_cpu1_pe2_rsr_txn(14)~
';
NODE_NAME     U2D1 BL4
 '@BASEBOARD_FAB2_LIB.BASEBOARD_FAB2(SCH_1):PAGE65_I68@CHPSET_LIB.SKX_EXT_B(CHIPS)':
 'PE2_TX_DN'<14>: CDS_PINID='PE2_TX_DN(14)';
NET_NAME
'TP_P3E_CPU1_PE2_RSR_TXN<15>'
 '@BASEBOARD_FAB2_LIB.BASEBOARD_FAB2(SCH_1):TP_P3E_CPU1_PE2_RSR_TXN'<15>:
 C_SIGNAL='@baseboard_fab2_lib.baseboard_fab2(sch_1):tp_p3e_cpu1_pe2_rsr_txn(15)~
';
NODE_NAME     U2D1 BM5
 '@BASEBOARD_FAB2_LIB.BASEBOARD_FAB2(SCH_1):PAGE65_I68@CHPSET_LIB.SKX_EXT_B(CHIPS)':
 'PE2_TX_DN'<15>: CDS_PINID='PE2_TX_DN(15)';
NET_NAME
'TP_P3E_CPU1_PE2_RSR_TXN<1>'
 '@BASEBOARD_FAB2_LIB.BASEBOARD_FAB2(SCH_1):TP_P3E_CPU1_PE2_RSR_TXN'<1>:
 C_SIGNAL='@baseboard_fab2_lib.baseboard_fab2(sch_1):tp_p3e_cpu1_pe2_rsr_txn(1)';
NODE_NAME     U2D1 CV3
 '@BASEBOARD_FAB2_LIB.BASEBOARD_FAB2(SCH_1):PAGE65_I68@CHPSET_LIB.SKX_EXT_B(CHIPS)':
 'PE2_TX_DN'<1>: CDS_PINID='PE2_TX_DN(1)';
NET_NAME
'TP_P3E_CPU1_PE2_RSR_TXN<2>'
 '@BASEBOARD_FAB2_LIB.BASEBOARD_FAB2(SCH_1):TP_P3E_CPU1_PE2_RSR_TXN'<2>:
 C_SIGNAL='@baseboard_fab2_lib.baseboard_fab2(sch_1):tp_p3e_cpu1_pe2_rsr_txn(2)';
NODE_NAME     U2D1 CT1
 '@BASEBOARD_FAB2_LIB.BASEBOARD_FAB2(SCH_1):PAGE65_I68@CHPSET_LIB.SKX_EXT_B(CHIPS)':
 'PE2_TX_DN'<2>: CDS_PINID='PE2_TX_DN(2)';
NET_NAME
'TP_P3E_CPU1_PE2_RSR_TXN<3>'
 '@BASEBOARD_FAB2_LIB.BASEBOARD_FAB2(SCH_1):TP_P3E_CPU1_PE2_RSR_TXN'<3>:
 C_SIGNAL='@baseboard_fab2_lib.baseboard_fab2(sch_1):tp_p3e_cpu1_pe2_rsr_txn(3)';
NODE_NAME     U2D1 CT3
 '@BASEBOARD_FAB2_LIB.BASEBOARD_FAB2(SCH_1):PAGE65_I68@CHPSET_LIB.SKX_EXT_B(CHIPS)':
 'PE2_TX_DN'<3>: CDS_PINID='PE2_TX_DN(3)';
NET_NAME
'TP_P3E_CPU1_PE2_RSR_TXN<4>'
 '@BASEBOARD_FAB2_LIB.BASEBOARD_FAB2(SCH_1):TP_P3E_CPU1_PE2_RSR_TXN'<4>:
 C_SIGNAL='@baseboard_fab2_lib.baseboard_fab2(sch_1):tp_p3e_cpu1_pe2_rsr_txn(4)';
NODE_NAME     U2D1 CM1
 '@BASEBOARD_FAB2_LIB.BASEBOARD_FAB2(SCH_1):PAGE65_I68@CHPSET_LIB.SKX_EXT_B(CHIPS)':
 'PE2_TX_DN'<4>: CDS_PINID='PE2_TX_DN(4)';
NET_NAME
'TP_P3E_CPU1_PE2_RSR_TXN<5>'
 '@BASEBOARD_FAB2_LIB.BASEBOARD_FAB2(SCH_1):TP_P3E_CPU1_PE2_RSR_TXN'<5>:
 C_SIGNAL='@baseboard_fab2_lib.baseboard_fab2(sch_1):tp_p3e_cpu1_pe2_rsr_txn(5)';
NODE_NAME     U2D1 CL2
 '@BASEBOARD_FAB2_LIB.BASEBOARD_FAB2(SCH_1):PAGE65_I68@CHPSET_LIB.SKX_EXT_B(CHIPS)':
 'PE2_TX_DN'<5>: CDS_PINID='PE2_TX_DN(5)';
NET_NAME
'TP_P3E_CPU1_PE2_RSR_TXN<6>'
 '@BASEBOARD_FAB2_LIB.BASEBOARD_FAB2(SCH_1):TP_P3E_CPU1_PE2_RSR_TXN'<6>:
 C_SIGNAL='@baseboard_fab2_lib.baseboard_fab2(sch_1):tp_p3e_cpu1_pe2_rsr_txn(6)';
NODE_NAME     U2D1 CG2
 '@BASEBOARD_FAB2_LIB.BASEBOARD_FAB2(SCH_1):PAGE65_I68@CHPSET_LIB.SKX_EXT_B(CHIPS)':
 'PE2_TX_DN'<6>: CDS_PINID='PE2_TX_DN(6)';
NET_NAME
'TP_P3E_CPU1_PE2_RSR_TXN<7>'
 '@BASEBOARD_FAB2_LIB.BASEBOARD_FAB2(SCH_1):TP_P3E_CPU1_PE2_RSR_TXN'<7>:
 C_SIGNAL='@baseboard_fab2_lib.baseboard_fab2(sch_1):tp_p3e_cpu1_pe2_rsr_txn(7)';
NODE_NAME     U2D1 CF3
 '@BASEBOARD_FAB2_LIB.BASEBOARD_FAB2(SCH_1):PAGE65_I68@CHPSET_LIB.SKX_EXT_B(CHIPS)':
 'PE2_TX_DN'<7>: CDS_PINID='PE2_TX_DN(7)';
NET_NAME
'TP_P3E_CPU1_PE2_RSR_TXN<8>'
 '@BASEBOARD_FAB2_LIB.BASEBOARD_FAB2(SCH_1):TP_P3E_CPU1_PE2_RSR_TXN'<8>:
 C_SIGNAL='@baseboard_fab2_lib.baseboard_fab2(sch_1):tp_p3e_cpu1_pe2_rsr_txn(8)';
NODE_NAME     U2D1 CC2
 '@BASEBOARD_FAB2_LIB.BASEBOARD_FAB2(SCH_1):PAGE65_I68@CHPSET_LIB.SKX_EXT_B(CHIPS)':
 'PE2_TX_DN'<8>: CDS_PINID='PE2_TX_DN(8)';
NET_NAME
'TP_P3E_CPU1_PE2_RSR_TXN<9>'
 '@BASEBOARD_FAB2_LIB.BASEBOARD_FAB2(SCH_1):TP_P3E_CPU1_PE2_RSR_TXN'<9>:
 C_SIGNAL='@baseboard_fab2_lib.baseboard_fab2(sch_1):tp_p3e_cpu1_pe2_rsr_txn(9)';
NODE_NAME     U2D1 CB3
 '@BASEBOARD_FAB2_LIB.BASEBOARD_FAB2(SCH_1):PAGE65_I68@CHPSET_LIB.SKX_EXT_B(CHIPS)':
 'PE2_TX_DN'<9>: CDS_PINID='PE2_TX_DN(9)';
NET_NAME
'TP_P3E_CPU1_PE2_RSR_TXP<0>'
 '@BASEBOARD_FAB2_LIB.BASEBOARD_FAB2(SCH_1):TP_P3E_CPU1_PE2_RSR_TXP'<0>:
 C_SIGNAL='@baseboard_fab2_lib.baseboard_fab2(sch_1):tp_p3e_cpu1_pe2_rsr_txp(0)';
NODE_NAME     U2D1 CW4
 '@BASEBOARD_FAB2_LIB.BASEBOARD_FAB2(SCH_1):PAGE65_I68@CHPSET_LIB.SKX_EXT_B(CHIPS)':
 'PE2_TX_DP'<0>: CDS_PINID='PE2_TX_DP(0)';
NET_NAME
'TP_P3E_CPU1_PE2_RSR_TXP<10>'
 '@BASEBOARD_FAB2_LIB.BASEBOARD_FAB2(SCH_1):TP_P3E_CPU1_PE2_RSR_TXP'<10>:
 C_SIGNAL='@baseboard_fab2_lib.baseboard_fab2(sch_1):tp_p3e_cpu1_pe2_rsr_txp(10)~
';
NODE_NAME     U2D1 BY5
 '@BASEBOARD_FAB2_LIB.BASEBOARD_FAB2(SCH_1):PAGE65_I68@CHPSET_LIB.SKX_EXT_B(CHIPS)':
 'PE2_TX_DP'<10>: CDS_PINID='PE2_TX_DP(10)';
NET_NAME
'TP_P3E_CPU1_PE2_RSR_TXP<11>'
 '@BASEBOARD_FAB2_LIB.BASEBOARD_FAB2(SCH_1):TP_P3E_CPU1_PE2_RSR_TXP'<11>:
 C_SIGNAL='@baseboard_fab2_lib.baseboard_fab2(sch_1):tp_p3e_cpu1_pe2_rsr_txp(11)~
';
NODE_NAME     U2D1 BV3
 '@BASEBOARD_FAB2_LIB.BASEBOARD_FAB2(SCH_1):PAGE65_I68@CHPSET_LIB.SKX_EXT_B(CHIPS)':
 'PE2_TX_DP'<11>: CDS_PINID='PE2_TX_DP(11)';
NET_NAME
'TP_P3E_CPU1_PE2_RSR_TXP<12>'
 '@BASEBOARD_FAB2_LIB.BASEBOARD_FAB2(SCH_1):TP_P3E_CPU1_PE2_RSR_TXP'<12>:
 C_SIGNAL='@baseboard_fab2_lib.baseboard_fab2(sch_1):tp_p3e_cpu1_pe2_rsr_txp(12)~
';
NODE_NAME     U2D1 BR4
 '@BASEBOARD_FAB2_LIB.BASEBOARD_FAB2(SCH_1):PAGE65_I68@CHPSET_LIB.SKX_EXT_B(CHIPS)':
 'PE2_TX_DP'<12>: CDS_PINID='PE2_TX_DP(12)';
NET_NAME
'TP_P3E_CPU1_PE2_RSR_TXP<13>'
 '@BASEBOARD_FAB2_LIB.BASEBOARD_FAB2(SCH_1):TP_P3E_CPU1_PE2_RSR_TXP'<13>:
 C_SIGNAL='@baseboard_fab2_lib.baseboard_fab2(sch_1):tp_p3e_cpu1_pe2_rsr_txp(13)~
';
NODE_NAME     U2D1 BN4
 '@BASEBOARD_FAB2_LIB.BASEBOARD_FAB2(SCH_1):PAGE65_I68@CHPSET_LIB.SKX_EXT_B(CHIPS)':
 'PE2_TX_DP'<13>: CDS_PINID='PE2_TX_DP(13)';
NET_NAME
'TP_P3E_CPU1_PE2_RSR_TXP<14>'
 '@BASEBOARD_FAB2_LIB.BASEBOARD_FAB2(SCH_1):TP_P3E_CPU1_PE2_RSR_TXP'<14>:
 C_SIGNAL='@baseboard_fab2_lib.baseboard_fab2(sch_1):tp_p3e_cpu1_pe2_rsr_txp(14)~
';
NODE_NAME     U2D1 BM3
 '@BASEBOARD_FAB2_LIB.BASEBOARD_FAB2(SCH_1):PAGE65_I68@CHPSET_LIB.SKX_EXT_B(CHIPS)':
 'PE2_TX_DP'<14>: CDS_PINID='PE2_TX_DP(14)';
NET_NAME
'TP_P3E_CPU1_PE2_RSR_TXP<15>'
 '@BASEBOARD_FAB2_LIB.BASEBOARD_FAB2(SCH_1):TP_P3E_CPU1_PE2_RSR_TXP'<15>:
 C_SIGNAL='@baseboard_fab2_lib.baseboard_fab2(sch_1):tp_p3e_cpu1_pe2_rsr_txp(15)~
';
NODE_NAME     U2D1 BK5
 '@BASEBOARD_FAB2_LIB.BASEBOARD_FAB2(SCH_1):PAGE65_I68@CHPSET_LIB.SKX_EXT_B(CHIPS)':
 'PE2_TX_DP'<15>: CDS_PINID='PE2_TX_DP(15)';
NET_NAME
'TP_P3E_CPU1_PE2_RSR_TXP<1>'
 '@BASEBOARD_FAB2_LIB.BASEBOARD_FAB2(SCH_1):TP_P3E_CPU1_PE2_RSR_TXP'<1>:
 C_SIGNAL='@baseboard_fab2_lib.baseboard_fab2(sch_1):tp_p3e_cpu1_pe2_rsr_txp(1)';
NODE_NAME     U2D1 CU2
 '@BASEBOARD_FAB2_LIB.BASEBOARD_FAB2(SCH_1):PAGE65_I68@CHPSET_LIB.SKX_EXT_B(CHIPS)':
 'PE2_TX_DP'<1>: CDS_PINID='PE2_TX_DP(1)';
NET_NAME
'TP_P3E_CPU1_PE2_RSR_TXP<2>'
 '@BASEBOARD_FAB2_LIB.BASEBOARD_FAB2(SCH_1):TP_P3E_CPU1_PE2_RSR_TXP'<2>:
 C_SIGNAL='@baseboard_fab2_lib.baseboard_fab2(sch_1):tp_p3e_cpu1_pe2_rsr_txp(2)';
NODE_NAME     U2D1 CR2
 '@BASEBOARD_FAB2_LIB.BASEBOARD_FAB2(SCH_1):PAGE65_I68@CHPSET_LIB.SKX_EXT_B(CHIPS)':
 'PE2_TX_DP'<2>: CDS_PINID='PE2_TX_DP(2)';
NET_NAME
'TP_P3E_CPU1_PE2_RSR_TXP<3>'
 '@BASEBOARD_FAB2_LIB.BASEBOARD_FAB2(SCH_1):TP_P3E_CPU1_PE2_RSR_TXP'<3>:
 C_SIGNAL='@baseboard_fab2_lib.baseboard_fab2(sch_1):tp_p3e_cpu1_pe2_rsr_txp(3)';
NODE_NAME     U2D1 CP3
 '@BASEBOARD_FAB2_LIB.BASEBOARD_FAB2(SCH_1):PAGE65_I68@CHPSET_LIB.SKX_EXT_B(CHIPS)':
 'PE2_TX_DP'<3>: CDS_PINID='PE2_TX_DP(3)';
NET_NAME
'TP_P3E_CPU1_PE2_RSR_TXP<4>'
 '@BASEBOARD_FAB2_LIB.BASEBOARD_FAB2(SCH_1):TP_P3E_CPU1_PE2_RSR_TXP'<4>:
 C_SIGNAL='@baseboard_fab2_lib.baseboard_fab2(sch_1):tp_p3e_cpu1_pe2_rsr_txp(4)';
NODE_NAME     U2D1 CK1
 '@BASEBOARD_FAB2_LIB.BASEBOARD_FAB2(SCH_1):PAGE65_I68@CHPSET_LIB.SKX_EXT_B(CHIPS)':
 'PE2_TX_DP'<4>: CDS_PINID='PE2_TX_DP(4)';
NET_NAME
'TP_P3E_CPU1_PE2_RSR_TXP<5>'
 '@BASEBOARD_FAB2_LIB.BASEBOARD_FAB2(SCH_1):TP_P3E_CPU1_PE2_RSR_TXP'<5>:
 C_SIGNAL='@baseboard_fab2_lib.baseboard_fab2(sch_1):tp_p3e_cpu1_pe2_rsr_txp(5)';
NODE_NAME     U2D1 CK3
 '@BASEBOARD_FAB2_LIB.BASEBOARD_FAB2(SCH_1):PAGE65_I68@CHPSET_LIB.SKX_EXT_B(CHIPS)':
 'PE2_TX_DP'<5>: CDS_PINID='PE2_TX_DP(5)';
NET_NAME
'TP_P3E_CPU1_PE2_RSR_TXP<6>'
 '@BASEBOARD_FAB2_LIB.BASEBOARD_FAB2(SCH_1):TP_P3E_CPU1_PE2_RSR_TXP'<6>:
 C_SIGNAL='@baseboard_fab2_lib.baseboard_fab2(sch_1):tp_p3e_cpu1_pe2_rsr_txp(6)';
NODE_NAME     U2D1 CE2
 '@BASEBOARD_FAB2_LIB.BASEBOARD_FAB2(SCH_1):PAGE65_I68@CHPSET_LIB.SKX_EXT_B(CHIPS)':
 'PE2_TX_DP'<6>: CDS_PINID='PE2_TX_DP(6)';
NET_NAME
'TP_P3E_CPU1_PE2_RSR_TXP<7>'
 '@BASEBOARD_FAB2_LIB.BASEBOARD_FAB2(SCH_1):TP_P3E_CPU1_PE2_RSR_TXP'<7>:
 C_SIGNAL='@baseboard_fab2_lib.baseboard_fab2(sch_1):tp_p3e_cpu1_pe2_rsr_txp(7)';
NODE_NAME     U2D1 CE4
 '@BASEBOARD_FAB2_LIB.BASEBOARD_FAB2(SCH_1):PAGE65_I68@CHPSET_LIB.SKX_EXT_B(CHIPS)':
 'PE2_TX_DP'<7>: CDS_PINID='PE2_TX_DP(7)';
NET_NAME
'TP_P3E_CPU1_PE2_RSR_TXP<8>'
 '@BASEBOARD_FAB2_LIB.BASEBOARD_FAB2(SCH_1):TP_P3E_CPU1_PE2_RSR_TXP'<8>:
 C_SIGNAL='@baseboard_fab2_lib.baseboard_fab2(sch_1):tp_p3e_cpu1_pe2_rsr_txp(8)';
NODE_NAME     U2D1 CD3
 '@BASEBOARD_FAB2_LIB.BASEBOARD_FAB2(SCH_1):PAGE65_I68@CHPSET_LIB.SKX_EXT_B(CHIPS)':
 'PE2_TX_DP'<8>: CDS_PINID='PE2_TX_DP(8)';
NET_NAME
'TP_P3E_CPU1_PE2_RSR_TXP<9>'
 '@BASEBOARD_FAB2_LIB.BASEBOARD_FAB2(SCH_1):TP_P3E_CPU1_PE2_RSR_TXP'<9>:
 C_SIGNAL='@baseboard_fab2_lib.baseboard_fab2(sch_1):tp_p3e_cpu1_pe2_rsr_txp(9)';
NODE_NAME     U2D1 BY3
 '@BASEBOARD_FAB2_LIB.BASEBOARD_FAB2(SCH_1):PAGE65_I68@CHPSET_LIB.SKX_EXT_B(CHIPS)':
 'PE2_TX_DP'<9>: CDS_PINID='PE2_TX_DP(9)';
NET_NAME
'TP_PASSWORD_CLEAR'
 '@BASEBOARD_FAB2_LIB.BASEBOARD_FAB2(SCH_1):TP_PASSWORD_CLEAR':
 C_SIGNAL='@baseboard_fab2_lib.baseboard_fab2(sch_1):tp_password_clear';
NODE_NAME     J7G3 7
 '@BASEBOARD_FAB2_LIB.BASEBOARD_FAB2(SCH_1):PAGE136_I174@MSTR_CONN.CONN12_C73564003(CHIPS)':
 'IO7': CDS_PINID='IO7';
NET_NAME
'TP_PCH_DISPA_BCLK'
 '@BASEBOARD_FAB2_LIB.BASEBOARD_FAB2(SCH_1):TP_PCH_DISPA_BCLK':
 C_SIGNAL='@baseboard_fab2_lib.baseboard_fab2(sch_1):tp_pch_dispa_bclk';
NODE_NAME     U7C1 U20
 '@BASEBOARD_FAB2_LIB.BASEBOARD_FAB2(SCH_1):PAGE121_I34@MSTR_U_PROC.LBG_CORE_QAT_EXT_D(CHIPS)':
 'RSVD'<66>: CDS_PINID='RSVD(66)';
NET_NAME
'TP_PCH_DISPA_SDI'
 '@BASEBOARD_FAB2_LIB.BASEBOARD_FAB2(SCH_1):TP_PCH_DISPA_SDI':
 C_SIGNAL='@baseboard_fab2_lib.baseboard_fab2(sch_1):tp_pch_dispa_sdi';
NODE_NAME     U7C1 R20
 '@BASEBOARD_FAB2_LIB.BASEBOARD_FAB2(SCH_1):PAGE121_I34@MSTR_U_PROC.LBG_CORE_QAT_EXT_D(CHIPS)':
 'RSVD'<67>: CDS_PINID='RSVD(67)';
NET_NAME
'TP_PCH_DISPA_SDO'
 '@BASEBOARD_FAB2_LIB.BASEBOARD_FAB2(SCH_1):TP_PCH_DISPA_SDO':
 C_SIGNAL='@baseboard_fab2_lib.baseboard_fab2(sch_1):tp_pch_dispa_sdo';
NODE_NAME     U7C1 V22
 '@BASEBOARD_FAB2_LIB.BASEBOARD_FAB2(SCH_1):PAGE121_I34@MSTR_U_PROC.LBG_CORE_QAT_EXT_D(CHIPS)':
 'RSVD'<68>: CDS_PINID='RSVD(68)';
NET_NAME
'TP_PCH_GDP8_SUSCLK'
 '@BASEBOARD_FAB2_LIB.BASEBOARD_FAB2(SCH_1):TP_PCH_GDP8_SUSCLK':
 C_SIGNAL='@baseboard_fab2_lib.baseboard_fab2(sch_1):tp_pch_gdp8_susclk';
NODE_NAME     U7C1 C13
 '@BASEBOARD_FAB2_LIB.BASEBOARD_FAB2(SCH_1):PAGE118_I73@MSTR_U_PROC.LBG_CORE_QAT_EXT_D(CHIPS)':
 'GPD8_SUSCLK': CDS_PINID='GPD8_SUSCLK';
NET_NAME
'TP_PCH_GPP_J17'
 '@BASEBOARD_FAB2_LIB.BASEBOARD_FAB2(SCH_1):TP_PCH_GPP_J17':
 C_SIGNAL='@baseboard_fab2_lib.baseboard_fab2(sch_1):tp_pch_gpp_j17';
NODE_NAME     U7C1 CA11
 '@BASEBOARD_FAB2_LIB.BASEBOARD_FAB2(SCH_1):PAGE120_I147@MSTR_U_PROC.LBG_CORE_QAT_EXT_D(CHIPS)':
 'GPP_J17_LAN_SDP_P0_1': CDS_PINID='GPP_J17_LAN_SDP_P0_1';
NET_NAME
'TP_PCH_GPP_J19'
 '@BASEBOARD_FAB2_LIB.BASEBOARD_FAB2(SCH_1):TP_PCH_GPP_J19':
 C_SIGNAL='@baseboard_fab2_lib.baseboard_fab2(sch_1):tp_pch_gpp_j19';
NODE_NAME     U7C1 BY14
 '@BASEBOARD_FAB2_LIB.BASEBOARD_FAB2(SCH_1):PAGE120_I147@MSTR_U_PROC.LBG_CORE_QAT_EXT_D(CHIPS)':
 'GPP_J19_LAN_SDP_P1_1': CDS_PINID='GPP_J19_LAN_SDP_P1_1';
NET_NAME
'TP_PCH_GPP_J21'
 '@BASEBOARD_FAB2_LIB.BASEBOARD_FAB2(SCH_1):TP_PCH_GPP_J21':
 C_SIGNAL='@baseboard_fab2_lib.baseboard_fab2(sch_1):tp_pch_gpp_j21';
NODE_NAME     U7C1 BV12
 '@BASEBOARD_FAB2_LIB.BASEBOARD_FAB2(SCH_1):PAGE120_I147@MSTR_U_PROC.LBG_CORE_QAT_EXT_D(CHIPS)':
 'GPP_J21_LAN_SDP_P2_1': CDS_PINID='GPP_J21_LAN_SDP_P2_1';
NET_NAME
'TP_PCH_GPP_J23'
 '@BASEBOARD_FAB2_LIB.BASEBOARD_FAB2(SCH_1):TP_PCH_GPP_J23':
 C_SIGNAL='@baseboard_fab2_lib.baseboard_fab2(sch_1):tp_pch_gpp_j23';
NODE_NAME     U7C1 BV14
 '@BASEBOARD_FAB2_LIB.BASEBOARD_FAB2(SCH_1):PAGE120_I147@MSTR_U_PROC.LBG_CORE_QAT_EXT_D(CHIPS)':
 'GPP_J23_LAN_SDP_P3_1': CDS_PINID='GPP_J23_LAN_SDP_P3_1';
NET_NAME
'TP_PCH_GPP_L10'
 '@BASEBOARD_FAB2_LIB.BASEBOARD_FAB2(SCH_1):TP_PCH_GPP_L10':
 C_SIGNAL='@baseboard_fab2_lib.baseboard_fab2(sch_1):tp_pch_gpp_l10';
NODE_NAME     U7C1 AF20
 '@BASEBOARD_FAB2_LIB.BASEBOARD_FAB2(SCH_1):PAGE121_I34@MSTR_U_PROC.LBG_CORE_QAT_EXT_D(CHIPS)':
 'GPP_L10_TESTCH0_CLK': CDS_PINID='GPP_L10_TESTCH0_CLK';
NET_NAME
'TP_PCH_GPP_L11'
 '@BASEBOARD_FAB2_LIB.BASEBOARD_FAB2(SCH_1):TP_PCH_GPP_L11':
 C_SIGNAL='@baseboard_fab2_lib.baseboard_fab2(sch_1):tp_pch_gpp_l11';
NODE_NAME     U7C1 AD20
 '@BASEBOARD_FAB2_LIB.BASEBOARD_FAB2(SCH_1):PAGE121_I34@MSTR_U_PROC.LBG_CORE_QAT_EXT_D(CHIPS)':
 'GPP_L11_TESTCH1_D0': CDS_PINID='GPP_L11_TESTCH1_D0';
NET_NAME
'TP_PCH_HDA_BCLK'
 '@BASEBOARD_FAB2_LIB.BASEBOARD_FAB2(SCH_1):TP_PCH_HDA_BCLK':
 C_SIGNAL='@baseboard_fab2_lib.baseboard_fab2(sch_1):tp_pch_hda_bclk';
NODE_NAME     U7C1 P18
 '@BASEBOARD_FAB2_LIB.BASEBOARD_FAB2(SCH_1):PAGE121_I34@MSTR_U_PROC.LBG_CORE_QAT_EXT_D(CHIPS)':
 'HDA_BCLK': CDS_PINID='HDA_BCLK';
NET_NAME
'TP_PCH_HDA_SDI_0'
 '@BASEBOARD_FAB2_LIB.BASEBOARD_FAB2(SCH_1):TP_PCH_HDA_SDI_0':
 C_SIGNAL='@baseboard_fab2_lib.baseboard_fab2(sch_1):tp_pch_hda_sdi_0';
NODE_NAME     U7C1 K20
 '@BASEBOARD_FAB2_LIB.BASEBOARD_FAB2(SCH_1):PAGE121_I34@MSTR_U_PROC.LBG_CORE_QAT_EXT_D(CHIPS)':
 'HDA_SDI_0': CDS_PINID='HDA_SDI_0';
NET_NAME
'TP_PCH_HDA_SDI_1'
 '@BASEBOARD_FAB2_LIB.BASEBOARD_FAB2(SCH_1):TP_PCH_HDA_SDI_1':
 C_SIGNAL='@baseboard_fab2_lib.baseboard_fab2(sch_1):tp_pch_hda_sdi_1';
NODE_NAME     U7C1 V18
 '@BASEBOARD_FAB2_LIB.BASEBOARD_FAB2(SCH_1):PAGE121_I34@MSTR_U_PROC.LBG_CORE_QAT_EXT_D(CHIPS)':
 'HDA_SDI_1': CDS_PINID='HDA_SDI_1';
NET_NAME
'TP_PCH_HDA_SYNC'
 '@BASEBOARD_FAB2_LIB.BASEBOARD_FAB2(SCH_1):TP_PCH_HDA_SYNC':
 C_SIGNAL='@baseboard_fab2_lib.baseboard_fab2(sch_1):tp_pch_hda_sync';
NODE_NAME     U7C1 H20
 '@BASEBOARD_FAB2_LIB.BASEBOARD_FAB2(SCH_1):PAGE121_I34@MSTR_U_PROC.LBG_CORE_QAT_EXT_D(CHIPS)':
 'HDA_SYNC': CDS_PINID='HDA_SYNC';
NET_NAME
'TP_PCH_HSA_RST_N'
 '@BASEBOARD_FAB2_LIB.BASEBOARD_FAB2(SCH_1):TP_PCH_HSA_RST_N':
 C_SIGNAL='@baseboard_fab2_lib.baseboard_fab2(sch_1):tp_pch_hsa_rst_n';
NODE_NAME     U7C1 M18
 '@BASEBOARD_FAB2_LIB.BASEBOARD_FAB2(SCH_1):PAGE121_I34@MSTR_U_PROC.LBG_CORE_QAT_EXT_D(CHIPS)':
 'HDA_RST_N': CDS_PINID='HDA_RST_N';
NET_NAME
'TP_PCH_RSVD0'
 '@BASEBOARD_FAB2_LIB.BASEBOARD_FAB2(SCH_1):TP_PCH_RSVD0':
 C_SIGNAL='@baseboard_fab2_lib.baseboard_fab2(sch_1):tp_pch_rsvd0';
NODE_NAME     U7C1 AF61
 '@BASEBOARD_FAB2_LIB.BASEBOARD_FAB2(SCH_1):PAGE121_I34@MSTR_U_PROC.LBG_CORE_QAT_EXT_D(CHIPS)':
 'RSVD'<0>: CDS_PINID='RSVD(0)';
NET_NAME
'TP_PCH_RSVD1'
 '@BASEBOARD_FAB2_LIB.BASEBOARD_FAB2(SCH_1):TP_PCH_RSVD1':
 C_SIGNAL='@baseboard_fab2_lib.baseboard_fab2(sch_1):tp_pch_rsvd1';
NODE_NAME     U7C1 AC56
 '@BASEBOARD_FAB2_LIB.BASEBOARD_FAB2(SCH_1):PAGE121_I34@MSTR_U_PROC.LBG_CORE_QAT_EXT_D(CHIPS)':
 'RSVD'<1>: CDS_PINID='RSVD(1)';
NET_NAME
'TP_PCH_RSVD12'
 '@BASEBOARD_FAB2_LIB.BASEBOARD_FAB2(SCH_1):TP_PCH_RSVD12':
 C_SIGNAL='@baseboard_fab2_lib.baseboard_fab2(sch_1):tp_pch_rsvd12';
NODE_NAME     U7C1 C68
 '@BASEBOARD_FAB2_LIB.BASEBOARD_FAB2(SCH_1):PAGE121_I34@MSTR_U_PROC.LBG_CORE_QAT_EXT_D(CHIPS)':
 'RSVD'<12>: CDS_PINID='RSVD(12)';
NET_NAME
'TP_PCH_RSVD13'
 '@BASEBOARD_FAB2_LIB.BASEBOARD_FAB2(SCH_1):TP_PCH_RSVD13':
 C_SIGNAL='@baseboard_fab2_lib.baseboard_fab2(sch_1):tp_pch_rsvd13';
NODE_NAME     U7C1 C67
 '@BASEBOARD_FAB2_LIB.BASEBOARD_FAB2(SCH_1):PAGE121_I34@MSTR_U_PROC.LBG_CORE_QAT_EXT_D(CHIPS)':
 'RSVD'<13>: CDS_PINID='RSVD(13)';
NET_NAME
'TP_PCH_RSVD14'
 '@BASEBOARD_FAB2_LIB.BASEBOARD_FAB2(SCH_1):TP_PCH_RSVD14':
 C_SIGNAL='@baseboard_fab2_lib.baseboard_fab2(sch_1):tp_pch_rsvd14';
NODE_NAME     U7C1 E18
 '@BASEBOARD_FAB2_LIB.BASEBOARD_FAB2(SCH_1):PAGE121_I34@MSTR_U_PROC.LBG_CORE_QAT_EXT_D(CHIPS)':
 'RSVD'<14>: CDS_PINID='RSVD(14)';
NET_NAME
'TP_PCH_RSVD15'
 '@BASEBOARD_FAB2_LIB.BASEBOARD_FAB2(SCH_1):TP_PCH_RSVD15':
 C_SIGNAL='@baseboard_fab2_lib.baseboard_fab2(sch_1):tp_pch_rsvd15';
NODE_NAME     U7C1 C6
 '@BASEBOARD_FAB2_LIB.BASEBOARD_FAB2(SCH_1):PAGE121_I34@MSTR_U_PROC.LBG_CORE_QAT_EXT_D(CHIPS)':
 'RSVD'<15>: CDS_PINID='RSVD(15)';
NET_NAME
'TP_PCH_RSVD16'
 '@BASEBOARD_FAB2_LIB.BASEBOARD_FAB2(SCH_1):TP_PCH_RSVD16':
 C_SIGNAL='@baseboard_fab2_lib.baseboard_fab2(sch_1):tp_pch_rsvd16';
NODE_NAME     U7C1 C5
 '@BASEBOARD_FAB2_LIB.BASEBOARD_FAB2(SCH_1):PAGE121_I34@MSTR_U_PROC.LBG_CORE_QAT_EXT_D(CHIPS)':
 'RSVD'<16>: CDS_PINID='RSVD(16)';
NET_NAME
'TP_PCH_RSVD17'
 '@BASEBOARD_FAB2_LIB.BASEBOARD_FAB2(SCH_1):TP_PCH_RSVD17':
 C_SIGNAL='@baseboard_fab2_lib.baseboard_fab2(sch_1):tp_pch_rsvd17';
NODE_NAME     U7C1 B10
 '@BASEBOARD_FAB2_LIB.BASEBOARD_FAB2(SCH_1):PAGE121_I34@MSTR_U_PROC.LBG_CORE_QAT_EXT_D(CHIPS)':
 'RSVD'<17>: CDS_PINID='RSVD(17)';
NET_NAME
'TP_PCH_RSVD18'
 '@BASEBOARD_FAB2_LIB.BASEBOARD_FAB2(SCH_1):TP_PCH_RSVD18':
 C_SIGNAL='@baseboard_fab2_lib.baseboard_fab2(sch_1):tp_pch_rsvd18';
NODE_NAME     U7C1 C11
 '@BASEBOARD_FAB2_LIB.BASEBOARD_FAB2(SCH_1):PAGE121_I34@MSTR_U_PROC.LBG_CORE_QAT_EXT_D(CHIPS)':
 'RSVD'<18>: CDS_PINID='RSVD(18)';
NET_NAME
'TP_PCH_RSVD19'
 '@BASEBOARD_FAB2_LIB.BASEBOARD_FAB2(SCH_1):TP_PCH_RSVD19':
 C_SIGNAL='@baseboard_fab2_lib.baseboard_fab2(sch_1):tp_pch_rsvd19';
NODE_NAME     U7C1 C9
 '@BASEBOARD_FAB2_LIB.BASEBOARD_FAB2(SCH_1):PAGE121_I34@MSTR_U_PROC.LBG_CORE_QAT_EXT_D(CHIPS)':
 'RSVD'<19>: CDS_PINID='RSVD(19)';
NET_NAME
'TP_PCH_RSVD2'
 '@BASEBOARD_FAB2_LIB.BASEBOARD_FAB2(SCH_1):TP_PCH_RSVD2':
 C_SIGNAL='@baseboard_fab2_lib.baseboard_fab2(sch_1):tp_pch_rsvd2';
NODE_NAME     U7C1 AA58
 '@BASEBOARD_FAB2_LIB.BASEBOARD_FAB2(SCH_1):PAGE121_I34@MSTR_U_PROC.LBG_CORE_QAT_EXT_D(CHIPS)':
 'RSVD'<2>: CDS_PINID='RSVD(2)';
NET_NAME
'TP_PCH_RSVD20'
 '@BASEBOARD_FAB2_LIB.BASEBOARD_FAB2(SCH_1):TP_PCH_RSVD20':
 C_SIGNAL='@baseboard_fab2_lib.baseboard_fab2(sch_1):tp_pch_rsvd20';
NODE_NAME     U7C1 D10
 '@BASEBOARD_FAB2_LIB.BASEBOARD_FAB2(SCH_1):PAGE121_I34@MSTR_U_PROC.LBG_CORE_QAT_EXT_D(CHIPS)':
 'RSVD'<20>: CDS_PINID='RSVD(20)';
NET_NAME
'TP_PCH_RSVD21'
 '@BASEBOARD_FAB2_LIB.BASEBOARD_FAB2(SCH_1):TP_PCH_RSVD21':
 C_SIGNAL='@baseboard_fab2_lib.baseboard_fab2(sch_1):tp_pch_rsvd21';
NODE_NAME     U7C1 A11
 '@BASEBOARD_FAB2_LIB.BASEBOARD_FAB2(SCH_1):PAGE121_I34@MSTR_U_PROC.LBG_CORE_QAT_EXT_D(CHIPS)':
 'RSVD'<21>: CDS_PINID='RSVD(21)';
NET_NAME
'TP_PCH_RSVD22'
 '@BASEBOARD_FAB2_LIB.BASEBOARD_FAB2(SCH_1):TP_PCH_RSVD22':
 C_SIGNAL='@baseboard_fab2_lib.baseboard_fab2(sch_1):tp_pch_rsvd22';
NODE_NAME     U7C1 AT71
 '@BASEBOARD_FAB2_LIB.BASEBOARD_FAB2(SCH_1):PAGE121_I34@MSTR_U_PROC.LBG_CORE_QAT_EXT_D(CHIPS)':
 'RSVD'<22>: CDS_PINID='RSVD(22)';
NET_NAME
'TP_PCH_RSVD23'
 '@BASEBOARD_FAB2_LIB.BASEBOARD_FAB2(SCH_1):TP_PCH_RSVD23':
 C_SIGNAL='@baseboard_fab2_lib.baseboard_fab2(sch_1):tp_pch_rsvd23';
NODE_NAME     U7C1 P40
 '@BASEBOARD_FAB2_LIB.BASEBOARD_FAB2(SCH_1):PAGE121_I34@MSTR_U_PROC.LBG_CORE_QAT_EXT_D(CHIPS)':
 'RSVD'<23>: CDS_PINID='RSVD(23)';
NET_NAME
'TP_PCH_RSVD24'
 '@BASEBOARD_FAB2_LIB.BASEBOARD_FAB2(SCH_1):TP_PCH_RSVD24':
 C_SIGNAL='@baseboard_fab2_lib.baseboard_fab2(sch_1):tp_pch_rsvd24';
NODE_NAME     U7C1 P44
 '@BASEBOARD_FAB2_LIB.BASEBOARD_FAB2(SCH_1):PAGE121_I34@MSTR_U_PROC.LBG_CORE_QAT_EXT_D(CHIPS)':
 'RSVD'<24>: CDS_PINID='RSVD(24)';
NET_NAME
'TP_PCH_RSVD25'
 '@BASEBOARD_FAB2_LIB.BASEBOARD_FAB2(SCH_1):TP_PCH_RSVD25':
 C_SIGNAL='@baseboard_fab2_lib.baseboard_fab2(sch_1):tp_pch_rsvd25';
NODE_NAME     U7C1 P48
 '@BASEBOARD_FAB2_LIB.BASEBOARD_FAB2(SCH_1):PAGE121_I34@MSTR_U_PROC.LBG_CORE_QAT_EXT_D(CHIPS)':
 'RSVD'<25>: CDS_PINID='RSVD(25)';
NET_NAME
'TP_PCH_RSVD26'
 '@BASEBOARD_FAB2_LIB.BASEBOARD_FAB2(SCH_1):TP_PCH_RSVD26':
 C_SIGNAL='@baseboard_fab2_lib.baseboard_fab2(sch_1):tp_pch_rsvd26';
NODE_NAME     U7C1 BH24
 '@BASEBOARD_FAB2_LIB.BASEBOARD_FAB2(SCH_1):PAGE121_I34@MSTR_U_PROC.LBG_CORE_QAT_EXT_D(CHIPS)':
 'RSVD'<26>: CDS_PINID='RSVD(26)';
NET_NAME
'TP_PCH_RSVD27'
 '@BASEBOARD_FAB2_LIB.BASEBOARD_FAB2(SCH_1):TP_PCH_RSVD27':
 C_SIGNAL='@baseboard_fab2_lib.baseboard_fab2(sch_1):tp_pch_rsvd27';
NODE_NAME     U7C1 BG26
 '@BASEBOARD_FAB2_LIB.BASEBOARD_FAB2(SCH_1):PAGE121_I34@MSTR_U_PROC.LBG_CORE_QAT_EXT_D(CHIPS)':
 'RSVD'<27>: CDS_PINID='RSVD(27)';
NET_NAME
'TP_PCH_RSVD28'
 '@BASEBOARD_FAB2_LIB.BASEBOARD_FAB2(SCH_1):TP_PCH_RSVD28':
 C_SIGNAL='@baseboard_fab2_lib.baseboard_fab2(sch_1):tp_pch_rsvd28';
NODE_NAME     U7C1 R35
 '@BASEBOARD_FAB2_LIB.BASEBOARD_FAB2(SCH_1):PAGE122_I63@MSTR_U_PROC.LBG_CORE_QAT_EXT_D(CHIPS)':
 'RSVD'<28>: CDS_PINID='RSVD(28)';
NET_NAME
'TP_PCH_RSVD29'
 '@BASEBOARD_FAB2_LIB.BASEBOARD_FAB2(SCH_1):TP_PCH_RSVD29':
 C_SIGNAL='@baseboard_fab2_lib.baseboard_fab2(sch_1):tp_pch_rsvd29';
NODE_NAME     U7C1 P33
 '@BASEBOARD_FAB2_LIB.BASEBOARD_FAB2(SCH_1):PAGE122_I63@MSTR_U_PROC.LBG_CORE_QAT_EXT_D(CHIPS)':
 'RSVD'<29>: CDS_PINID='RSVD(29)';
NET_NAME
'TP_PCH_RSVD3'
 '@BASEBOARD_FAB2_LIB.BASEBOARD_FAB2(SCH_1):TP_PCH_RSVD3':
 C_SIGNAL='@baseboard_fab2_lib.baseboard_fab2(sch_1):tp_pch_rsvd3';
NODE_NAME     U7C1 V11
 '@BASEBOARD_FAB2_LIB.BASEBOARD_FAB2(SCH_1):PAGE121_I34@MSTR_U_PROC.LBG_CORE_QAT_EXT_D(CHIPS)':
 'RSVD'<3>: CDS_PINID='RSVD(3)';
NET_NAME
'TP_PCH_RSVD30'
 '@BASEBOARD_FAB2_LIB.BASEBOARD_FAB2(SCH_1):TP_PCH_RSVD30':
 C_SIGNAL='@baseboard_fab2_lib.baseboard_fab2(sch_1):tp_pch_rsvd30';
NODE_NAME     U7C1 R31
 '@BASEBOARD_FAB2_LIB.BASEBOARD_FAB2(SCH_1):PAGE122_I63@MSTR_U_PROC.LBG_CORE_QAT_EXT_D(CHIPS)':
 'RSVD'<30>: CDS_PINID='RSVD(30)';
NET_NAME
'TP_PCH_RSVD31'
 '@BASEBOARD_FAB2_LIB.BASEBOARD_FAB2(SCH_1):TP_PCH_RSVD31':
 C_SIGNAL='@baseboard_fab2_lib.baseboard_fab2(sch_1):tp_pch_rsvd31';
NODE_NAME     U7C1 P29
 '@BASEBOARD_FAB2_LIB.BASEBOARD_FAB2(SCH_1):PAGE122_I63@MSTR_U_PROC.LBG_CORE_QAT_EXT_D(CHIPS)':
 'RSVD'<31>: CDS_PINID='RSVD(31)';
NET_NAME
'TP_PCH_RSVD32'
 '@BASEBOARD_FAB2_LIB.BASEBOARD_FAB2(SCH_1):TP_PCH_RSVD32':
 C_SIGNAL='@baseboard_fab2_lib.baseboard_fab2(sch_1):tp_pch_rsvd32';
NODE_NAME     U7C1 AA54
 '@BASEBOARD_FAB2_LIB.BASEBOARD_FAB2(SCH_1):PAGE118_I73@MSTR_U_PROC.LBG_CORE_QAT_EXT_D(CHIPS)':
 'RSVD'<32>: CDS_PINID='RSVD(32)';
NET_NAME
'TP_PCH_RSVD33'
 '@BASEBOARD_FAB2_LIB.BASEBOARD_FAB2(SCH_1):TP_PCH_RSVD33':
 C_SIGNAL='@baseboard_fab2_lib.baseboard_fab2(sch_1):tp_pch_rsvd33';
NODE_NAME     U7C1 V56
 '@BASEBOARD_FAB2_LIB.BASEBOARD_FAB2(SCH_1):PAGE118_I73@MSTR_U_PROC.LBG_CORE_QAT_EXT_D(CHIPS)':
 'RSVD'<33>: CDS_PINID='RSVD(33)';
NET_NAME
'TP_PCH_RSVD34'
 '@BASEBOARD_FAB2_LIB.BASEBOARD_FAB2(SCH_1):TP_PCH_RSVD34':
 C_SIGNAL='@baseboard_fab2_lib.baseboard_fab2(sch_1):tp_pch_rsvd34';
NODE_NAME     U7C1 Y56
 '@BASEBOARD_FAB2_LIB.BASEBOARD_FAB2(SCH_1):PAGE118_I73@MSTR_U_PROC.LBG_CORE_QAT_EXT_D(CHIPS)':
 'RSVD'<34>: CDS_PINID='RSVD(34)';
NET_NAME
'TP_PCH_RSVD35'
 '@BASEBOARD_FAB2_LIB.BASEBOARD_FAB2(SCH_1):TP_PCH_RSVD35':
 C_SIGNAL='@baseboard_fab2_lib.baseboard_fab2(sch_1):tp_pch_rsvd35';
NODE_NAME     U7C1 W54
 '@BASEBOARD_FAB2_LIB.BASEBOARD_FAB2(SCH_1):PAGE118_I73@MSTR_U_PROC.LBG_CORE_QAT_EXT_D(CHIPS)':
 'RSVD'<35>: CDS_PINID='RSVD(35)';
NET_NAME
'TP_PCH_RSVD36'
 '@BASEBOARD_FAB2_LIB.BASEBOARD_FAB2(SCH_1):TP_PCH_RSVD36':
 C_SIGNAL='@baseboard_fab2_lib.baseboard_fab2(sch_1):tp_pch_rsvd36';
NODE_NAME     U7C1 AK54
 '@BASEBOARD_FAB2_LIB.BASEBOARD_FAB2(SCH_1):PAGE118_I73@MSTR_U_PROC.LBG_CORE_QAT_EXT_D(CHIPS)':
 'RSVD'<36>: CDS_PINID='RSVD(36)';
NET_NAME
'TP_PCH_RSVD37'
 '@BASEBOARD_FAB2_LIB.BASEBOARD_FAB2(SCH_1):TP_PCH_RSVD37':
 C_SIGNAL='@baseboard_fab2_lib.baseboard_fab2(sch_1):tp_pch_rsvd37';
NODE_NAME     U7C1 BN29
 '@BASEBOARD_FAB2_LIB.BASEBOARD_FAB2(SCH_1):PAGE118_I73@MSTR_U_PROC.LBG_CORE_QAT_EXT_D(CHIPS)':
 'RSVD'<37>: CDS_PINID='RSVD(37)';
NET_NAME
'TP_PCH_RSVD38'
 '@BASEBOARD_FAB2_LIB.BASEBOARD_FAB2(SCH_1):TP_PCH_RSVD38':
 C_SIGNAL='@baseboard_fab2_lib.baseboard_fab2(sch_1):tp_pch_rsvd38';
NODE_NAME     U7C1 BL29
 '@BASEBOARD_FAB2_LIB.BASEBOARD_FAB2(SCH_1):PAGE118_I73@MSTR_U_PROC.LBG_CORE_QAT_EXT_D(CHIPS)':
 'RSVD'<38>: CDS_PINID='RSVD(38)';
NET_NAME
'TP_PCH_RSVD4'
 '@BASEBOARD_FAB2_LIB.BASEBOARD_FAB2(SCH_1):TP_PCH_RSVD4':
 C_SIGNAL='@baseboard_fab2_lib.baseboard_fab2(sch_1):tp_pch_rsvd4';
NODE_NAME     U7C1 P37
 '@BASEBOARD_FAB2_LIB.BASEBOARD_FAB2(SCH_1):PAGE121_I34@MSTR_U_PROC.LBG_CORE_QAT_EXT_D(CHIPS)':
 'RSVD'<4>: CDS_PINID='RSVD(4)';
NET_NAME
'TP_PCH_RSVD41'
 '@BASEBOARD_FAB2_LIB.BASEBOARD_FAB2(SCH_1):TP_PCH_RSVD41':
 C_SIGNAL='@baseboard_fab2_lib.baseboard_fab2(sch_1):tp_pch_rsvd41';
NODE_NAME     U7C1 BJ40
 '@BASEBOARD_FAB2_LIB.BASEBOARD_FAB2(SCH_1):PAGE118_I73@MSTR_U_PROC.LBG_CORE_QAT_EXT_D(CHIPS)':
 'RSVD'<41>: CDS_PINID='RSVD(41)';
NET_NAME
'TP_PCH_RSVD42'
 '@BASEBOARD_FAB2_LIB.BASEBOARD_FAB2(SCH_1):TP_PCH_RSVD42':
 C_SIGNAL='@baseboard_fab2_lib.baseboard_fab2(sch_1):tp_pch_rsvd42';
NODE_NAME     U7C1 BG40
 '@BASEBOARD_FAB2_LIB.BASEBOARD_FAB2(SCH_1):PAGE118_I73@MSTR_U_PROC.LBG_CORE_QAT_EXT_D(CHIPS)':
 'RSVD'<42>: CDS_PINID='RSVD(42)';
NET_NAME
'TP_PCH_RSVD45'
 '@BASEBOARD_FAB2_LIB.BASEBOARD_FAB2(SCH_1):TP_PCH_RSVD45':
 C_SIGNAL='@baseboard_fab2_lib.baseboard_fab2(sch_1):tp_pch_rsvd45';
NODE_NAME     U7C1 P22
 '@BASEBOARD_FAB2_LIB.BASEBOARD_FAB2(SCH_1):PAGE118_I73@MSTR_U_PROC.LBG_CORE_QAT_EXT_D(CHIPS)':
 'RSVD'<45>: CDS_PINID='RSVD(45)';
NET_NAME
'TP_PCH_RSVD46'
 '@BASEBOARD_FAB2_LIB.BASEBOARD_FAB2(SCH_1):TP_PCH_RSVD46':
 C_SIGNAL='@baseboard_fab2_lib.baseboard_fab2(sch_1):tp_pch_rsvd46';
NODE_NAME     U7C1 BW3
 '@BASEBOARD_FAB2_LIB.BASEBOARD_FAB2(SCH_1):PAGE121_I34@MSTR_U_PROC.LBG_CORE_QAT_EXT_D(CHIPS)':
 'RSVD'<46>: CDS_PINID='RSVD(46)';
NET_NAME
'TP_PCH_RSVD47'
 '@BASEBOARD_FAB2_LIB.BASEBOARD_FAB2(SCH_1):TP_PCH_RSVD47':
 C_SIGNAL='@baseboard_fab2_lib.baseboard_fab2(sch_1):tp_pch_rsvd47';
NODE_NAME     U7C1 AP69
 '@BASEBOARD_FAB2_LIB.BASEBOARD_FAB2(SCH_1):PAGE116_I220@MSTR_U_PROC.LBG_CORE_QAT_EXT_D(CHIPS)':
 'RSVD'<47>: CDS_PINID='RSVD(47)';
NET_NAME
'TP_PCH_RSVD48'
 '@BASEBOARD_FAB2_LIB.BASEBOARD_FAB2(SCH_1):TP_PCH_RSVD48':
 C_SIGNAL='@baseboard_fab2_lib.baseboard_fab2(sch_1):tp_pch_rsvd48';
NODE_NAME     U7C1 AP71
 '@BASEBOARD_FAB2_LIB.BASEBOARD_FAB2(SCH_1):PAGE116_I220@MSTR_U_PROC.LBG_CORE_QAT_EXT_D(CHIPS)':
 'RSVD'<48>: CDS_PINID='RSVD(48)';
NET_NAME
'TP_PCH_RSVD49'
 '@BASEBOARD_FAB2_LIB.BASEBOARD_FAB2(SCH_1):TP_PCH_RSVD49':
 C_SIGNAL='@baseboard_fab2_lib.baseboard_fab2(sch_1):tp_pch_rsvd49';
NODE_NAME     U7C1 G67
 '@BASEBOARD_FAB2_LIB.BASEBOARD_FAB2(SCH_1):PAGE116_I220@MSTR_U_PROC.LBG_CORE_QAT_EXT_D(CHIPS)':
 'RSVD'<49>: CDS_PINID='RSVD(49)';
NET_NAME
'TP_PCH_RSVD5'
 '@BASEBOARD_FAB2_LIB.BASEBOARD_FAB2(SCH_1):TP_PCH_RSVD5':
 C_SIGNAL='@baseboard_fab2_lib.baseboard_fab2(sch_1):tp_pch_rsvd5';
NODE_NAME     U7C1 AG15
 '@BASEBOARD_FAB2_LIB.BASEBOARD_FAB2(SCH_1):PAGE121_I34@MSTR_U_PROC.LBG_CORE_QAT_EXT_D(CHIPS)':
 'RSVD'<5>: CDS_PINID='RSVD(5)';
NET_NAME
'TP_PCH_RSVD50'
 '@BASEBOARD_FAB2_LIB.BASEBOARD_FAB2(SCH_1):TP_PCH_RSVD50':
 C_SIGNAL='@baseboard_fab2_lib.baseboard_fab2(sch_1):tp_pch_rsvd50';
NODE_NAME     U7C1 H69
 '@BASEBOARD_FAB2_LIB.BASEBOARD_FAB2(SCH_1):PAGE116_I220@MSTR_U_PROC.LBG_CORE_QAT_EXT_D(CHIPS)':
 'RSVD'<50>: CDS_PINID='RSVD(50)';
NET_NAME
'TP_PCH_RSVD51'
 '@BASEBOARD_FAB2_LIB.BASEBOARD_FAB2(SCH_1):TP_PCH_RSVD51':
 C_SIGNAL='@baseboard_fab2_lib.baseboard_fab2(sch_1):tp_pch_rsvd51';
NODE_NAME     U7C1 AA69
 '@BASEBOARD_FAB2_LIB.BASEBOARD_FAB2(SCH_1):PAGE116_I220@MSTR_U_PROC.LBG_CORE_QAT_EXT_D(CHIPS)':
 'RSVD'<51>: CDS_PINID='RSVD(51)';
NET_NAME
'TP_PCH_RSVD52'
 '@BASEBOARD_FAB2_LIB.BASEBOARD_FAB2(SCH_1):TP_PCH_RSVD52':
 C_SIGNAL='@baseboard_fab2_lib.baseboard_fab2(sch_1):tp_pch_rsvd52';
NODE_NAME     U7C1 AA71
 '@BASEBOARD_FAB2_LIB.BASEBOARD_FAB2(SCH_1):PAGE116_I220@MSTR_U_PROC.LBG_CORE_QAT_EXT_D(CHIPS)':
 'RSVD'<52>: CDS_PINID='RSVD(52)';
NET_NAME
'TP_PCH_RSVD53'
 '@BASEBOARD_FAB2_LIB.BASEBOARD_FAB2(SCH_1):TP_PCH_RSVD53':
 C_SIGNAL='@baseboard_fab2_lib.baseboard_fab2(sch_1):tp_pch_rsvd53';
NODE_NAME     U7C1 P26
 '@BASEBOARD_FAB2_LIB.BASEBOARD_FAB2(SCH_1):PAGE118_I73@MSTR_U_PROC.LBG_CORE_QAT_EXT_D(CHIPS)':
 'RSVD'<53>: CDS_PINID='RSVD(53)';
NET_NAME
'TP_PCH_RSVD54'
 '@BASEBOARD_FAB2_LIB.BASEBOARD_FAB2(SCH_1):TP_PCH_RSVD54':
 C_SIGNAL='@baseboard_fab2_lib.baseboard_fab2(sch_1):tp_pch_rsvd54';
NODE_NAME     U7C1 R24
 '@BASEBOARD_FAB2_LIB.BASEBOARD_FAB2(SCH_1):PAGE118_I73@MSTR_U_PROC.LBG_CORE_QAT_EXT_D(CHIPS)':
 'RSVD'<54>: CDS_PINID='RSVD(54)';
NET_NAME
'TP_PCH_RSVD55'
 '@BASEBOARD_FAB2_LIB.BASEBOARD_FAB2(SCH_1):TP_PCH_RSVD55':
 C_SIGNAL='@baseboard_fab2_lib.baseboard_fab2(sch_1):tp_pch_rsvd55';
NODE_NAME     U7C1 BN68
 '@BASEBOARD_FAB2_LIB.BASEBOARD_FAB2(SCH_1):PAGE115_I74@MSTR_U_PROC.LBG_CORE_QAT_EXT_D(CHIPS)':
 'RSVD'<55>: CDS_PINID='RSVD(55)';
NET_NAME
'TP_PCH_RSVD58'
 '@BASEBOARD_FAB2_LIB.BASEBOARD_FAB2(SCH_1):TP_PCH_RSVD58':
 C_SIGNAL='@baseboard_fab2_lib.baseboard_fab2(sch_1):tp_pch_rsvd58';
NODE_NAME     U7C1 AP27
 '@BASEBOARD_FAB2_LIB.BASEBOARD_FAB2(SCH_1):PAGE122_I63@MSTR_U_PROC.LBG_CORE_QAT_EXT_D(CHIPS)':
 'RSVD'<58>: CDS_PINID='RSVD(58)';
NET_NAME
'TP_PCH_RSVD59'
 '@BASEBOARD_FAB2_LIB.BASEBOARD_FAB2(SCH_1):TP_PCH_RSVD59':
 C_SIGNAL='@baseboard_fab2_lib.baseboard_fab2(sch_1):tp_pch_rsvd59';
NODE_NAME     U7C1 AT27
 '@BASEBOARD_FAB2_LIB.BASEBOARD_FAB2(SCH_1):PAGE122_I63@MSTR_U_PROC.LBG_CORE_QAT_EXT_D(CHIPS)':
 'RSVD'<59>: CDS_PINID='RSVD(59)';
NET_NAME
'TP_PCH_RSVD6'
 '@BASEBOARD_FAB2_LIB.BASEBOARD_FAB2(SCH_1):TP_PCH_RSVD6':
 C_SIGNAL='@baseboard_fab2_lib.baseboard_fab2(sch_1):tp_pch_rsvd6';
NODE_NAME     U7C1 AT69
 '@BASEBOARD_FAB2_LIB.BASEBOARD_FAB2(SCH_1):PAGE121_I34@MSTR_U_PROC.LBG_CORE_QAT_EXT_D(CHIPS)':
 'RSVD'<6>: CDS_PINID='RSVD(6)';
NET_NAME
'TP_PCH_RSVD64'
 '@BASEBOARD_FAB2_LIB.BASEBOARD_FAB2(SCH_1):TP_PCH_RSVD64':
 C_SIGNAL='@baseboard_fab2_lib.baseboard_fab2(sch_1):tp_pch_rsvd64';
NODE_NAME     U7C1 C26
 '@BASEBOARD_FAB2_LIB.BASEBOARD_FAB2(SCH_1):PAGE114_I40@MSTR_U_PROC.LBG_CORE_QAT_EXT_D(CHIPS)':
 'RSVD'<64>: CDS_PINID='RSVD(64)';
NET_NAME
'TP_PCH_RSVD65'
 '@BASEBOARD_FAB2_LIB.BASEBOARD_FAB2(SCH_1):TP_PCH_RSVD65':
 C_SIGNAL='@baseboard_fab2_lib.baseboard_fab2(sch_1):tp_pch_rsvd65';
NODE_NAME     U7C1 A26
 '@BASEBOARD_FAB2_LIB.BASEBOARD_FAB2(SCH_1):PAGE114_I40@MSTR_U_PROC.LBG_CORE_QAT_EXT_D(CHIPS)':
 'RSVD'<65>: CDS_PINID='RSVD(65)';
NET_NAME
'TP_PCH_RSVD7'
 '@BASEBOARD_FAB2_LIB.BASEBOARD_FAB2(SCH_1):TP_PCH_RSVD7':
 C_SIGNAL='@baseboard_fab2_lib.baseboard_fab2(sch_1):tp_pch_rsvd7';
NODE_NAME     U7C1 F8
 '@BASEBOARD_FAB2_LIB.BASEBOARD_FAB2(SCH_1):PAGE121_I34@MSTR_U_PROC.LBG_CORE_QAT_EXT_D(CHIPS)':
 'RSVD'<7>: CDS_PINID='RSVD(7)';
NET_NAME
'TP_PCH_RSVD8'
 '@BASEBOARD_FAB2_LIB.BASEBOARD_FAB2(SCH_1):TP_PCH_RSVD8':
 C_SIGNAL='@baseboard_fab2_lib.baseboard_fab2(sch_1):tp_pch_rsvd8';
NODE_NAME     U7C1 F69
 '@BASEBOARD_FAB2_LIB.BASEBOARD_FAB2(SCH_1):PAGE121_I34@MSTR_U_PROC.LBG_CORE_QAT_EXT_D(CHIPS)':
 'RSVD'<8>: CDS_PINID='RSVD(8)';
NET_NAME
'TP_PCH_RSVD9'
 '@BASEBOARD_FAB2_LIB.BASEBOARD_FAB2(SCH_1):TP_PCH_RSVD9':
 C_SIGNAL='@baseboard_fab2_lib.baseboard_fab2(sch_1):tp_pch_rsvd9';
NODE_NAME     U7C1 F66
 '@BASEBOARD_FAB2_LIB.BASEBOARD_FAB2(SCH_1):PAGE121_I34@MSTR_U_PROC.LBG_CORE_QAT_EXT_D(CHIPS)':
 'RSVD'<9>: CDS_PINID='RSVD(9)';
NET_NAME
'TP_PLTRST_CPU_N'
 '@BASEBOARD_FAB2_LIB.BASEBOARD_FAB2(SCH_1):TP_PLTRST_CPU_N':
 C_SIGNAL='@baseboard_fab2_lib.baseboard_fab2(sch_1):tp_pltrst_cpu_n';
NODE_NAME     U7C1 U17
 '@BASEBOARD_FAB2_LIB.BASEBOARD_FAB2(SCH_1):PAGE118_I73@MSTR_U_PROC.LBG_CORE_QAT_EXT_D(CHIPS)':
 'PLTRST_CPU_N': CDS_PINID='PLTRST_CPU_N';
NET_NAME
'TP_PM_SYNC_GTL'
 '@BASEBOARD_FAB2_LIB.BASEBOARD_FAB2(SCH_1):TP_PM_SYNC_GTL':
 C_SIGNAL='@baseboard_fab2_lib.baseboard_fab2(sch_1):tp_pm_sync_gtl';
NODE_NAME     U7C1 V7
 '@BASEBOARD_FAB2_LIB.BASEBOARD_FAB2(SCH_1):PAGE118_I73@MSTR_U_PROC.LBG_CORE_QAT_EXT_D(CHIPS)':
 'PM_SYNC2': CDS_PINID='PM_SYNC2';
NET_NAME
'TP_PUMP'
 '@BASEBOARD_FAB2_LIB.BASEBOARD_FAB2(SCH_1):TP_PUMP':
 C_SIGNAL='@baseboard_fab2_lib.baseboard_fab2(sch_1):tp_pump';
NODE_NAME     J1B2 6
 '@BASEBOARD_FAB2_LIB.BASEBOARD_FAB2(SCH_1):PAGE251_I25@MSTR_CONN.CONN6_C74770005(CHIPS)':
 'IO6': CDS_PINID='IO6';
NET_NAME
'TP_PVCCINC_CPU1_PH1_GL_0'
 '@BASEBOARD_FAB2_LIB.BASEBOARD_FAB2(SCH_1):TP_PVCCINC_CPU1_PH1_GL_0':
 C_SIGNAL='@baseboard_fab2_lib.baseboard_fab2(sch_1):tp_pvccinc_cpu1_ph1_gl_0';
NODE_NAME     EU1E2 6
 '@BASEBOARD_FAB2_LIB.BASEBOARD_FAB2(SCH_1):PAGE207_I20@MSTR_DISCRETE.IR354XX(CHIPS)':
 'GL'<0>: CDS_PINID='GL(0)';
NET_NAME
'TP_PVCCINC_CPU1_PH1_GL_1'
 '@BASEBOARD_FAB2_LIB.BASEBOARD_FAB2(SCH_1):TP_PVCCINC_CPU1_PH1_GL_1':
 C_SIGNAL='@baseboard_fab2_lib.baseboard_fab2(sch_1):tp_pvccinc_cpu1_ph1_gl_1';
NODE_NAME     EU1E2 41
 '@BASEBOARD_FAB2_LIB.BASEBOARD_FAB2(SCH_1):PAGE207_I20@MSTR_DISCRETE.IR354XX(CHIPS)':
 'GL'<1>: CDS_PINID='GL(1)';
NET_NAME
'TP_PVCCINC_CPU1_PH2_GL_0'
 '@BASEBOARD_FAB2_LIB.BASEBOARD_FAB2(SCH_1):TP_PVCCINC_CPU1_PH2_GL_0':
 C_SIGNAL='@baseboard_fab2_lib.baseboard_fab2(sch_1):tp_pvccinc_cpu1_ph2_gl_0';
NODE_NAME     EU1D4 6
 '@BASEBOARD_FAB2_LIB.BASEBOARD_FAB2(SCH_1):PAGE207_I113@MSTR_DISCRETE.IR354XX(CHIPS)':
 'GL'<0>: CDS_PINID='GL(0)';
NET_NAME
'TP_PVCCINC_CPU1_PH2_GL_1'
 '@BASEBOARD_FAB2_LIB.BASEBOARD_FAB2(SCH_1):TP_PVCCINC_CPU1_PH2_GL_1':
 C_SIGNAL='@baseboard_fab2_lib.baseboard_fab2(sch_1):tp_pvccinc_cpu1_ph2_gl_1';
NODE_NAME     EU1D4 41
 '@BASEBOARD_FAB2_LIB.BASEBOARD_FAB2(SCH_1):PAGE207_I113@MSTR_DISCRETE.IR354XX(CHIPS)':
 'GL'<1>: CDS_PINID='GL(1)';
NET_NAME
'TP_PVCCIN_CPU0_PH1_GL_0'
 '@BASEBOARD_FAB2_LIB.BASEBOARD_FAB2(SCH_1):TP_PVCCIN_CPU0_PH1_GL_0':
 C_SIGNAL='@baseboard_fab2_lib.baseboard_fab2(sch_1):tp_pvccin_cpu0_ph1_gl_0';
NODE_NAME     EU4E1 6
 '@BASEBOARD_FAB2_LIB.BASEBOARD_FAB2(SCH_1):PAGE202_I63@MSTR_DISCRETE.IR354XX(CHIPS)':
 'GL'<0>: CDS_PINID='GL(0)';
NET_NAME
'TP_PVCCIN_CPU0_PH1_GL_1'
 '@BASEBOARD_FAB2_LIB.BASEBOARD_FAB2(SCH_1):TP_PVCCIN_CPU0_PH1_GL_1':
 C_SIGNAL='@baseboard_fab2_lib.baseboard_fab2(sch_1):tp_pvccin_cpu0_ph1_gl_1';
NODE_NAME     EU4E1 41
 '@BASEBOARD_FAB2_LIB.BASEBOARD_FAB2(SCH_1):PAGE202_I63@MSTR_DISCRETE.IR354XX(CHIPS)':
 'GL'<1>: CDS_PINID='GL(1)';
NET_NAME
'TP_PVCCIN_CPU0_PH2_GL_0'
 '@BASEBOARD_FAB2_LIB.BASEBOARD_FAB2(SCH_1):TP_PVCCIN_CPU0_PH2_GL_0':
 C_SIGNAL='@baseboard_fab2_lib.baseboard_fab2(sch_1):tp_pvccin_cpu0_ph2_gl_0';
NODE_NAME     EU4D6 6
 '@BASEBOARD_FAB2_LIB.BASEBOARD_FAB2(SCH_1):PAGE202_I64@MSTR_DISCRETE.IR354XX(CHIPS)':
 'GL'<0>: CDS_PINID='GL(0)';
NET_NAME
'TP_PVCCIN_CPU0_PH2_GL_1'
 '@BASEBOARD_FAB2_LIB.BASEBOARD_FAB2(SCH_1):TP_PVCCIN_CPU0_PH2_GL_1':
 C_SIGNAL='@baseboard_fab2_lib.baseboard_fab2(sch_1):tp_pvccin_cpu0_ph2_gl_1';
NODE_NAME     EU4D6 41
 '@BASEBOARD_FAB2_LIB.BASEBOARD_FAB2(SCH_1):PAGE202_I64@MSTR_DISCRETE.IR354XX(CHIPS)':
 'GL'<1>: CDS_PINID='GL(1)';
NET_NAME
'TP_PVCCIN_CPU0_PH3_GL_0'
 '@BASEBOARD_FAB2_LIB.BASEBOARD_FAB2(SCH_1):TP_PVCCIN_CPU0_PH3_GL_0':
 C_SIGNAL='@baseboard_fab2_lib.baseboard_fab2(sch_1):tp_pvccin_cpu0_ph3_gl_0';
NODE_NAME     EU4D3 6
 '@BASEBOARD_FAB2_LIB.BASEBOARD_FAB2(SCH_1):PAGE203_I70@MSTR_DISCRETE.IR354XX(CHIPS)':
 'GL'<0>: CDS_PINID='GL(0)';
NET_NAME
'TP_PVCCIN_CPU0_PH3_GL_1'
 '@BASEBOARD_FAB2_LIB.BASEBOARD_FAB2(SCH_1):TP_PVCCIN_CPU0_PH3_GL_1':
 C_SIGNAL='@baseboard_fab2_lib.baseboard_fab2(sch_1):tp_pvccin_cpu0_ph3_gl_1';
NODE_NAME     EU4D3 41
 '@BASEBOARD_FAB2_LIB.BASEBOARD_FAB2(SCH_1):PAGE203_I70@MSTR_DISCRETE.IR354XX(CHIPS)':
 'GL'<1>: CDS_PINID='GL(1)';
NET_NAME
'TP_PVCCIN_CPU0_PH4_GL_0'
 '@BASEBOARD_FAB2_LIB.BASEBOARD_FAB2(SCH_1):TP_PVCCIN_CPU0_PH4_GL_0':
 C_SIGNAL='@baseboard_fab2_lib.baseboard_fab2(sch_1):tp_pvccin_cpu0_ph4_gl_0';
NODE_NAME     EU4D1 6
 '@BASEBOARD_FAB2_LIB.BASEBOARD_FAB2(SCH_1):PAGE203_I71@MSTR_DISCRETE.IR354XX(CHIPS)':
 'GL'<0>: CDS_PINID='GL(0)';
NET_NAME
'TP_PVCCIN_CPU0_PH4_GL_1'
 '@BASEBOARD_FAB2_LIB.BASEBOARD_FAB2(SCH_1):TP_PVCCIN_CPU0_PH4_GL_1':
 C_SIGNAL='@baseboard_fab2_lib.baseboard_fab2(sch_1):tp_pvccin_cpu0_ph4_gl_1';
NODE_NAME     EU4D1 41
 '@BASEBOARD_FAB2_LIB.BASEBOARD_FAB2(SCH_1):PAGE203_I71@MSTR_DISCRETE.IR354XX(CHIPS)':
 'GL'<1>: CDS_PINID='GL(1)';
NET_NAME
'TP_PVCCIN_CPU0_PH5_GL_0'
 '@BASEBOARD_FAB2_LIB.BASEBOARD_FAB2(SCH_1):TP_PVCCIN_CPU0_PH5_GL_0':
 C_SIGNAL='@baseboard_fab2_lib.baseboard_fab2(sch_1):tp_pvccin_cpu0_ph5_gl_0';
NODE_NAME     EU4C2 6
 '@BASEBOARD_FAB2_LIB.BASEBOARD_FAB2(SCH_1):PAGE204_I71@MSTR_DISCRETE.IR354XX(CHIPS)':
 'GL'<0>: CDS_PINID='GL(0)';
NET_NAME
'TP_PVCCIN_CPU0_PH5_GL_1'
 '@BASEBOARD_FAB2_LIB.BASEBOARD_FAB2(SCH_1):TP_PVCCIN_CPU0_PH5_GL_1':
 C_SIGNAL='@baseboard_fab2_lib.baseboard_fab2(sch_1):tp_pvccin_cpu0_ph5_gl_1';
NODE_NAME     EU4C2 41
 '@BASEBOARD_FAB2_LIB.BASEBOARD_FAB2(SCH_1):PAGE204_I71@MSTR_DISCRETE.IR354XX(CHIPS)':
 'GL'<1>: CDS_PINID='GL(1)';
NET_NAME
'TP_PVCCIN_CPU1_PH3_GL_0'
 '@BASEBOARD_FAB2_LIB.BASEBOARD_FAB2(SCH_1):TP_PVCCIN_CPU1_PH3_GL_0':
 C_SIGNAL='@baseboard_fab2_lib.baseboard_fab2(sch_1):tp_pvccin_cpu1_ph3_gl_0';
NODE_NAME     EU1D3 6
 '@BASEBOARD_FAB2_LIB.BASEBOARD_FAB2(SCH_1):PAGE208_I27@MSTR_DISCRETE.IR354XX(CHIPS)':
 'GL'<0>: CDS_PINID='GL(0)';
NET_NAME
'TP_PVCCIN_CPU1_PH3_GL_1'
 '@BASEBOARD_FAB2_LIB.BASEBOARD_FAB2(SCH_1):TP_PVCCIN_CPU1_PH3_GL_1':
 C_SIGNAL='@baseboard_fab2_lib.baseboard_fab2(sch_1):tp_pvccin_cpu1_ph3_gl_1';
NODE_NAME     EU1D3 41
 '@BASEBOARD_FAB2_LIB.BASEBOARD_FAB2(SCH_1):PAGE208_I27@MSTR_DISCRETE.IR354XX(CHIPS)':
 'GL'<1>: CDS_PINID='GL(1)';
NET_NAME
'TP_PVCCIN_CPU1_PH4_GL_0'
 '@BASEBOARD_FAB2_LIB.BASEBOARD_FAB2(SCH_1):TP_PVCCIN_CPU1_PH4_GL_0':
 C_SIGNAL='@baseboard_fab2_lib.baseboard_fab2(sch_1):tp_pvccin_cpu1_ph4_gl_0';
NODE_NAME     EU1D1 6
 '@BASEBOARD_FAB2_LIB.BASEBOARD_FAB2(SCH_1):PAGE208_I71@MSTR_DISCRETE.IR354XX(CHIPS)':
 'GL'<0>: CDS_PINID='GL(0)';
NET_NAME
'TP_PVCCIN_CPU1_PH4_GL_1'
 '@BASEBOARD_FAB2_LIB.BASEBOARD_FAB2(SCH_1):TP_PVCCIN_CPU1_PH4_GL_1':
 C_SIGNAL='@baseboard_fab2_lib.baseboard_fab2(sch_1):tp_pvccin_cpu1_ph4_gl_1';
NODE_NAME     EU1D1 41
 '@BASEBOARD_FAB2_LIB.BASEBOARD_FAB2(SCH_1):PAGE208_I71@MSTR_DISCRETE.IR354XX(CHIPS)':
 'GL'<1>: CDS_PINID='GL(1)';
NET_NAME
'TP_PVCCIN_CPU1_PH5_GL_0'
 '@BASEBOARD_FAB2_LIB.BASEBOARD_FAB2(SCH_1):TP_PVCCIN_CPU1_PH5_GL_0':
 C_SIGNAL='@baseboard_fab2_lib.baseboard_fab2(sch_1):tp_pvccin_cpu1_ph5_gl_0';
NODE_NAME     EU1C3 6
 '@BASEBOARD_FAB2_LIB.BASEBOARD_FAB2(SCH_1):PAGE209_I56@MSTR_DISCRETE.IR354XX(CHIPS)':
 'GL'<0>: CDS_PINID='GL(0)';
NET_NAME
'TP_PVCCIN_CPU1_PH5_GL_1'
 '@BASEBOARD_FAB2_LIB.BASEBOARD_FAB2(SCH_1):TP_PVCCIN_CPU1_PH5_GL_1':
 C_SIGNAL='@baseboard_fab2_lib.baseboard_fab2(sch_1):tp_pvccin_cpu1_ph5_gl_1';
NODE_NAME     EU1C3 41
 '@BASEBOARD_FAB2_LIB.BASEBOARD_FAB2(SCH_1):PAGE209_I56@MSTR_DISCRETE.IR354XX(CHIPS)':
 'GL'<1>: CDS_PINID='GL(1)';
NET_NAME
'TP_PVCCIO_CPU0_GL_0'
 '@BASEBOARD_FAB2_LIB.BASEBOARD_FAB2(SCH_1):TP_PVCCIO_CPU0_GL_0':
 C_SIGNAL='@baseboard_fab2_lib.baseboard_fab2(sch_1):tp_pvccio_cpu0_gl_0';
NODE_NAME     EU7C1 6
 '@BASEBOARD_FAB2_LIB.BASEBOARD_FAB2(SCH_1):PAGE212_I101@MSTR_DISCRETE.IR354XX(CHIPS)':
 'GL'<0>: CDS_PINID='GL(0)';
NET_NAME
'TP_PVCCIO_CPU0_GL_1'
 '@BASEBOARD_FAB2_LIB.BASEBOARD_FAB2(SCH_1):TP_PVCCIO_CPU0_GL_1':
 C_SIGNAL='@baseboard_fab2_lib.baseboard_fab2(sch_1):tp_pvccio_cpu0_gl_1';
NODE_NAME     EU7C1 41
 '@BASEBOARD_FAB2_LIB.BASEBOARD_FAB2(SCH_1):PAGE212_I101@MSTR_DISCRETE.IR354XX(CHIPS)':
 'GL'<1>: CDS_PINID='GL(1)';
NET_NAME
'TP_PVCCIO_CPU1_GL_0'
 '@BASEBOARD_FAB2_LIB.BASEBOARD_FAB2(SCH_1):TP_PVCCIO_CPU1_GL_0':
 C_SIGNAL='@baseboard_fab2_lib.baseboard_fab2(sch_1):tp_pvccio_cpu1_gl_0';
NODE_NAME     EU4E2 6
 '@BASEBOARD_FAB2_LIB.BASEBOARD_FAB2(SCH_1):PAGE214_I126@MSTR_DISCRETE.IR354XX(CHIPS)':
 'GL'<0>: CDS_PINID='GL(0)';
NET_NAME
'TP_PVCCIO_CPU1_GL_1'
 '@BASEBOARD_FAB2_LIB.BASEBOARD_FAB2(SCH_1):TP_PVCCIO_CPU1_GL_1':
 C_SIGNAL='@baseboard_fab2_lib.baseboard_fab2(sch_1):tp_pvccio_cpu1_gl_1';
NODE_NAME     EU4E2 41
 '@BASEBOARD_FAB2_LIB.BASEBOARD_FAB2(SCH_1):PAGE214_I126@MSTR_DISCRETE.IR354XX(CHIPS)':
 'GL'<1>: CDS_PINID='GL(1)';
NET_NAME
'TP_PVDDQ_ABC_MP1'
 '@BASEBOARD_FAB2_LIB.BASEBOARD_FAB2(SCH_1):TP_PVDDQ_ABC_MP1':
 C_SIGNAL='@baseboard_fab2_lib.baseboard_fab2(sch_1):tp_pvddq_abc_mp1';
NODE_NAME     R12W26 1
 '@BASEBOARD_FAB2_LIB.BASEBOARD_FAB2(SCH_1):PAGE215_I45@MSTR_DISCRETE.RES(CHIPS)':
 'A': CDS_PINID='A';
NODE_NAME     EU7G1 14
 '@BASEBOARD_FAB2_LIB.BASEBOARD_FAB2(SCH_1):PAGE215_I69@MSTR_CONTROLLER.PXM1310B(CHIPS)':
 'MP1': CDS_PINID='MP1';
NET_NAME
'TP_PVDDQ_ABC_MP2'
 '@BASEBOARD_FAB2_LIB.BASEBOARD_FAB2(SCH_1):TP_PVDDQ_ABC_MP2':
 C_SIGNAL='@baseboard_fab2_lib.baseboard_fab2(sch_1):tp_pvddq_abc_mp2';
NODE_NAME     R12W27 1
 '@BASEBOARD_FAB2_LIB.BASEBOARD_FAB2(SCH_1):PAGE215_I54@MSTR_DISCRETE.RES(CHIPS)':
 'A': CDS_PINID='A';
NODE_NAME     EU7G1 18
 '@BASEBOARD_FAB2_LIB.BASEBOARD_FAB2(SCH_1):PAGE215_I69@MSTR_CONTROLLER.PXM1310B(CHIPS)':
 'MP2': CDS_PINID='MP2';
NET_NAME
'TP_PVDDQ_ABC_PH1_GL_0'
 '@BASEBOARD_FAB2_LIB.BASEBOARD_FAB2(SCH_1):TP_PVDDQ_ABC_PH1_GL_0':
 C_SIGNAL='@baseboard_fab2_lib.baseboard_fab2(sch_1):tp_pvddq_abc_ph1_gl_0';
NODE_NAME     EU7G2 6
 '@BASEBOARD_FAB2_LIB.BASEBOARD_FAB2(SCH_1):PAGE216_I102@MSTR_DISCRETE.IR354XX(CHIPS)':
 'GL'<0>: CDS_PINID='GL(0)';
NET_NAME
'TP_PVDDQ_ABC_PH1_GL_1'
 '@BASEBOARD_FAB2_LIB.BASEBOARD_FAB2(SCH_1):TP_PVDDQ_ABC_PH1_GL_1':
 C_SIGNAL='@baseboard_fab2_lib.baseboard_fab2(sch_1):tp_pvddq_abc_ph1_gl_1';
NODE_NAME     EU7G2 41
 '@BASEBOARD_FAB2_LIB.BASEBOARD_FAB2(SCH_1):PAGE216_I102@MSTR_DISCRETE.IR354XX(CHIPS)':
 'GL'<1>: CDS_PINID='GL(1)';
NET_NAME
'TP_PVDDQ_ABC_PH2_GL_0'
 '@BASEBOARD_FAB2_LIB.BASEBOARD_FAB2(SCH_1):TP_PVDDQ_ABC_PH2_GL_0':
 C_SIGNAL='@baseboard_fab2_lib.baseboard_fab2(sch_1):tp_pvddq_abc_ph2_gl_0';
NODE_NAME     EU7G3 6
 '@BASEBOARD_FAB2_LIB.BASEBOARD_FAB2(SCH_1):PAGE216_I103@MSTR_DISCRETE.IR354XX(CHIPS)':
 'GL'<0>: CDS_PINID='GL(0)';
NET_NAME
'TP_PVDDQ_ABC_PH2_GL_1'
 '@BASEBOARD_FAB2_LIB.BASEBOARD_FAB2(SCH_1):TP_PVDDQ_ABC_PH2_GL_1':
 C_SIGNAL='@baseboard_fab2_lib.baseboard_fab2(sch_1):tp_pvddq_abc_ph2_gl_1';
NODE_NAME     EU7G3 41
 '@BASEBOARD_FAB2_LIB.BASEBOARD_FAB2(SCH_1):PAGE216_I103@MSTR_DISCRETE.IR354XX(CHIPS)':
 'GL'<1>: CDS_PINID='GL(1)';
NET_NAME
'TP_PVDDQ_DEF_MP1'
 '@BASEBOARD_FAB2_LIB.BASEBOARD_FAB2(SCH_1):TP_PVDDQ_DEF_MP1':
 C_SIGNAL='@baseboard_fab2_lib.baseboard_fab2(sch_1):tp_pvddq_def_mp1';
NODE_NAME     R12W29 1
 '@BASEBOARD_FAB2_LIB.BASEBOARD_FAB2(SCH_1):PAGE218_I46@MSTR_DISCRETE.RES(CHIPS)':
 'A': CDS_PINID='A';
NODE_NAME     EU7A5 14
 '@BASEBOARD_FAB2_LIB.BASEBOARD_FAB2(SCH_1):PAGE218_I69@MSTR_CONTROLLER.PXM1310B(CHIPS)':
 'MP1': CDS_PINID='MP1';
NET_NAME
'TP_PVDDQ_DEF_MP2'
 '@BASEBOARD_FAB2_LIB.BASEBOARD_FAB2(SCH_1):TP_PVDDQ_DEF_MP2':
 C_SIGNAL='@baseboard_fab2_lib.baseboard_fab2(sch_1):tp_pvddq_def_mp2';
NODE_NAME     R12W30 1
 '@BASEBOARD_FAB2_LIB.BASEBOARD_FAB2(SCH_1):PAGE218_I55@MSTR_DISCRETE.RES(CHIPS)':
 'A': CDS_PINID='A';
NODE_NAME     EU7A5 18
 '@BASEBOARD_FAB2_LIB.BASEBOARD_FAB2(SCH_1):PAGE218_I69@MSTR_CONTROLLER.PXM1310B(CHIPS)':
 'MP2': CDS_PINID='MP2';
NET_NAME
'TP_PVDDQ_DEF_PH1_GL_0'
 '@BASEBOARD_FAB2_LIB.BASEBOARD_FAB2(SCH_1):TP_PVDDQ_DEF_PH1_GL_0':
 C_SIGNAL='@baseboard_fab2_lib.baseboard_fab2(sch_1):tp_pvddq_def_ph1_gl_0';
NODE_NAME     EU7A1 6
 '@BASEBOARD_FAB2_LIB.BASEBOARD_FAB2(SCH_1):PAGE219_I106@MSTR_DISCRETE.IR354XX(CHIPS)':
 'GL'<0>: CDS_PINID='GL(0)';
NET_NAME
'TP_PVDDQ_DEF_PH1_GL_1'
 '@BASEBOARD_FAB2_LIB.BASEBOARD_FAB2(SCH_1):TP_PVDDQ_DEF_PH1_GL_1':
 C_SIGNAL='@baseboard_fab2_lib.baseboard_fab2(sch_1):tp_pvddq_def_ph1_gl_1';
NODE_NAME     EU7A1 41
 '@BASEBOARD_FAB2_LIB.BASEBOARD_FAB2(SCH_1):PAGE219_I106@MSTR_DISCRETE.IR354XX(CHIPS)':
 'GL'<1>: CDS_PINID='GL(1)';
NET_NAME
'TP_PVDDQ_DEF_PH2_GL_0'
 '@BASEBOARD_FAB2_LIB.BASEBOARD_FAB2(SCH_1):TP_PVDDQ_DEF_PH2_GL_0':
 C_SIGNAL='@baseboard_fab2_lib.baseboard_fab2(sch_1):tp_pvddq_def_ph2_gl_0';
NODE_NAME     EU7A4 6
 '@BASEBOARD_FAB2_LIB.BASEBOARD_FAB2(SCH_1):PAGE219_I107@MSTR_DISCRETE.IR354XX(CHIPS)':
 'GL'<0>: CDS_PINID='GL(0)';
NET_NAME
'TP_PVDDQ_DEF_PH2_GL_1'
 '@BASEBOARD_FAB2_LIB.BASEBOARD_FAB2(SCH_1):TP_PVDDQ_DEF_PH2_GL_1':
 C_SIGNAL='@baseboard_fab2_lib.baseboard_fab2(sch_1):tp_pvddq_def_ph2_gl_1';
NODE_NAME     EU7A4 41
 '@BASEBOARD_FAB2_LIB.BASEBOARD_FAB2(SCH_1):PAGE219_I107@MSTR_DISCRETE.IR354XX(CHIPS)':
 'GL'<1>: CDS_PINID='GL(1)';
NET_NAME
'TP_PVDDQ_GHJ_MP1'
 '@BASEBOARD_FAB2_LIB.BASEBOARD_FAB2(SCH_1):TP_PVDDQ_GHJ_MP1':
 C_SIGNAL='@baseboard_fab2_lib.baseboard_fab2(sch_1):tp_pvddq_ghj_mp1';
NODE_NAME     R12W32 1
 '@BASEBOARD_FAB2_LIB.BASEBOARD_FAB2(SCH_1):PAGE223_I45@MSTR_DISCRETE.RES(CHIPS)':
 'A': CDS_PINID='A';
NODE_NAME     EU1G2 14
 '@BASEBOARD_FAB2_LIB.BASEBOARD_FAB2(SCH_1):PAGE223_I69@MSTR_CONTROLLER.PXM1310B(CHIPS)':
 'MP1': CDS_PINID='MP1';
NET_NAME
'TP_PVDDQ_GHJ_MP2'
 '@BASEBOARD_FAB2_LIB.BASEBOARD_FAB2(SCH_1):TP_PVDDQ_GHJ_MP2':
 C_SIGNAL='@baseboard_fab2_lib.baseboard_fab2(sch_1):tp_pvddq_ghj_mp2';
NODE_NAME     R12W33 1
 '@BASEBOARD_FAB2_LIB.BASEBOARD_FAB2(SCH_1):PAGE223_I53@MSTR_DISCRETE.RES(CHIPS)':
 'A': CDS_PINID='A';
NODE_NAME     EU1G2 18
 '@BASEBOARD_FAB2_LIB.BASEBOARD_FAB2(SCH_1):PAGE223_I69@MSTR_CONTROLLER.PXM1310B(CHIPS)':
 'MP2': CDS_PINID='MP2';
NET_NAME
'TP_PVDDQ_GHJ_PH1_GL_0'
 '@BASEBOARD_FAB2_LIB.BASEBOARD_FAB2(SCH_1):TP_PVDDQ_GHJ_PH1_GL_0':
 C_SIGNAL='@baseboard_fab2_lib.baseboard_fab2(sch_1):tp_pvddq_ghj_ph1_gl_0';
NODE_NAME     EU1G1 6
 '@BASEBOARD_FAB2_LIB.BASEBOARD_FAB2(SCH_1):PAGE224_I110@MSTR_DISCRETE.IR354XX(CHIPS)':
 'GL'<0>: CDS_PINID='GL(0)';
NET_NAME
'TP_PVDDQ_GHJ_PH1_GL_1'
 '@BASEBOARD_FAB2_LIB.BASEBOARD_FAB2(SCH_1):TP_PVDDQ_GHJ_PH1_GL_1':
 C_SIGNAL='@baseboard_fab2_lib.baseboard_fab2(sch_1):tp_pvddq_ghj_ph1_gl_1';
NODE_NAME     EU1G1 41
 '@BASEBOARD_FAB2_LIB.BASEBOARD_FAB2(SCH_1):PAGE224_I110@MSTR_DISCRETE.IR354XX(CHIPS)':
 'GL'<1>: CDS_PINID='GL(1)';
NET_NAME
'TP_PVDDQ_GHJ_PH2_GL_0'
 '@BASEBOARD_FAB2_LIB.BASEBOARD_FAB2(SCH_1):TP_PVDDQ_GHJ_PH2_GL_0':
 C_SIGNAL='@baseboard_fab2_lib.baseboard_fab2(sch_1):tp_pvddq_ghj_ph2_gl_0';
NODE_NAME     EU1F1 6
 '@BASEBOARD_FAB2_LIB.BASEBOARD_FAB2(SCH_1):PAGE224_I111@MSTR_DISCRETE.IR354XX(CHIPS)':
 'GL'<0>: CDS_PINID='GL(0)';
NET_NAME
'TP_PVDDQ_GHJ_PH2_GL_1'
 '@BASEBOARD_FAB2_LIB.BASEBOARD_FAB2(SCH_1):TP_PVDDQ_GHJ_PH2_GL_1':
 C_SIGNAL='@baseboard_fab2_lib.baseboard_fab2(sch_1):tp_pvddq_ghj_ph2_gl_1';
NODE_NAME     EU1F1 41
 '@BASEBOARD_FAB2_LIB.BASEBOARD_FAB2(SCH_1):PAGE224_I111@MSTR_DISCRETE.IR354XX(CHIPS)':
 'GL'<1>: CDS_PINID='GL(1)';
NET_NAME
'TP_PVDDQ_KLM_PH1_GL_0'
 '@BASEBOARD_FAB2_LIB.BASEBOARD_FAB2(SCH_1):TP_PVDDQ_KLM_PH1_GL_0':
 C_SIGNAL='@baseboard_fab2_lib.baseboard_fab2(sch_1):tp_pvddq_klm_ph1_gl_0';
NODE_NAME     EU1A2 6
 '@BASEBOARD_FAB2_LIB.BASEBOARD_FAB2(SCH_1):PAGE227_I101@MSTR_DISCRETE.IR354XX(CHIPS)':
 'GL'<0>: CDS_PINID='GL(0)';
NET_NAME
'TP_PVDDQ_KLM_PH1_GL_1'
 '@BASEBOARD_FAB2_LIB.BASEBOARD_FAB2(SCH_1):TP_PVDDQ_KLM_PH1_GL_1':
 C_SIGNAL='@baseboard_fab2_lib.baseboard_fab2(sch_1):tp_pvddq_klm_ph1_gl_1';
NODE_NAME     EU1A2 41
 '@BASEBOARD_FAB2_LIB.BASEBOARD_FAB2(SCH_1):PAGE227_I101@MSTR_DISCRETE.IR354XX(CHIPS)':
 'GL'<1>: CDS_PINID='GL(1)';
NET_NAME
'TP_PVDDQ_KLM_PH2_GL_0'
 '@BASEBOARD_FAB2_LIB.BASEBOARD_FAB2(SCH_1):TP_PVDDQ_KLM_PH2_GL_0':
 C_SIGNAL='@baseboard_fab2_lib.baseboard_fab2(sch_1):tp_pvddq_klm_ph2_gl_0';
NODE_NAME     EU1A1 6
 '@BASEBOARD_FAB2_LIB.BASEBOARD_FAB2(SCH_1):PAGE227_I102@MSTR_DISCRETE.IR354XX(CHIPS)':
 'GL'<0>: CDS_PINID='GL(0)';
NET_NAME
'TP_PVDDQ_KLM_PH2_GL_1'
 '@BASEBOARD_FAB2_LIB.BASEBOARD_FAB2(SCH_1):TP_PVDDQ_KLM_PH2_GL_1':
 C_SIGNAL='@baseboard_fab2_lib.baseboard_fab2(sch_1):tp_pvddq_klm_ph2_gl_1';
NODE_NAME     EU1A1 41
 '@BASEBOARD_FAB2_LIB.BASEBOARD_FAB2(SCH_1):PAGE227_I102@MSTR_DISCRETE.IR354XX(CHIPS)':
 'GL'<1>: CDS_PINID='GL(1)';
NET_NAME
'TP_PVNN_PCH_GL_0'
 '@BASEBOARD_FAB2_LIB.BASEBOARD_FAB2(SCH_1):TP_PVNN_PCH_GL_0':
 C_SIGNAL='@baseboard_fab2_lib.baseboard_fab2(sch_1):tp_pvnn_pch_gl_0';
NODE_NAME     EU7A3 6
 '@BASEBOARD_FAB2_LIB.BASEBOARD_FAB2(SCH_1):PAGE236_I116@MSTR_DISCRETE.IR354XX(CHIPS)':
 'GL'<0>: CDS_PINID='GL(0)';
NET_NAME
'TP_PVNN_PCH_GL_1'
 '@BASEBOARD_FAB2_LIB.BASEBOARD_FAB2(SCH_1):TP_PVNN_PCH_GL_1':
 C_SIGNAL='@baseboard_fab2_lib.baseboard_fab2(sch_1):tp_pvnn_pch_gl_1';
NODE_NAME     EU7A3 41
 '@BASEBOARD_FAB2_LIB.BASEBOARD_FAB2(SCH_1):PAGE236_I116@MSTR_DISCRETE.IR354XX(CHIPS)':
 'GL'<1>: CDS_PINID='GL(1)';
NET_NAME
'TP_PVSA_CPU0_GL_0'
 '@BASEBOARD_FAB2_LIB.BASEBOARD_FAB2(SCH_1):TP_PVSA_CPU0_GL_0':
 C_SIGNAL='@baseboard_fab2_lib.baseboard_fab2(sch_1):tp_pvsa_cpu0_gl_0';
NODE_NAME     EU4C1 6
 '@BASEBOARD_FAB2_LIB.BASEBOARD_FAB2(SCH_1):PAGE205_I46@MSTR_DISCRETE.IR354XX(CHIPS)':
 'GL'<0>: CDS_PINID='GL(0)';
NET_NAME
'TP_PVSA_CPU0_GL_1'
 '@BASEBOARD_FAB2_LIB.BASEBOARD_FAB2(SCH_1):TP_PVSA_CPU0_GL_1':
 C_SIGNAL='@baseboard_fab2_lib.baseboard_fab2(sch_1):tp_pvsa_cpu0_gl_1';
NODE_NAME     EU4C1 41
 '@BASEBOARD_FAB2_LIB.BASEBOARD_FAB2(SCH_1):PAGE205_I46@MSTR_DISCRETE.IR354XX(CHIPS)':
 'GL'<1>: CDS_PINID='GL(1)';
NET_NAME
'TP_PVSA_CPU1_GL_0'
 '@BASEBOARD_FAB2_LIB.BASEBOARD_FAB2(SCH_1):TP_PVSA_CPU1_GL_0':
 C_SIGNAL='@baseboard_fab2_lib.baseboard_fab2(sch_1):tp_pvsa_cpu1_gl_0';
NODE_NAME     EU1C1 6
 '@BASEBOARD_FAB2_LIB.BASEBOARD_FAB2(SCH_1):PAGE210_I51@MSTR_DISCRETE.IR354XX(CHIPS)':
 'GL'<0>: CDS_PINID='GL(0)';
NET_NAME
'TP_PVSA_CPU1_GL_1'
 '@BASEBOARD_FAB2_LIB.BASEBOARD_FAB2(SCH_1):TP_PVSA_CPU1_GL_1':
 C_SIGNAL='@baseboard_fab2_lib.baseboard_fab2(sch_1):tp_pvsa_cpu1_gl_1';
NODE_NAME     EU1C1 41
 '@BASEBOARD_FAB2_LIB.BASEBOARD_FAB2(SCH_1):PAGE210_I51@MSTR_DISCRETE.IR354XX(CHIPS)':
 'GL'<1>: CDS_PINID='GL(1)';
NET_NAME
'TP_RGMII1TXD2_GPIOT4'
 '@BASEBOARD_FAB2_LIB.BASEBOARD_FAB2(SCH_1):TP_RGMII1TXD2_GPIOT4':
 C_SIGNAL='@baseboard_fab2_lib.baseboard_fab2(sch_1):tp_rgmii1txd2_gpiot4';
NODE_NAME     U25W4 E7
 '@BASEBOARD_FAB2_LIB.BASEBOARD_FAB2(SCH_1):PAGE147_I106@W_HDL.AST2520A1-GP-GP(CHIPS)':
 'RGMII1TXD2_GPIOT4': CDS_PINID='RGMII1TXD2_GPIOT4';
NODE_NAME     R25W114 2
 '@BASEBOARD_FAB2_LIB.BASEBOARD_FAB2(SCH_1):PAGE150_I218@MSTR_DISCRETE.RES(CHIPS)':
 'B': CDS_PINID='B';
NODE_NAME     R25W149 2
 '@BASEBOARD_FAB2_LIB.BASEBOARD_FAB2(SCH_1):PAGE150_I219@MSTR_DISCRETE.RES(CHIPS)':
 'B': CDS_PINID='B';
NET_NAME
'TP_RGMII1TXD3_GPIOT5'
 '@BASEBOARD_FAB2_LIB.BASEBOARD_FAB2(SCH_1):TP_RGMII1TXD3_GPIOT5':
 C_SIGNAL='@baseboard_fab2_lib.baseboard_fab2(sch_1):tp_rgmii1txd3_gpiot5';
NODE_NAME     U25W4 D7
 '@BASEBOARD_FAB2_LIB.BASEBOARD_FAB2(SCH_1):PAGE147_I106@W_HDL.AST2520A1-GP-GP(CHIPS)':
 'RGMII1TXD3_GPIOT5': CDS_PINID='RGMII1TXD3_GPIOT5';
NODE_NAME     R25W115 2
 '@BASEBOARD_FAB2_LIB.BASEBOARD_FAB2(SCH_1):PAGE150_I242@MSTR_DISCRETE.RES(CHIPS)':
 'B': CDS_PINID='B';
NET_NAME
'TP_RGMII2TXD2_GPIOU2'
 '@BASEBOARD_FAB2_LIB.BASEBOARD_FAB2(SCH_1):TP_RGMII2TXD2_GPIOU2':
 C_SIGNAL='@baseboard_fab2_lib.baseboard_fab2(sch_1):tp_rgmii2txd2_gpiou2';
NODE_NAME     U25W4 D5
 '@BASEBOARD_FAB2_LIB.BASEBOARD_FAB2(SCH_1):PAGE147_I106@W_HDL.AST2520A1-GP-GP(CHIPS)':
 'RGMII2TXD2_GPIOU2': CDS_PINID='RGMII2TXD2_GPIOU2';
NODE_NAME     R25W110 2
 '@BASEBOARD_FAB2_LIB.BASEBOARD_FAB2(SCH_1):PAGE150_I233@MSTR_DISCRETE.RES(CHIPS)':
 'B': CDS_PINID='B';
NODE_NAME     R25W152 2
 '@BASEBOARD_FAB2_LIB.BASEBOARD_FAB2(SCH_1):PAGE150_I234@MSTR_DISCRETE.RES(CHIPS)':
 'B': CDS_PINID='B';
NET_NAME
'TP_RGMII2TXD3_GPIOU3'
 '@BASEBOARD_FAB2_LIB.BASEBOARD_FAB2(SCH_1):TP_RGMII2TXD3_GPIOU3':
 C_SIGNAL='@baseboard_fab2_lib.baseboard_fab2(sch_1):tp_rgmii2txd3_gpiou3';
NODE_NAME     U25W4 D4
 '@BASEBOARD_FAB2_LIB.BASEBOARD_FAB2(SCH_1):PAGE147_I106@W_HDL.AST2520A1-GP-GP(CHIPS)':
 'RGMII2TXD3_GPIOU3': CDS_PINID='RGMII2TXD3_GPIOU3';
NODE_NAME     R25W109 2
 '@BASEBOARD_FAB2_LIB.BASEBOARD_FAB2(SCH_1):PAGE150_I236@MSTR_DISCRETE.RES(CHIPS)':
 'B': CDS_PINID='B';
NET_NAME
'TP_RST_CPU1_CD_HFI0_N'
 '@BASEBOARD_FAB2_LIB.BASEBOARD_FAB2(SCH_1):TP_RST_CPU1_CD_HFI0_N':
 C_SIGNAL='@baseboard_fab2_lib.baseboard_fab2(sch_1):tp_rst_cpu1_cd_hfi0_n';
NODE_NAME     U2D1 BN24
 '@BASEBOARD_FAB2_LIB.BASEBOARD_FAB2(SCH_1):PAGE63_I23@CHPSET_LIB.SKX_EXT_B(CHIPS)':
 'CD_HFI0_RESET_N': CDS_PINID='CD_HFI0_RESET_N';
NET_NAME
'TP_RST_RTCRST_N'
 '@BASEBOARD_FAB2_LIB.BASEBOARD_FAB2(SCH_1):TP_RST_RTCRST_N':
 C_SIGNAL='@baseboard_fab2_lib.baseboard_fab2(sch_1):tp_rst_rtcrst_n';
NODE_NAME     J9G1 2
 '@BASEBOARD_FAB2_LIB.BASEBOARD_FAB2(SCH_1):PAGE137_I128@MSTR_CONN.CONN12_C73564003(CHIPS)':
 'IO2': CDS_PINID='IO2';
NET_NAME
'TP_RSVD<0>'
 '@BASEBOARD_FAB2_LIB.BASEBOARD_FAB2(SCH_1):TP_RSVD'<0>:
 C_SIGNAL='@baseboard_fab2_lib.baseboard_fab2(sch_1):tp_rsvd(0)';
NODE_NAME     J8E4 36
 '@BASEBOARD_FAB2_LIB.BASEBOARD_FAB2(SCH_1):PAGE188_I27@MSTR_SCONN.SCONN64_H87568002_A(CHIPS)':
 'IO36': CDS_PINID='IO36';
NET_NAME
'TP_RSVD_B1'
 '@BASEBOARD_FAB2_LIB.BASEBOARD_FAB2(SCH_1):TP_RSVD_B1':
 C_SIGNAL='@baseboard_fab2_lib.baseboard_fab2(sch_1):tp_rsvd_b1';
NODE_NAME     J8E3 6
 '@BASEBOARD_FAB2_LIB.BASEBOARD_FAB2(SCH_1):PAGE187_I119@MSTR_SCONN.SCONN80_E67482007(CHIPS)':
 'IO6': CDS_PINID='IO6';
NET_NAME
'TP_SGPIO_SATA_CLOCK1_R'
 '@BASEBOARD_FAB2_LIB.BASEBOARD_FAB2(SCH_1):TP_SGPIO_SATA_CLOCK1_R':
 C_SIGNAL='@baseboard_fab2_lib.baseboard_fab2(sch_1):tp_sgpio_sata_clock1_r';
NODE_NAME     J8A1 2A2
 '@BASEBOARD_FAB2_LIB.BASEBOARD_FAB2(SCH_1):PAGE173_I163@MSTR_CONN.CONN72_G97614002_A(CHIPS)':
 'SIDEBANDB_0': CDS_PINID='SIDEBANDB_0';
NET_NAME
'TP_SGPIO_SATA_DATA1_R'
 '@BASEBOARD_FAB2_LIB.BASEBOARD_FAB2(SCH_1):TP_SGPIO_SATA_DATA1_R':
 C_SIGNAL='@baseboard_fab2_lib.baseboard_fab2(sch_1):tp_sgpio_sata_data1_r';
NODE_NAME     J8A1 2C1
 '@BASEBOARD_FAB2_LIB.BASEBOARD_FAB2(SCH_1):PAGE173_I163@MSTR_CONN.CONN72_G97614002_A(CHIPS)':
 'SIDEBANDB_4': CDS_PINID='SIDEBANDB_4';
NET_NAME
'TP_SGPIO_SATA_LOAD1_R'
 '@BASEBOARD_FAB2_LIB.BASEBOARD_FAB2(SCH_1):TP_SGPIO_SATA_LOAD1_R':
 C_SIGNAL='@baseboard_fab2_lib.baseboard_fab2(sch_1):tp_sgpio_sata_load1_r';
NODE_NAME     J8A1 2B2
 '@BASEBOARD_FAB2_LIB.BASEBOARD_FAB2(SCH_1):PAGE173_I163@MSTR_CONN.CONN72_G97614002_A(CHIPS)':
 'SIDEBANDB_1': CDS_PINID='SIDEBANDB_1';
NET_NAME
'TP_SHARED_KR_MDC_0'
 '@BASEBOARD_FAB2_LIB.BASEBOARD_FAB2(SCH_1):TP_SHARED_KR_MDC_0':
 C_SIGNAL='@baseboard_fab2_lib.baseboard_fab2(sch_1):tp_shared_kr_mdc_0';
NODE_NAME     J8E4 49
 '@BASEBOARD_FAB2_LIB.BASEBOARD_FAB2(SCH_1):PAGE188_I27@MSTR_SCONN.SCONN64_H87568002_A(CHIPS)':
 'IO49': CDS_PINID='IO49';
NET_NAME
'TP_SHARED_KR_MDIO_0'
 '@BASEBOARD_FAB2_LIB.BASEBOARD_FAB2(SCH_1):TP_SHARED_KR_MDIO_0':
 C_SIGNAL='@baseboard_fab2_lib.baseboard_fab2(sch_1):tp_shared_kr_mdio_0';
NODE_NAME     J8E4 50
 '@BASEBOARD_FAB2_LIB.BASEBOARD_FAB2(SCH_1):PAGE188_I27@MSTR_SCONN.SCONN64_H87568002_A(CHIPS)':
 'IO50': CDS_PINID='IO50';
NET_NAME
'TP_SLG55021_P12V_FAN_8'
 '@BASEBOARD_FAB2_LIB.BASEBOARD_FAB2(SCH_1):TP_SLG55021_P12V_FAN_8':
 C_SIGNAL='@baseboard_fab2_lib.baseboard_fab2(sch_1):tp_slg55021_p12v_fan_8';
NODE_NAME     EU9M1 8
 '@BASEBOARD_FAB2_LIB.BASEBOARD_FAB2(SCH_1):PAGE198_I69@MSTR_VREG.SLG55021(CHIPS)':
 'PG': CDS_PINID='PG';
NET_NAME
'TP_SLG55021_P12V_MAIN_8'
 '@BASEBOARD_FAB2_LIB.BASEBOARD_FAB2(SCH_1):TP_SLG55021_P12V_MAIN_8':
 C_SIGNAL='@baseboard_fab2_lib.baseboard_fab2(sch_1):tp_slg55021_p12v_main_8';
NODE_NAME     EU7E1 8
 '@BASEBOARD_FAB2_LIB.BASEBOARD_FAB2(SCH_1):PAGE198_I19@MSTR_VREG.SLG55021(CHIPS)':
 'PG': CDS_PINID='PG';
NET_NAME
'TP_SLG55021_P3V3_8'
 '@BASEBOARD_FAB2_LIB.BASEBOARD_FAB2(SCH_1):TP_SLG55021_P3V3_8':
 C_SIGNAL='@baseboard_fab2_lib.baseboard_fab2(sch_1):tp_slg55021_p3v3_8';
NODE_NAME     EU2T1 8
 '@BASEBOARD_FAB2_LIB.BASEBOARD_FAB2(SCH_1):PAGE198_I1@MSTR_VREG.SLG55021(CHIPS)':
 'PG': CDS_PINID='PG';
NET_NAME
'TP_SLG55021_P5V_8'
 '@BASEBOARD_FAB2_LIB.BASEBOARD_FAB2(SCH_1):TP_SLG55021_P5V_8':
 C_SIGNAL='@baseboard_fab2_lib.baseboard_fab2(sch_1):tp_slg55021_p5v_8';
NODE_NAME     EU8B1 8
 '@BASEBOARD_FAB2_LIB.BASEBOARD_FAB2(SCH_1):PAGE198_I13@MSTR_VREG.SLG55021(CHIPS)':
 'PG': CDS_PINID='PG';
NET_NAME
'TP_SLOTX24_RSVD63'
 '@BASEBOARD_FAB2_LIB.BASEBOARD_FAB2(SCH_1):TP_SLOTX24_RSVD63':
 C_SIGNAL='@baseboard_fab2_lib.baseboard_fab2(sch_1):tp_slotx24_rsvd63';
NODE_NAME     J8G1 63
 '@BASEBOARD_FAB2_LIB.BASEBOARD_FAB2(SCH_1):PAGE108_I258@MSTR_SCONN.SCONN200_H68296001(CHIPS)':
 'IO63': CDS_PINID='IO63';
NET_NAME
'TP_SLOTX24_RSVD66'
 '@BASEBOARD_FAB2_LIB.BASEBOARD_FAB2(SCH_1):TP_SLOTX24_RSVD66':
 C_SIGNAL='@baseboard_fab2_lib.baseboard_fab2(sch_1):tp_slotx24_rsvd66';
NODE_NAME     J8G1 66
 '@BASEBOARD_FAB2_LIB.BASEBOARD_FAB2(SCH_1):PAGE108_I258@MSTR_SCONN.SCONN200_H68296001(CHIPS)':
 'IO66': CDS_PINID='IO66';
NET_NAME
'TP_SLP_LAN_N'
 '@BASEBOARD_FAB2_LIB.BASEBOARD_FAB2(SCH_1):TP_SLP_LAN_N':
 C_SIGNAL='@baseboard_fab2_lib.baseboard_fab2(sch_1):tp_slp_lan_n';
NODE_NAME     U7C1 M15
 '@BASEBOARD_FAB2_LIB.BASEBOARD_FAB2(SCH_1):PAGE118_I73@MSTR_U_PROC.LBG_CORE_QAT_EXT_D(CHIPS)':
 'SLP_GBE_N': CDS_PINID='SLP_GBE_N';
NET_NAME
'TP_SMB_CPU1_CD_HFI0_I2CCLK'
 '@BASEBOARD_FAB2_LIB.BASEBOARD_FAB2(SCH_1):TP_SMB_CPU1_CD_HFI0_I2CCLK':
 C_SIGNAL='@baseboard_fab2_lib.baseboard_fab2(sch_1):tp_smb_cpu1_cd_hfi0_i2cclk';
NODE_NAME     U2D1 BN22
 '@BASEBOARD_FAB2_LIB.BASEBOARD_FAB2(SCH_1):PAGE63_I23@CHPSET_LIB.SKX_EXT_B(CHIPS)':
 'CD_HFI0_I2CCLK': CDS_PINID='CD_HFI0_I2CCLK';
NET_NAME
'TP_SMB_CPU1_CD_HFI0_I2CDAT'
 '@BASEBOARD_FAB2_LIB.BASEBOARD_FAB2(SCH_1):TP_SMB_CPU1_CD_HFI0_I2CDAT':
 C_SIGNAL='@baseboard_fab2_lib.baseboard_fab2(sch_1):tp_smb_cpu1_cd_hfi0_i2cdat';
NODE_NAME     U2D1 BP23
 '@BASEBOARD_FAB2_LIB.BASEBOARD_FAB2(SCH_1):PAGE63_I23@CHPSET_LIB.SKX_EXT_B(CHIPS)':
 'CD_HFI0_I2CDAT': CDS_PINID='CD_HFI0_I2CDAT';
NET_NAME
'TP_SMB_DDR_ABC_EN'
 '@BASEBOARD_FAB2_LIB.BASEBOARD_FAB2(SCH_1):TP_SMB_DDR_ABC_EN':
 C_SIGNAL='@baseboard_fab2_lib.baseboard_fab2(sch_1):tp_smb_ddr_abc_en';
NODE_NAME     U6F1 5
 '@BASEBOARD_FAB2_LIB.BASEBOARD_FAB2(SCH_1):PAGE99_I15@MSTR_DIGITAL.PCA9617(CHIPS)':
 'EN': CDS_PINID='EN';
NET_NAME
'TP_SMB_DDR_DEF_EN'
 '@BASEBOARD_FAB2_LIB.BASEBOARD_FAB2(SCH_1):TP_SMB_DDR_DEF_EN':
 C_SIGNAL='@baseboard_fab2_lib.baseboard_fab2(sch_1):tp_smb_ddr_def_en';
NODE_NAME     U7E1 5
 '@BASEBOARD_FAB2_LIB.BASEBOARD_FAB2(SCH_1):PAGE99_I61@MSTR_DIGITAL.PCA9617(CHIPS)':
 'EN': CDS_PINID='EN';
NET_NAME
'TP_SMB_DDR_GHJ_EN'
 '@BASEBOARD_FAB2_LIB.BASEBOARD_FAB2(SCH_1):TP_SMB_DDR_GHJ_EN':
 C_SIGNAL='@baseboard_fab2_lib.baseboard_fab2(sch_1):tp_smb_ddr_ghj_en';
NODE_NAME     U4G1 5
 '@BASEBOARD_FAB2_LIB.BASEBOARD_FAB2(SCH_1):PAGE99_I63@MSTR_DIGITAL.PCA9617(CHIPS)':
 'EN': CDS_PINID='EN';
NET_NAME
'TP_SMB_DDR_KLM_EN'
 '@BASEBOARD_FAB2_LIB.BASEBOARD_FAB2(SCH_1):TP_SMB_DDR_KLM_EN':
 C_SIGNAL='@baseboard_fab2_lib.baseboard_fab2(sch_1):tp_smb_ddr_klm_en';
NODE_NAME     U3B1 5
 '@BASEBOARD_FAB2_LIB.BASEBOARD_FAB2(SCH_1):PAGE99_I75@MSTR_DIGITAL.PCA9617(CHIPS)':
 'EN': CDS_PINID='EN';
NET_NAME
'TP_SMB_PEHPCPU0_EN'
 '@BASEBOARD_FAB2_LIB.BASEBOARD_FAB2(SCH_1):TP_SMB_PEHPCPU0_EN':
 C_SIGNAL='@baseboard_fab2_lib.baseboard_fab2(sch_1):tp_smb_pehpcpu0_en';
NODE_NAME     U1W2 5
 '@BASEBOARD_FAB2_LIB.BASEBOARD_FAB2(SCH_1):PAGE248_I49@W_HDL.TCA9517DGKR-GP(CHIPS)':
 'EN': CDS_PINID='EN';
NET_NAME
'TP_SMB_PEHPCPU1_EN'
 '@BASEBOARD_FAB2_LIB.BASEBOARD_FAB2(SCH_1):TP_SMB_PEHPCPU1_EN':
 C_SIGNAL='@baseboard_fab2_lib.baseboard_fab2(sch_1):tp_smb_pehpcpu1_en';
NODE_NAME     U1B2 5
 '@BASEBOARD_FAB2_LIB.BASEBOARD_FAB2(SCH_1):PAGE163_I28@W_HDL.TCA9517DGKR-GP(CHIPS)':
 'EN': CDS_PINID='EN';
NET_NAME
'TP_SPI_0_0'
 '@BASEBOARD_FAB2_LIB.BASEBOARD_FAB2(SCH_1):TP_SPI_0_0':
 C_SIGNAL='@baseboard_fab2_lib.baseboard_fab2(sch_1):tp_spi_0_0';
NODE_NAME     U7F1 14
 '@BASEBOARD_FAB2_LIB.BASEBOARD_FAB2(SCH_1):PAGE153_I146@MSTR_MEMORY.W25Q256(CHIPS)':
 'NC'<0>: CDS_PINID='NC(0)';
NET_NAME
'TP_SPI_0_1'
 '@BASEBOARD_FAB2_LIB.BASEBOARD_FAB2(SCH_1):TP_SPI_0_1':
 C_SIGNAL='@baseboard_fab2_lib.baseboard_fab2(sch_1):tp_spi_0_1';
NODE_NAME     U7F1 13
 '@BASEBOARD_FAB2_LIB.BASEBOARD_FAB2(SCH_1):PAGE153_I146@MSTR_MEMORY.W25Q256(CHIPS)':
 'NC'<1>: CDS_PINID='NC(1)';
NET_NAME
'TP_SPI_0_2'
 '@BASEBOARD_FAB2_LIB.BASEBOARD_FAB2(SCH_1):TP_SPI_0_2':
 C_SIGNAL='@baseboard_fab2_lib.baseboard_fab2(sch_1):tp_spi_0_2';
NODE_NAME     U7F1 12
 '@BASEBOARD_FAB2_LIB.BASEBOARD_FAB2(SCH_1):PAGE153_I146@MSTR_MEMORY.W25Q256(CHIPS)':
 'NC'<2>: CDS_PINID='NC(2)';
NET_NAME
'TP_SPI_0_3'
 '@BASEBOARD_FAB2_LIB.BASEBOARD_FAB2(SCH_1):TP_SPI_0_3':
 C_SIGNAL='@baseboard_fab2_lib.baseboard_fab2(sch_1):tp_spi_0_3';
NODE_NAME     U7F1 11
 '@BASEBOARD_FAB2_LIB.BASEBOARD_FAB2(SCH_1):PAGE153_I146@MSTR_MEMORY.W25Q256(CHIPS)':
 'NC'<3>: CDS_PINID='NC(3)';
NET_NAME
'TP_SPI_0_4'
 '@BASEBOARD_FAB2_LIB.BASEBOARD_FAB2(SCH_1):TP_SPI_0_4':
 C_SIGNAL='@baseboard_fab2_lib.baseboard_fab2(sch_1):tp_spi_0_4';
NODE_NAME     U7F1 6
 '@BASEBOARD_FAB2_LIB.BASEBOARD_FAB2(SCH_1):PAGE153_I146@MSTR_MEMORY.W25Q256(CHIPS)':
 'NC'<4>: CDS_PINID='NC(4)';
NET_NAME
'TP_SPI_0_5'
 '@BASEBOARD_FAB2_LIB.BASEBOARD_FAB2(SCH_1):TP_SPI_0_5':
 C_SIGNAL='@baseboard_fab2_lib.baseboard_fab2(sch_1):tp_spi_0_5';
NODE_NAME     U7F1 5
 '@BASEBOARD_FAB2_LIB.BASEBOARD_FAB2(SCH_1):PAGE153_I146@MSTR_MEMORY.W25Q256(CHIPS)':
 'NC'<5>: CDS_PINID='NC(5)';
NET_NAME
'TP_SPI_0_6'
 '@BASEBOARD_FAB2_LIB.BASEBOARD_FAB2(SCH_1):TP_SPI_0_6':
 C_SIGNAL='@baseboard_fab2_lib.baseboard_fab2(sch_1):tp_spi_0_6';
NODE_NAME     U7F1 4
 '@BASEBOARD_FAB2_LIB.BASEBOARD_FAB2(SCH_1):PAGE153_I146@MSTR_MEMORY.W25Q256(CHIPS)':
 'NC'<6>: CDS_PINID='NC(6)';
NET_NAME
'TP_SPI_1_0'
 '@BASEBOARD_FAB2_LIB.BASEBOARD_FAB2(SCH_1):TP_SPI_1_0':
 C_SIGNAL='@baseboard_fab2_lib.baseboard_fab2(sch_1):tp_spi_1_0';
NODE_NAME     U3T1 14
 '@BASEBOARD_FAB2_LIB.BASEBOARD_FAB2(SCH_1):PAGE153_I185@W_HDL.W25Q256FVFIG-GP(CHIPS)':
 'NC#14': CDS_PINID='\nc#14\';
NET_NAME
'TP_SPI_1_1'
 '@BASEBOARD_FAB2_LIB.BASEBOARD_FAB2(SCH_1):TP_SPI_1_1':
 C_SIGNAL='@baseboard_fab2_lib.baseboard_fab2(sch_1):tp_spi_1_1';
NODE_NAME     U3T1 13
 '@BASEBOARD_FAB2_LIB.BASEBOARD_FAB2(SCH_1):PAGE153_I185@W_HDL.W25Q256FVFIG-GP(CHIPS)':
 'NC#13': CDS_PINID='\nc#13\';
NET_NAME
'TP_SPI_1_2'
 '@BASEBOARD_FAB2_LIB.BASEBOARD_FAB2(SCH_1):TP_SPI_1_2':
 C_SIGNAL='@baseboard_fab2_lib.baseboard_fab2(sch_1):tp_spi_1_2';
NODE_NAME     U3T1 12
 '@BASEBOARD_FAB2_LIB.BASEBOARD_FAB2(SCH_1):PAGE153_I185@W_HDL.W25Q256FVFIG-GP(CHIPS)':
 'NC#12': CDS_PINID='\nc#12\';
NET_NAME
'TP_SPI_1_3'
 '@BASEBOARD_FAB2_LIB.BASEBOARD_FAB2(SCH_1):TP_SPI_1_3':
 C_SIGNAL='@baseboard_fab2_lib.baseboard_fab2(sch_1):tp_spi_1_3';
NODE_NAME     U3T1 11
 '@BASEBOARD_FAB2_LIB.BASEBOARD_FAB2(SCH_1):PAGE153_I185@W_HDL.W25Q256FVFIG-GP(CHIPS)':
 'NC#11': CDS_PINID='\nc#11\';
NET_NAME
'TP_SPI_1_4'
 '@BASEBOARD_FAB2_LIB.BASEBOARD_FAB2(SCH_1):TP_SPI_1_4':
 C_SIGNAL='@baseboard_fab2_lib.baseboard_fab2(sch_1):tp_spi_1_4';
NODE_NAME     U3T1 6
 '@BASEBOARD_FAB2_LIB.BASEBOARD_FAB2(SCH_1):PAGE153_I185@W_HDL.W25Q256FVFIG-GP(CHIPS)':
 'NC#6': CDS_PINID='\nc#6\';
NET_NAME
'TP_SPI_1_5'
 '@BASEBOARD_FAB2_LIB.BASEBOARD_FAB2(SCH_1):TP_SPI_1_5':
 C_SIGNAL='@baseboard_fab2_lib.baseboard_fab2(sch_1):tp_spi_1_5';
NODE_NAME     U3T1 5
 '@BASEBOARD_FAB2_LIB.BASEBOARD_FAB2(SCH_1):PAGE153_I185@W_HDL.W25Q256FVFIG-GP(CHIPS)':
 'NC#5': CDS_PINID='\nc#5\';
NET_NAME
'TP_SPI_1_6'
 '@BASEBOARD_FAB2_LIB.BASEBOARD_FAB2(SCH_1):TP_SPI_1_6':
 C_SIGNAL='@baseboard_fab2_lib.baseboard_fab2(sch_1):tp_spi_1_6';
NODE_NAME     U3T1 4
 '@BASEBOARD_FAB2_LIB.BASEBOARD_FAB2(SCH_1):PAGE153_I185@W_HDL.W25Q256FVFIG-GP(CHIPS)':
 'NC#4': CDS_PINID='\nc#4\';
NET_NAME
'TP_SPI_2_0'
 '@BASEBOARD_FAB2_LIB.BASEBOARD_FAB2(SCH_1):TP_SPI_2_0':
 C_SIGNAL='@baseboard_fab2_lib.baseboard_fab2(sch_1):tp_spi_2_0';
NODE_NAME     U8F2 4
 '@BASEBOARD_FAB2_LIB.BASEBOARD_FAB2(SCH_1):PAGE162_I32@MSTR_MEMORY.W25Q128(CHIPS)':
 'NC'<0>: CDS_PINID='NC(0)';
NET_NAME
'TP_SPI_2_1'
 '@BASEBOARD_FAB2_LIB.BASEBOARD_FAB2(SCH_1):TP_SPI_2_1':
 C_SIGNAL='@baseboard_fab2_lib.baseboard_fab2(sch_1):tp_spi_2_1';
NODE_NAME     U8F2 5
 '@BASEBOARD_FAB2_LIB.BASEBOARD_FAB2(SCH_1):PAGE162_I32@MSTR_MEMORY.W25Q128(CHIPS)':
 'NC'<1>: CDS_PINID='NC(1)';
NET_NAME
'TP_SPI_2_2'
 '@BASEBOARD_FAB2_LIB.BASEBOARD_FAB2(SCH_1):TP_SPI_2_2':
 C_SIGNAL='@baseboard_fab2_lib.baseboard_fab2(sch_1):tp_spi_2_2';
NODE_NAME     U8F2 6
 '@BASEBOARD_FAB2_LIB.BASEBOARD_FAB2(SCH_1):PAGE162_I32@MSTR_MEMORY.W25Q128(CHIPS)':
 'NC'<2>: CDS_PINID='NC(2)';
NET_NAME
'TP_SPI_2_3'
 '@BASEBOARD_FAB2_LIB.BASEBOARD_FAB2(SCH_1):TP_SPI_2_3':
 C_SIGNAL='@baseboard_fab2_lib.baseboard_fab2(sch_1):tp_spi_2_3';
NODE_NAME     U8F2 11
 '@BASEBOARD_FAB2_LIB.BASEBOARD_FAB2(SCH_1):PAGE162_I32@MSTR_MEMORY.W25Q128(CHIPS)':
 'NC'<3>: CDS_PINID='NC(3)';
NET_NAME
'TP_SPI_2_4'
 '@BASEBOARD_FAB2_LIB.BASEBOARD_FAB2(SCH_1):TP_SPI_2_4':
 C_SIGNAL='@baseboard_fab2_lib.baseboard_fab2(sch_1):tp_spi_2_4';
NODE_NAME     U8F2 12
 '@BASEBOARD_FAB2_LIB.BASEBOARD_FAB2(SCH_1):PAGE162_I32@MSTR_MEMORY.W25Q128(CHIPS)':
 'NC'<4>: CDS_PINID='NC(4)';
NET_NAME
'TP_SPI_2_5'
 '@BASEBOARD_FAB2_LIB.BASEBOARD_FAB2(SCH_1):TP_SPI_2_5':
 C_SIGNAL='@baseboard_fab2_lib.baseboard_fab2(sch_1):tp_spi_2_5';
NODE_NAME     U8F2 13
 '@BASEBOARD_FAB2_LIB.BASEBOARD_FAB2(SCH_1):PAGE162_I32@MSTR_MEMORY.W25Q128(CHIPS)':
 'NC'<5>: CDS_PINID='NC(5)';
NET_NAME
'TP_SPI_2_6'
 '@BASEBOARD_FAB2_LIB.BASEBOARD_FAB2(SCH_1):TP_SPI_2_6':
 C_SIGNAL='@baseboard_fab2_lib.baseboard_fab2(sch_1):tp_spi_2_6';
NODE_NAME     U8F2 14
 '@BASEBOARD_FAB2_LIB.BASEBOARD_FAB2(SCH_1):PAGE162_I32@MSTR_MEMORY.W25Q128(CHIPS)':
 'NC'<6>: CDS_PINID='NC(6)';
NET_NAME
'TP_SPI_PCH_CS1_R1_N'
 '@BASEBOARD_FAB2_LIB.BASEBOARD_FAB2(SCH_1):TP_SPI_PCH_CS1_R1_N':
 C_SIGNAL='@baseboard_fab2_lib.baseboard_fab2(sch_1):tp_spi_pch_cs1_r1_n';
NODE_NAME     U7C1 G7
 '@BASEBOARD_FAB2_LIB.BASEBOARD_FAB2(SCH_1):PAGE121_I34@MSTR_U_PROC.LBG_CORE_QAT_EXT_D(CHIPS)':
 'SPI0_FLASH_CS1_N': CDS_PINID='SPI0_FLASH_CS1_N';
NET_NAME
'TP_SPI_SWITCH1_10'
 '@BASEBOARD_FAB2_LIB.BASEBOARD_FAB2(SCH_1):TP_SPI_SWITCH1_10':
 C_SIGNAL='@baseboard_fab2_lib.baseboard_fab2(sch_1):tp_spi_switch1_10';
NODE_NAME     U2T1 10
 '@BASEBOARD_FAB2_LIB.BASEBOARD_FAB2(SCH_1):PAGE154_I75@MSTR_DIGITAL.PI3B3257A(CHIPS)':
 'IC1': CDS_PINID='IC1';
NET_NAME
'TP_SPI_SWITCH1_11'
 '@BASEBOARD_FAB2_LIB.BASEBOARD_FAB2(SCH_1):TP_SPI_SWITCH1_11':
 C_SIGNAL='@baseboard_fab2_lib.baseboard_fab2(sch_1):tp_spi_switch1_11';
NODE_NAME     U2T1 11
 '@BASEBOARD_FAB2_LIB.BASEBOARD_FAB2(SCH_1):PAGE154_I75@MSTR_DIGITAL.PI3B3257A(CHIPS)':
 'IC0': CDS_PINID='IC0';
NET_NAME
'TP_SPI_SWITCH1_12'
 '@BASEBOARD_FAB2_LIB.BASEBOARD_FAB2(SCH_1):TP_SPI_SWITCH1_12':
 C_SIGNAL='@baseboard_fab2_lib.baseboard_fab2(sch_1):tp_spi_switch1_12';
NODE_NAME     U2T1 12
 '@BASEBOARD_FAB2_LIB.BASEBOARD_FAB2(SCH_1):PAGE154_I75@MSTR_DIGITAL.PI3B3257A(CHIPS)':
 'YD': CDS_PINID='YD';
NET_NAME
'TP_SPI_SWITCH1_13'
 '@BASEBOARD_FAB2_LIB.BASEBOARD_FAB2(SCH_1):TP_SPI_SWITCH1_13':
 C_SIGNAL='@baseboard_fab2_lib.baseboard_fab2(sch_1):tp_spi_switch1_13';
NODE_NAME     U2T1 13
 '@BASEBOARD_FAB2_LIB.BASEBOARD_FAB2(SCH_1):PAGE154_I75@MSTR_DIGITAL.PI3B3257A(CHIPS)':
 'ID1': CDS_PINID='ID1';
NET_NAME
'TP_SPI_SWITCH1_14'
 '@BASEBOARD_FAB2_LIB.BASEBOARD_FAB2(SCH_1):TP_SPI_SWITCH1_14':
 C_SIGNAL='@baseboard_fab2_lib.baseboard_fab2(sch_1):tp_spi_switch1_14';
NODE_NAME     U2T1 14
 '@BASEBOARD_FAB2_LIB.BASEBOARD_FAB2(SCH_1):PAGE154_I75@MSTR_DIGITAL.PI3B3257A(CHIPS)':
 'ID0': CDS_PINID='ID0';
NET_NAME
'TP_SPI_SWITCH1_3'
 '@BASEBOARD_FAB2_LIB.BASEBOARD_FAB2(SCH_1):TP_SPI_SWITCH1_3':
 C_SIGNAL='@baseboard_fab2_lib.baseboard_fab2(sch_1):tp_spi_switch1_3';
NODE_NAME     U2T1 3
 '@BASEBOARD_FAB2_LIB.BASEBOARD_FAB2(SCH_1):PAGE154_I75@MSTR_DIGITAL.PI3B3257A(CHIPS)':
 'IA1': CDS_PINID='IA1';
NET_NAME
'TP_SPI_SWITCH1_6'
 '@BASEBOARD_FAB2_LIB.BASEBOARD_FAB2(SCH_1):TP_SPI_SWITCH1_6':
 C_SIGNAL='@baseboard_fab2_lib.baseboard_fab2(sch_1):tp_spi_switch1_6';
NODE_NAME     U2T1 6
 '@BASEBOARD_FAB2_LIB.BASEBOARD_FAB2(SCH_1):PAGE154_I75@MSTR_DIGITAL.PI3B3257A(CHIPS)':
 'IB1': CDS_PINID='IB1';
NET_NAME
'TP_SPI_SWITCH1_9'
 '@BASEBOARD_FAB2_LIB.BASEBOARD_FAB2(SCH_1):TP_SPI_SWITCH1_9':
 C_SIGNAL='@baseboard_fab2_lib.baseboard_fab2(sch_1):tp_spi_switch1_9';
NODE_NAME     U2T1 9
 '@BASEBOARD_FAB2_LIB.BASEBOARD_FAB2(SCH_1):PAGE154_I75@MSTR_DIGITAL.PI3B3257A(CHIPS)':
 'YC': CDS_PINID='YC';
NET_NAME
'TP_SPRV_SDP0'
 '@BASEBOARD_FAB2_LIB.BASEBOARD_FAB2(SCH_1):TP_SPRV_SDP0':
 C_SIGNAL='@baseboard_fab2_lib.baseboard_fab2(sch_1):tp_sprv_sdp0';
NODE_NAME     EU9E1 63
 '@BASEBOARD_FAB2_LIB.BASEBOARD_FAB2(SCH_1):PAGE139_I72@MSTR_INTEL.SPRINGVILLE(CHIPS)':
 'SDP0': CDS_PINID='SDP0';
NET_NAME
'TP_SPRV_SDP2'
 '@BASEBOARD_FAB2_LIB.BASEBOARD_FAB2(SCH_1):TP_SPRV_SDP2':
 C_SIGNAL='@baseboard_fab2_lib.baseboard_fab2(sch_1):tp_sprv_sdp2';
NODE_NAME     EU9E1 62
 '@BASEBOARD_FAB2_LIB.BASEBOARD_FAB2(SCH_1):PAGE139_I72@MSTR_INTEL.SPRINGVILLE(CHIPS)':
 'SDP2': CDS_PINID='SDP2';
NET_NAME
'TP_SPRV_SDP3'
 '@BASEBOARD_FAB2_LIB.BASEBOARD_FAB2(SCH_1):TP_SPRV_SDP3':
 C_SIGNAL='@baseboard_fab2_lib.baseboard_fab2(sch_1):tp_sprv_sdp3';
NODE_NAME     EU9E1 60
 '@BASEBOARD_FAB2_LIB.BASEBOARD_FAB2(SCH_1):PAGE139_I72@MSTR_INTEL.SPRINGVILLE(CHIPS)':
 'SDP3': CDS_PINID='SDP3';
NET_NAME
'TP_TPM_SPI_0'
 '@BASEBOARD_FAB2_LIB.BASEBOARD_FAB2(SCH_1):TP_TPM_SPI_0':
 C_SIGNAL='@baseboard_fab2_lib.baseboard_fab2(sch_1):tp_tpm_spi_0';
NODE_NAME     UN8F2 14
 '@BASEBOARD_FAB2_LIB.BASEBOARD_FAB2(SCH_1):PAGE246_I17@MSTR_MEMORY.W25Q256(CHIPS)':
 'NC'<0>: CDS_PINID='NC(0)';
NET_NAME
'TP_TPM_SPI_1'
 '@BASEBOARD_FAB2_LIB.BASEBOARD_FAB2(SCH_1):TP_TPM_SPI_1':
 C_SIGNAL='@baseboard_fab2_lib.baseboard_fab2(sch_1):tp_tpm_spi_1';
NODE_NAME     UN8F2 13
 '@BASEBOARD_FAB2_LIB.BASEBOARD_FAB2(SCH_1):PAGE246_I17@MSTR_MEMORY.W25Q256(CHIPS)':
 'NC'<1>: CDS_PINID='NC(1)';
NET_NAME
'TP_TPM_SPI_2'
 '@BASEBOARD_FAB2_LIB.BASEBOARD_FAB2(SCH_1):TP_TPM_SPI_2':
 C_SIGNAL='@baseboard_fab2_lib.baseboard_fab2(sch_1):tp_tpm_spi_2';
NODE_NAME     UN8F2 12
 '@BASEBOARD_FAB2_LIB.BASEBOARD_FAB2(SCH_1):PAGE246_I17@MSTR_MEMORY.W25Q256(CHIPS)':
 'NC'<2>: CDS_PINID='NC(2)';
NET_NAME
'TP_TPM_SPI_3'
 '@BASEBOARD_FAB2_LIB.BASEBOARD_FAB2(SCH_1):TP_TPM_SPI_3':
 C_SIGNAL='@baseboard_fab2_lib.baseboard_fab2(sch_1):tp_tpm_spi_3';
NODE_NAME     UN8F2 11
 '@BASEBOARD_FAB2_LIB.BASEBOARD_FAB2(SCH_1):PAGE246_I17@MSTR_MEMORY.W25Q256(CHIPS)':
 'NC'<3>: CDS_PINID='NC(3)';
NET_NAME
'TP_TPM_SPI_4'
 '@BASEBOARD_FAB2_LIB.BASEBOARD_FAB2(SCH_1):TP_TPM_SPI_4':
 C_SIGNAL='@baseboard_fab2_lib.baseboard_fab2(sch_1):tp_tpm_spi_4';
NODE_NAME     UN8F2 6
 '@BASEBOARD_FAB2_LIB.BASEBOARD_FAB2(SCH_1):PAGE246_I17@MSTR_MEMORY.W25Q256(CHIPS)':
 'NC'<4>: CDS_PINID='NC(4)';
NET_NAME
'TP_TPM_SPI_5'
 '@BASEBOARD_FAB2_LIB.BASEBOARD_FAB2(SCH_1):TP_TPM_SPI_5':
 C_SIGNAL='@baseboard_fab2_lib.baseboard_fab2(sch_1):tp_tpm_spi_5';
NODE_NAME     UN8F2 5
 '@BASEBOARD_FAB2_LIB.BASEBOARD_FAB2(SCH_1):PAGE246_I17@MSTR_MEMORY.W25Q256(CHIPS)':
 'NC'<5>: CDS_PINID='NC(5)';
NET_NAME
'TP_TPM_SPI_6'
 '@BASEBOARD_FAB2_LIB.BASEBOARD_FAB2(SCH_1):TP_TPM_SPI_6':
 C_SIGNAL='@baseboard_fab2_lib.baseboard_fab2(sch_1):tp_tpm_spi_6';
NODE_NAME     UN8F2 4
 '@BASEBOARD_FAB2_LIB.BASEBOARD_FAB2(SCH_1):PAGE246_I17@MSTR_MEMORY.W25Q256(CHIPS)':
 'NC'<6>: CDS_PINID='NC(6)';
NET_NAME
'TP_USB2_P03_DN'
 '@BASEBOARD_FAB2_LIB.BASEBOARD_FAB2(SCH_1):TP_USB2_P03_DN':
 C_SIGNAL='@baseboard_fab2_lib.baseboard_fab2(sch_1):tp_usb2_p03_dn';
NODE_NAME     U7C1 CA59
 '@BASEBOARD_FAB2_LIB.BASEBOARD_FAB2(SCH_1):PAGE115_I74@MSTR_U_PROC.LBG_CORE_QAT_EXT_D(CHIPS)':
 'USB2N_3': CDS_PINID='USB2N_3';
NET_NAME
'TP_USB2_P03_DP'
 '@BASEBOARD_FAB2_LIB.BASEBOARD_FAB2(SCH_1):TP_USB2_P03_DP':
 C_SIGNAL='@baseboard_fab2_lib.baseboard_fab2(sch_1):tp_usb2_p03_dp';
NODE_NAME     U7C1 BW59
 '@BASEBOARD_FAB2_LIB.BASEBOARD_FAB2(SCH_1):PAGE115_I74@MSTR_U_PROC.LBG_CORE_QAT_EXT_D(CHIPS)':
 'USB2P_3': CDS_PINID='USB2P_3';
NET_NAME
'TP_USB2_P06_DN'
 '@BASEBOARD_FAB2_LIB.BASEBOARD_FAB2(SCH_1):TP_USB2_P06_DN':
 C_SIGNAL='@baseboard_fab2_lib.baseboard_fab2(sch_1):tp_usb2_p06_dn';
NODE_NAME     U7C1 CA63
 '@BASEBOARD_FAB2_LIB.BASEBOARD_FAB2(SCH_1):PAGE115_I74@MSTR_U_PROC.LBG_CORE_QAT_EXT_D(CHIPS)':
 'USB2N_6': CDS_PINID='USB2N_6';
NET_NAME
'TP_USB2_P06_DP'
 '@BASEBOARD_FAB2_LIB.BASEBOARD_FAB2(SCH_1):TP_USB2_P06_DP':
 C_SIGNAL='@baseboard_fab2_lib.baseboard_fab2(sch_1):tp_usb2_p06_dp';
NODE_NAME     U7C1 BW63
 '@BASEBOARD_FAB2_LIB.BASEBOARD_FAB2(SCH_1):PAGE115_I74@MSTR_U_PROC.LBG_CORE_QAT_EXT_D(CHIPS)':
 'USB2P_6': CDS_PINID='USB2P_6';
NET_NAME
'TP_USB2_P07_DN'
 '@BASEBOARD_FAB2_LIB.BASEBOARD_FAB2(SCH_1):TP_USB2_P07_DN':
 C_SIGNAL='@baseboard_fab2_lib.baseboard_fab2(sch_1):tp_usb2_p07_dn';
NODE_NAME     U7C1 CA57
 '@BASEBOARD_FAB2_LIB.BASEBOARD_FAB2(SCH_1):PAGE115_I74@MSTR_U_PROC.LBG_CORE_QAT_EXT_D(CHIPS)':
 'USB2N_7': CDS_PINID='USB2N_7';
NET_NAME
'TP_USB2_P07_DP'
 '@BASEBOARD_FAB2_LIB.BASEBOARD_FAB2(SCH_1):TP_USB2_P07_DP':
 C_SIGNAL='@baseboard_fab2_lib.baseboard_fab2(sch_1):tp_usb2_p07_dp';
NODE_NAME     U7C1 BW57
 '@BASEBOARD_FAB2_LIB.BASEBOARD_FAB2(SCH_1):PAGE115_I74@MSTR_U_PROC.LBG_CORE_QAT_EXT_D(CHIPS)':
 'USB2P_7': CDS_PINID='USB2P_7';
NET_NAME
'TP_USB2_P10_DN'
 '@BASEBOARD_FAB2_LIB.BASEBOARD_FAB2(SCH_1):TP_USB2_P10_DN':
 C_SIGNAL='@baseboard_fab2_lib.baseboard_fab2(sch_1):tp_usb2_p10_dn';
NODE_NAME     U7C1 BW65
 '@BASEBOARD_FAB2_LIB.BASEBOARD_FAB2(SCH_1):PAGE115_I74@MSTR_U_PROC.LBG_CORE_QAT_EXT_D(CHIPS)':
 'USB2N_10': CDS_PINID='USB2N_10';
NET_NAME
'TP_USB2_P10_DP'
 '@BASEBOARD_FAB2_LIB.BASEBOARD_FAB2(SCH_1):TP_USB2_P10_DP':
 C_SIGNAL='@baseboard_fab2_lib.baseboard_fab2(sch_1):tp_usb2_p10_dp';
NODE_NAME     U7C1 BU65
 '@BASEBOARD_FAB2_LIB.BASEBOARD_FAB2(SCH_1):PAGE115_I74@MSTR_U_PROC.LBG_CORE_QAT_EXT_D(CHIPS)':
 'USB2P_10': CDS_PINID='USB2P_10';
NET_NAME
'TP_USB2_P11_DN'
 '@BASEBOARD_FAB2_LIB.BASEBOARD_FAB2(SCH_1):TP_USB2_P11_DN':
 C_SIGNAL='@baseboard_fab2_lib.baseboard_fab2(sch_1):tp_usb2_p11_dn';
NODE_NAME     U7C1 CA54
 '@BASEBOARD_FAB2_LIB.BASEBOARD_FAB2(SCH_1):PAGE115_I74@MSTR_U_PROC.LBG_CORE_QAT_EXT_D(CHIPS)':
 'USB2N_11': CDS_PINID='USB2N_11';
NET_NAME
'TP_USB2_P11_DP'
 '@BASEBOARD_FAB2_LIB.BASEBOARD_FAB2(SCH_1):TP_USB2_P11_DP':
 C_SIGNAL='@baseboard_fab2_lib.baseboard_fab2(sch_1):tp_usb2_p11_dp';
NODE_NAME     U7C1 BW54
 '@BASEBOARD_FAB2_LIB.BASEBOARD_FAB2(SCH_1):PAGE115_I74@MSTR_U_PROC.LBG_CORE_QAT_EXT_D(CHIPS)':
 'USB2P_11': CDS_PINID='USB2P_11';
NET_NAME
'TP_USB2_P12_DN'
 '@BASEBOARD_FAB2_LIB.BASEBOARD_FAB2(SCH_1):TP_USB2_P12_DN':
 C_SIGNAL='@baseboard_fab2_lib.baseboard_fab2(sch_1):tp_usb2_p12_dn';
NODE_NAME     U7C1 BW67
 '@BASEBOARD_FAB2_LIB.BASEBOARD_FAB2(SCH_1):PAGE115_I74@MSTR_U_PROC.LBG_CORE_QAT_EXT_D(CHIPS)':
 'USB2N_12': CDS_PINID='USB2N_12';
NET_NAME
'TP_USB2_P12_DP'
 '@BASEBOARD_FAB2_LIB.BASEBOARD_FAB2(SCH_1):TP_USB2_P12_DP':
 C_SIGNAL='@baseboard_fab2_lib.baseboard_fab2(sch_1):tp_usb2_p12_dp';
NODE_NAME     U7C1 BV66
 '@BASEBOARD_FAB2_LIB.BASEBOARD_FAB2(SCH_1):PAGE115_I74@MSTR_U_PROC.LBG_CORE_QAT_EXT_D(CHIPS)':
 'USB2P_12': CDS_PINID='USB2P_12';
NET_NAME
'TP_USB2_P13_DN'
 '@BASEBOARD_FAB2_LIB.BASEBOARD_FAB2(SCH_1):TP_USB2_P13_DN':
 C_SIGNAL='@baseboard_fab2_lib.baseboard_fab2(sch_1):tp_usb2_p13_dn';
NODE_NAME     U7C1 BY53
 '@BASEBOARD_FAB2_LIB.BASEBOARD_FAB2(SCH_1):PAGE115_I74@MSTR_U_PROC.LBG_CORE_QAT_EXT_D(CHIPS)':
 'USB2N_13': CDS_PINID='USB2N_13';
NET_NAME
'TP_USB2_P13_DP'
 '@BASEBOARD_FAB2_LIB.BASEBOARD_FAB2(SCH_1):TP_USB2_P13_DP':
 C_SIGNAL='@baseboard_fab2_lib.baseboard_fab2(sch_1):tp_usb2_p13_dp';
NODE_NAME     U7C1 BV53
 '@BASEBOARD_FAB2_LIB.BASEBOARD_FAB2(SCH_1):PAGE115_I74@MSTR_U_PROC.LBG_CORE_QAT_EXT_D(CHIPS)':
 'USB2P_13': CDS_PINID='USB2P_13';
NET_NAME
'TP_USB2_P14_DN'
 '@BASEBOARD_FAB2_LIB.BASEBOARD_FAB2(SCH_1):TP_USB2_P14_DN':
 C_SIGNAL='@baseboard_fab2_lib.baseboard_fab2(sch_1):tp_usb2_p14_dn';
NODE_NAME     U7C1 BW68
 '@BASEBOARD_FAB2_LIB.BASEBOARD_FAB2(SCH_1):PAGE115_I74@MSTR_U_PROC.LBG_CORE_QAT_EXT_D(CHIPS)':
 'USB2N_14': CDS_PINID='USB2N_14';
NET_NAME
'TP_USB2_P14_DP'
 '@BASEBOARD_FAB2_LIB.BASEBOARD_FAB2(SCH_1):TP_USB2_P14_DP':
 C_SIGNAL='@baseboard_fab2_lib.baseboard_fab2(sch_1):tp_usb2_p14_dp';
NODE_NAME     U7C1 BU67
 '@BASEBOARD_FAB2_LIB.BASEBOARD_FAB2(SCH_1):PAGE115_I74@MSTR_U_PROC.LBG_CORE_QAT_EXT_D(CHIPS)':
 'USB2P_14': CDS_PINID='USB2P_14';
NET_NAME
'TP_USB2_P8_DN'
 '@BASEBOARD_FAB2_LIB.BASEBOARD_FAB2(SCH_1):TP_USB2_P8_DN':
 C_SIGNAL='@baseboard_fab2_lib.baseboard_fab2(sch_1):tp_usb2_p8_dn';
NODE_NAME     U7C1 BY64
 '@BASEBOARD_FAB2_LIB.BASEBOARD_FAB2(SCH_1):PAGE115_I74@MSTR_U_PROC.LBG_CORE_QAT_EXT_D(CHIPS)':
 'USB2N_8': CDS_PINID='USB2N_8';
NET_NAME
'TP_USB2_P8_DP'
 '@BASEBOARD_FAB2_LIB.BASEBOARD_FAB2(SCH_1):TP_USB2_P8_DP':
 C_SIGNAL='@baseboard_fab2_lib.baseboard_fab2(sch_1):tp_usb2_p8_dp';
NODE_NAME     U7C1 BV64
 '@BASEBOARD_FAB2_LIB.BASEBOARD_FAB2(SCH_1):PAGE115_I74@MSTR_U_PROC.LBG_CORE_QAT_EXT_D(CHIPS)':
 'USB2P_8': CDS_PINID='USB2P_8';
NET_NAME
'TP_USB2_P9_DN'
 '@BASEBOARD_FAB2_LIB.BASEBOARD_FAB2(SCH_1):TP_USB2_P9_DN':
 C_SIGNAL='@baseboard_fab2_lib.baseboard_fab2(sch_1):tp_usb2_p9_dn';
NODE_NAME     U7C1 BY55
 '@BASEBOARD_FAB2_LIB.BASEBOARD_FAB2(SCH_1):PAGE115_I74@MSTR_U_PROC.LBG_CORE_QAT_EXT_D(CHIPS)':
 'USB2N_9': CDS_PINID='USB2N_9';
NET_NAME
'TP_USB2_P9_DP'
 '@BASEBOARD_FAB2_LIB.BASEBOARD_FAB2(SCH_1):TP_USB2_P9_DP':
 C_SIGNAL='@baseboard_fab2_lib.baseboard_fab2(sch_1):tp_usb2_p9_dp';
NODE_NAME     U7C1 BV55
 '@BASEBOARD_FAB2_LIB.BASEBOARD_FAB2(SCH_1):PAGE115_I74@MSTR_U_PROC.LBG_CORE_QAT_EXT_D(CHIPS)':
 'USB2P_9': CDS_PINID='USB2P_9';
NET_NAME
'TP_USB3_P02_RXN'
 '@BASEBOARD_FAB2_LIB.BASEBOARD_FAB2(SCH_1):TP_USB3_P02_RXN':
 C_SIGNAL='@baseboard_fab2_lib.baseboard_fab2(sch_1):tp_usb3_p02_rxn';
NODE_NAME     U7C1 BJ72
 '@BASEBOARD_FAB2_LIB.BASEBOARD_FAB2(SCH_1):PAGE115_I74@MSTR_U_PROC.LBG_CORE_QAT_EXT_D(CHIPS)':
 'USB3_2_RXN': CDS_PINID='USB3_2_RXN';
NET_NAME
'TP_USB3_P02_RXP'
 '@BASEBOARD_FAB2_LIB.BASEBOARD_FAB2(SCH_1):TP_USB3_P02_RXP':
 C_SIGNAL='@baseboard_fab2_lib.baseboard_fab2(sch_1):tp_usb3_p02_rxp';
NODE_NAME     U7C1 BJ70
 '@BASEBOARD_FAB2_LIB.BASEBOARD_FAB2(SCH_1):PAGE115_I74@MSTR_U_PROC.LBG_CORE_QAT_EXT_D(CHIPS)':
 'USB3_2_RXP': CDS_PINID='USB3_2_RXP';
NET_NAME
'TP_USB3_P02_TXN'
 '@BASEBOARD_FAB2_LIB.BASEBOARD_FAB2(SCH_1):TP_USB3_P02_TXN':
 C_SIGNAL='@baseboard_fab2_lib.baseboard_fab2(sch_1):tp_usb3_p02_txn';
NODE_NAME     U7C1 BL56
 '@BASEBOARD_FAB2_LIB.BASEBOARD_FAB2(SCH_1):PAGE115_I74@MSTR_U_PROC.LBG_CORE_QAT_EXT_D(CHIPS)':
 'USB3_2_TXN': CDS_PINID='USB3_2_TXN';
NET_NAME
'TP_USB3_P02_TXP'
 '@BASEBOARD_FAB2_LIB.BASEBOARD_FAB2(SCH_1):TP_USB3_P02_TXP':
 C_SIGNAL='@baseboard_fab2_lib.baseboard_fab2(sch_1):tp_usb3_p02_txp';
NODE_NAME     U7C1 BJ56
 '@BASEBOARD_FAB2_LIB.BASEBOARD_FAB2(SCH_1):PAGE115_I74@MSTR_U_PROC.LBG_CORE_QAT_EXT_D(CHIPS)':
 'USB3_2_TXP': CDS_PINID='USB3_2_TXP';
NET_NAME
'TP_USB3_P03_RXN'
 '@BASEBOARD_FAB2_LIB.BASEBOARD_FAB2(SCH_1):TP_USB3_P03_RXN':
 C_SIGNAL='@baseboard_fab2_lib.baseboard_fab2(sch_1):tp_usb3_p03_rxn';
NODE_NAME     U7C1 BH71
 '@BASEBOARD_FAB2_LIB.BASEBOARD_FAB2(SCH_1):PAGE115_I74@MSTR_U_PROC.LBG_CORE_QAT_EXT_D(CHIPS)':
 'USB3_3_RXN': CDS_PINID='USB3_3_RXN';
NET_NAME
'TP_USB3_P03_RXP'
 '@BASEBOARD_FAB2_LIB.BASEBOARD_FAB2(SCH_1):TP_USB3_P03_RXP':
 C_SIGNAL='@baseboard_fab2_lib.baseboard_fab2(sch_1):tp_usb3_p03_rxp';
NODE_NAME     U7C1 BH69
 '@BASEBOARD_FAB2_LIB.BASEBOARD_FAB2(SCH_1):PAGE115_I74@MSTR_U_PROC.LBG_CORE_QAT_EXT_D(CHIPS)':
 'USB3_3_RXP': CDS_PINID='USB3_3_RXP';
NET_NAME
'TP_USB3_P03_TXN'
 '@BASEBOARD_FAB2_LIB.BASEBOARD_FAB2(SCH_1):TP_USB3_P03_TXN':
 C_SIGNAL='@baseboard_fab2_lib.baseboard_fab2(sch_1):tp_usb3_p03_txn';
NODE_NAME     U7C1 BM54
 '@BASEBOARD_FAB2_LIB.BASEBOARD_FAB2(SCH_1):PAGE115_I74@MSTR_U_PROC.LBG_CORE_QAT_EXT_D(CHIPS)':
 'USB3_3_TXN': CDS_PINID='USB3_3_TXN';
NET_NAME
'TP_USB3_P03_TXP'
 '@BASEBOARD_FAB2_LIB.BASEBOARD_FAB2(SCH_1):TP_USB3_P03_TXP':
 C_SIGNAL='@baseboard_fab2_lib.baseboard_fab2(sch_1):tp_usb3_p03_txp';
NODE_NAME     U7C1 BN56
 '@BASEBOARD_FAB2_LIB.BASEBOARD_FAB2(SCH_1):PAGE115_I74@MSTR_U_PROC.LBG_CORE_QAT_EXT_D(CHIPS)':
 'USB3_3_TXP': CDS_PINID='USB3_3_TXP';
NET_NAME
'TP_USB3_P04_RXN'
 '@BASEBOARD_FAB2_LIB.BASEBOARD_FAB2(SCH_1):TP_USB3_P04_RXN':
 C_SIGNAL='@baseboard_fab2_lib.baseboard_fab2(sch_1):tp_usb3_p04_rxn';
NODE_NAME     U7C1 BF72
 '@BASEBOARD_FAB2_LIB.BASEBOARD_FAB2(SCH_1):PAGE115_I74@MSTR_U_PROC.LBG_CORE_QAT_EXT_D(CHIPS)':
 'USB3_4_RXN': CDS_PINID='USB3_4_RXN';
NET_NAME
'TP_USB3_P04_RXP'
 '@BASEBOARD_FAB2_LIB.BASEBOARD_FAB2(SCH_1):TP_USB3_P04_RXP':
 C_SIGNAL='@baseboard_fab2_lib.baseboard_fab2(sch_1):tp_usb3_p04_rxp';
NODE_NAME     U7C1 BF70
 '@BASEBOARD_FAB2_LIB.BASEBOARD_FAB2(SCH_1):PAGE115_I74@MSTR_U_PROC.LBG_CORE_QAT_EXT_D(CHIPS)':
 'USB3_4_RXP': CDS_PINID='USB3_4_RXP';
NET_NAME
'TP_USB3_P04_TXN'
 '@BASEBOARD_FAB2_LIB.BASEBOARD_FAB2(SCH_1):TP_USB3_P04_TXN':
 C_SIGNAL='@baseboard_fab2_lib.baseboard_fab2(sch_1):tp_usb3_p04_txn';
NODE_NAME     U7C1 BH58
 '@BASEBOARD_FAB2_LIB.BASEBOARD_FAB2(SCH_1):PAGE115_I74@MSTR_U_PROC.LBG_CORE_QAT_EXT_D(CHIPS)':
 'USB3_4_TXN': CDS_PINID='USB3_4_TXN';
NET_NAME
'TP_USB3_P04_TXP'
 '@BASEBOARD_FAB2_LIB.BASEBOARD_FAB2(SCH_1):TP_USB3_P04_TXP':
 C_SIGNAL='@baseboard_fab2_lib.baseboard_fab2(sch_1):tp_usb3_p04_txp';
NODE_NAME     U7C1 BG56
 '@BASEBOARD_FAB2_LIB.BASEBOARD_FAB2(SCH_1):PAGE115_I74@MSTR_U_PROC.LBG_CORE_QAT_EXT_D(CHIPS)':
 'USB3_4_TXP': CDS_PINID='USB3_4_TXP';
NET_NAME
'TP_USB3_P05_RXN'
 '@BASEBOARD_FAB2_LIB.BASEBOARD_FAB2(SCH_1):TP_USB3_P05_RXN':
 C_SIGNAL='@baseboard_fab2_lib.baseboard_fab2(sch_1):tp_usb3_p05_rxn';
NODE_NAME     U7C1 BE71
 '@BASEBOARD_FAB2_LIB.BASEBOARD_FAB2(SCH_1):PAGE115_I74@MSTR_U_PROC.LBG_CORE_QAT_EXT_D(CHIPS)':
 'USB3_5_RXN': CDS_PINID='USB3_5_RXN';
NET_NAME
'TP_USB3_P05_RXP'
 '@BASEBOARD_FAB2_LIB.BASEBOARD_FAB2(SCH_1):TP_USB3_P05_RXP':
 C_SIGNAL='@baseboard_fab2_lib.baseboard_fab2(sch_1):tp_usb3_p05_rxp';
NODE_NAME     U7C1 BE69
 '@BASEBOARD_FAB2_LIB.BASEBOARD_FAB2(SCH_1):PAGE115_I74@MSTR_U_PROC.LBG_CORE_QAT_EXT_D(CHIPS)':
 'USB3_5_RXP': CDS_PINID='USB3_5_RXP';
NET_NAME
'TP_USB3_P05_TXN'
 '@BASEBOARD_FAB2_LIB.BASEBOARD_FAB2(SCH_1):TP_USB3_P05_TXN':
 C_SIGNAL='@baseboard_fab2_lib.baseboard_fab2(sch_1):tp_usb3_p05_txn';
NODE_NAME     U7C1 BK58
 '@BASEBOARD_FAB2_LIB.BASEBOARD_FAB2(SCH_1):PAGE115_I74@MSTR_U_PROC.LBG_CORE_QAT_EXT_D(CHIPS)':
 'USB3_5_TXN': CDS_PINID='USB3_5_TXN';
NET_NAME
'TP_USB3_P05_TXP'
 '@BASEBOARD_FAB2_LIB.BASEBOARD_FAB2(SCH_1):TP_USB3_P05_TXP':
 C_SIGNAL='@baseboard_fab2_lib.baseboard_fab2(sch_1):tp_usb3_p05_txp';
NODE_NAME     U7C1 BJ59
 '@BASEBOARD_FAB2_LIB.BASEBOARD_FAB2(SCH_1):PAGE115_I74@MSTR_U_PROC.LBG_CORE_QAT_EXT_D(CHIPS)':
 'USB3_5_TXP': CDS_PINID='USB3_5_TXP';
NET_NAME
'TP_USB3_P06_RXN'
 '@BASEBOARD_FAB2_LIB.BASEBOARD_FAB2(SCH_1):TP_USB3_P06_RXN':
 C_SIGNAL='@baseboard_fab2_lib.baseboard_fab2(sch_1):tp_usb3_p06_rxn';
NODE_NAME     U7C1 BD72
 '@BASEBOARD_FAB2_LIB.BASEBOARD_FAB2(SCH_1):PAGE115_I74@MSTR_U_PROC.LBG_CORE_QAT_EXT_D(CHIPS)':
 'USB3_6_RXN': CDS_PINID='USB3_6_RXN';
NET_NAME
'TP_USB3_P06_RXP'
 '@BASEBOARD_FAB2_LIB.BASEBOARD_FAB2(SCH_1):TP_USB3_P06_RXP':
 C_SIGNAL='@baseboard_fab2_lib.baseboard_fab2(sch_1):tp_usb3_p06_rxp';
NODE_NAME     U7C1 BD70
 '@BASEBOARD_FAB2_LIB.BASEBOARD_FAB2(SCH_1):PAGE115_I74@MSTR_U_PROC.LBG_CORE_QAT_EXT_D(CHIPS)':
 'USB3_6_RXP': CDS_PINID='USB3_6_RXP';
NET_NAME
'TP_USB3_P06_TXN'
 '@BASEBOARD_FAB2_LIB.BASEBOARD_FAB2(SCH_1):TP_USB3_P06_TXN':
 C_SIGNAL='@baseboard_fab2_lib.baseboard_fab2(sch_1):tp_usb3_p06_txn';
NODE_NAME     U7C1 BL59
 '@BASEBOARD_FAB2_LIB.BASEBOARD_FAB2(SCH_1):PAGE115_I74@MSTR_U_PROC.LBG_CORE_QAT_EXT_D(CHIPS)':
 'USB3_6_TXN': CDS_PINID='USB3_6_TXN';
NET_NAME
'TP_USB3_P06_TXP'
 '@BASEBOARD_FAB2_LIB.BASEBOARD_FAB2(SCH_1):TP_USB3_P06_TXP':
 C_SIGNAL='@baseboard_fab2_lib.baseboard_fab2(sch_1):tp_usb3_p06_txp';
NODE_NAME     U7C1 BM61
 '@BASEBOARD_FAB2_LIB.BASEBOARD_FAB2(SCH_1):PAGE115_I74@MSTR_U_PROC.LBG_CORE_QAT_EXT_D(CHIPS)':
 'USB3_6_TXP': CDS_PINID='USB3_6_TXP';
NET_NAME
'TP_USB_ESD_AC2'
 '@BASEBOARD_FAB2_LIB.BASEBOARD_FAB2(SCH_1):TP_USB_ESD_AC2':
 C_SIGNAL='@baseboard_fab2_lib.baseboard_fab2(sch_1):tp_usb_esd_ac2';
NODE_NAME     CR1M2 4
 '@BASEBOARD_FAB2_LIB.BASEBOARD_FAB2(SCH_1):PAGE176_I98@MSTR_DISCRETE.DIODEAC_DUAL_ARRAY(CHIPS)':
 'AC2': CDS_PINID='AC2';
NET_NAME
'TP_USB_ESD_AC3'
 '@BASEBOARD_FAB2_LIB.BASEBOARD_FAB2(SCH_1):TP_USB_ESD_AC3':
 C_SIGNAL='@baseboard_fab2_lib.baseboard_fab2(sch_1):tp_usb_esd_ac3';
NODE_NAME     CR1M2 5
 '@BASEBOARD_FAB2_LIB.BASEBOARD_FAB2(SCH_1):PAGE176_I98@MSTR_DISCRETE.DIODEAC_DUAL_ARRAY(CHIPS)':
 'AC3': CDS_PINID='AC3';
NET_NAME
'TP_USB_ESD_OUT2'
 '@BASEBOARD_FAB2_LIB.BASEBOARD_FAB2(SCH_1):TP_USB_ESD_OUT2':
 C_SIGNAL='@baseboard_fab2_lib.baseboard_fab2(sch_1):tp_usb_esd_out2';
NODE_NAME     CR1M2 7
 '@BASEBOARD_FAB2_LIB.BASEBOARD_FAB2(SCH_1):PAGE176_I98@MSTR_DISCRETE.DIODEAC_DUAL_ARRAY(CHIPS)':
 'OUT2': CDS_PINID='OUT2';
NET_NAME
'TP_USB_ESD_OUT3'
 '@BASEBOARD_FAB2_LIB.BASEBOARD_FAB2(SCH_1):TP_USB_ESD_OUT3':
 C_SIGNAL='@baseboard_fab2_lib.baseboard_fab2(sch_1):tp_usb_esd_out3';
NODE_NAME     CR1M2 6
 '@BASEBOARD_FAB2_LIB.BASEBOARD_FAB2(SCH_1):PAGE176_I98@MSTR_DISCRETE.DIODEAC_DUAL_ARRAY(CHIPS)':
 'OUT3': CDS_PINID='OUT3';
NET_NAME
'TP_XDP_CPU0_OBSDATA_A0_MBP2_N'
 '@BASEBOARD_FAB2_LIB.BASEBOARD_FAB2(SCH_1):TP_XDP_CPU0_OBSDATA_A0_MBP2_N':
 C_SIGNAL='@baseboard_fab2_lib.baseboard_fab2(sch_1):tp_xdp_cpu0_obsdata_a0_mbp2~
_n';
NODE_NAME     U5D1 AG10
 '@BASEBOARD_FAB2_LIB.BASEBOARD_FAB2(SCH_1):PAGE21_I259@CHPSET_LIB.SKX_EXT_B(CHIPS)':
 'BPM_N'<2>: CDS_PINID='BPM_N(2)';
NET_NAME
'TP_XDP_CPU0_OBSDATA_A1_MBP3_N'
 '@BASEBOARD_FAB2_LIB.BASEBOARD_FAB2(SCH_1):TP_XDP_CPU0_OBSDATA_A1_MBP3_N':
 C_SIGNAL='@baseboard_fab2_lib.baseboard_fab2(sch_1):tp_xdp_cpu0_obsdata_a1_mbp3~
_n';
NODE_NAME     U5D1 AF11
 '@BASEBOARD_FAB2_LIB.BASEBOARD_FAB2(SCH_1):PAGE21_I259@CHPSET_LIB.SKX_EXT_B(CHIPS)':
 'BPM_N'<3>: CDS_PINID='BPM_N(3)';
NET_NAME
'TP_XDP_CPU0_OBSDATA_A2_MBP4_N'
 '@BASEBOARD_FAB2_LIB.BASEBOARD_FAB2(SCH_1):TP_XDP_CPU0_OBSDATA_A2_MBP4_N':
 C_SIGNAL='@baseboard_fab2_lib.baseboard_fab2(sch_1):tp_xdp_cpu0_obsdata_a2_mbp4~
_n';
NODE_NAME     U5D1 AA12
 '@BASEBOARD_FAB2_LIB.BASEBOARD_FAB2(SCH_1):PAGE21_I259@CHPSET_LIB.SKX_EXT_B(CHIPS)':
 'BPM_N'<4>: CDS_PINID='BPM_N(4)';
NET_NAME
'TP_XDP_CPU0_OBSDATA_A3_MBP5_N'
 '@BASEBOARD_FAB2_LIB.BASEBOARD_FAB2(SCH_1):TP_XDP_CPU0_OBSDATA_A3_MBP5_N':
 C_SIGNAL='@baseboard_fab2_lib.baseboard_fab2(sch_1):tp_xdp_cpu0_obsdata_a3_mbp5~
_n';
NODE_NAME     U5D1 Y11
 '@BASEBOARD_FAB2_LIB.BASEBOARD_FAB2(SCH_1):PAGE21_I259@CHPSET_LIB.SKX_EXT_B(CHIPS)':
 'BPM_N'<5>: CDS_PINID='BPM_N(5)';
NET_NAME
'TP_XDP_CPU1_OBSDATA_B0_MBP2_N'
 '@BASEBOARD_FAB2_LIB.BASEBOARD_FAB2(SCH_1):TP_XDP_CPU1_OBSDATA_B0_MBP2_N':
 C_SIGNAL='@baseboard_fab2_lib.baseboard_fab2(sch_1):tp_xdp_cpu1_obsdata_b0_mbp2~
_n';
NODE_NAME     U2D1 AG10
 '@BASEBOARD_FAB2_LIB.BASEBOARD_FAB2(SCH_1):PAGE55_I172@CHPSET_LIB.SKX_EXT_B(CHIPS)':
 'BPM_N'<2>: CDS_PINID='BPM_N(2)';
NET_NAME
'TP_XDP_CPU1_OBSDATA_B1_MBP3_N'
 '@BASEBOARD_FAB2_LIB.BASEBOARD_FAB2(SCH_1):TP_XDP_CPU1_OBSDATA_B1_MBP3_N':
 C_SIGNAL='@baseboard_fab2_lib.baseboard_fab2(sch_1):tp_xdp_cpu1_obsdata_b1_mbp3~
_n';
NODE_NAME     U2D1 AF11
 '@BASEBOARD_FAB2_LIB.BASEBOARD_FAB2(SCH_1):PAGE55_I172@CHPSET_LIB.SKX_EXT_B(CHIPS)':
 'BPM_N'<3>: CDS_PINID='BPM_N(3)';
NET_NAME
'TP_XDP_CPU1_OBSDATA_B2_MBP4_N'
 '@BASEBOARD_FAB2_LIB.BASEBOARD_FAB2(SCH_1):TP_XDP_CPU1_OBSDATA_B2_MBP4_N':
 C_SIGNAL='@baseboard_fab2_lib.baseboard_fab2(sch_1):tp_xdp_cpu1_obsdata_b2_mbp4~
_n';
NODE_NAME     U2D1 AA12
 '@BASEBOARD_FAB2_LIB.BASEBOARD_FAB2(SCH_1):PAGE55_I172@CHPSET_LIB.SKX_EXT_B(CHIPS)':
 'BPM_N'<4>: CDS_PINID='BPM_N(4)';
NET_NAME
'TP_XDP_CPU1_OBSDATA_B3_MBP5_N'
 '@BASEBOARD_FAB2_LIB.BASEBOARD_FAB2(SCH_1):TP_XDP_CPU1_OBSDATA_B3_MBP5_N':
 C_SIGNAL='@baseboard_fab2_lib.baseboard_fab2(sch_1):tp_xdp_cpu1_obsdata_b3_mbp5~
_n';
NODE_NAME     U2D1 Y11
 '@BASEBOARD_FAB2_LIB.BASEBOARD_FAB2(SCH_1):PAGE55_I172@CHPSET_LIB.SKX_EXT_B(CHIPS)':
 'BPM_N'<5>: CDS_PINID='BPM_N(5)';
NET_NAME
'TP_XDP_CPU_OBSDATA_C0'
 '@BASEBOARD_FAB2_LIB.BASEBOARD_FAB2(SCH_1):TP_XDP_CPU_OBSDATA_C0':
 C_SIGNAL='@baseboard_fab2_lib.baseboard_fab2(sch_1):tp_xdp_cpu_obsdata_c0';
NODE_NAME     J9A3 10
 '@BASEBOARD_FAB2_LIB.BASEBOARD_FAB2(SCH_1):PAGE111_I26@MSTR_SCONN.SCONN60_C21100002(CHIPS)':
 'IO10': CDS_PINID='IO10';
NET_NAME
'TP_XDP_CPU_OBSDATA_C1'
 '@BASEBOARD_FAB2_LIB.BASEBOARD_FAB2(SCH_1):TP_XDP_CPU_OBSDATA_C1':
 C_SIGNAL='@baseboard_fab2_lib.baseboard_fab2(sch_1):tp_xdp_cpu_obsdata_c1';
NODE_NAME     J9A3 12
 '@BASEBOARD_FAB2_LIB.BASEBOARD_FAB2(SCH_1):PAGE111_I26@MSTR_SCONN.SCONN60_C21100002(CHIPS)':
 'IO12': CDS_PINID='IO12';
NET_NAME
'TP_XDP_CPU_OBSDATA_C2'
 '@BASEBOARD_FAB2_LIB.BASEBOARD_FAB2(SCH_1):TP_XDP_CPU_OBSDATA_C2':
 C_SIGNAL='@baseboard_fab2_lib.baseboard_fab2(sch_1):tp_xdp_cpu_obsdata_c2';
NODE_NAME     J9A3 16
 '@BASEBOARD_FAB2_LIB.BASEBOARD_FAB2(SCH_1):PAGE111_I26@MSTR_SCONN.SCONN60_C21100002(CHIPS)':
 'IO16': CDS_PINID='IO16';
NET_NAME
'TP_XDP_CPU_OBSDATA_C3'
 '@BASEBOARD_FAB2_LIB.BASEBOARD_FAB2(SCH_1):TP_XDP_CPU_OBSDATA_C3':
 C_SIGNAL='@baseboard_fab2_lib.baseboard_fab2(sch_1):tp_xdp_cpu_obsdata_c3';
NODE_NAME     J9A3 18
 '@BASEBOARD_FAB2_LIB.BASEBOARD_FAB2(SCH_1):PAGE111_I26@MSTR_SCONN.SCONN60_C21100002(CHIPS)':
 'IO18': CDS_PINID='IO18';
NET_NAME
'TP_XDP_CPU_OBSDATA_D0'
 '@BASEBOARD_FAB2_LIB.BASEBOARD_FAB2(SCH_1):TP_XDP_CPU_OBSDATA_D0':
 C_SIGNAL='@baseboard_fab2_lib.baseboard_fab2(sch_1):tp_xdp_cpu_obsdata_d0';
NODE_NAME     J9A3 28
 '@BASEBOARD_FAB2_LIB.BASEBOARD_FAB2(SCH_1):PAGE111_I26@MSTR_SCONN.SCONN60_C21100002(CHIPS)':
 'IO28': CDS_PINID='IO28';
NET_NAME
'TP_XDP_CPU_OBSDATA_D1'
 '@BASEBOARD_FAB2_LIB.BASEBOARD_FAB2(SCH_1):TP_XDP_CPU_OBSDATA_D1':
 C_SIGNAL='@baseboard_fab2_lib.baseboard_fab2(sch_1):tp_xdp_cpu_obsdata_d1';
NODE_NAME     J9A3 30
 '@BASEBOARD_FAB2_LIB.BASEBOARD_FAB2(SCH_1):PAGE111_I26@MSTR_SCONN.SCONN60_C21100002(CHIPS)':
 'IO30': CDS_PINID='IO30';
NET_NAME
'TP_XDP_CPU_OBSDATA_D2'
 '@BASEBOARD_FAB2_LIB.BASEBOARD_FAB2(SCH_1):TP_XDP_CPU_OBSDATA_D2':
 C_SIGNAL='@baseboard_fab2_lib.baseboard_fab2(sch_1):tp_xdp_cpu_obsdata_d2';
NODE_NAME     J9A3 34
 '@BASEBOARD_FAB2_LIB.BASEBOARD_FAB2(SCH_1):PAGE111_I26@MSTR_SCONN.SCONN60_C21100002(CHIPS)':
 'IO34': CDS_PINID='IO34';
NET_NAME
'TP_XDP_CPU_OBSDATA_D3'
 '@BASEBOARD_FAB2_LIB.BASEBOARD_FAB2(SCH_1):TP_XDP_CPU_OBSDATA_D3':
 C_SIGNAL='@baseboard_fab2_lib.baseboard_fab2(sch_1):tp_xdp_cpu_obsdata_d3';
NODE_NAME     J9A3 36
 '@BASEBOARD_FAB2_LIB.BASEBOARD_FAB2(SCH_1):PAGE111_I26@MSTR_SCONN.SCONN60_C21100002(CHIPS)':
 'IO36': CDS_PINID='IO36';
NET_NAME
'TP_XDP_CPU_OBSFN_C0'
 '@BASEBOARD_FAB2_LIB.BASEBOARD_FAB2(SCH_1):TP_XDP_CPU_OBSFN_C0':
 C_SIGNAL='@baseboard_fab2_lib.baseboard_fab2(sch_1):tp_xdp_cpu_obsfn_c0';
NODE_NAME     J9A3 4
 '@BASEBOARD_FAB2_LIB.BASEBOARD_FAB2(SCH_1):PAGE111_I26@MSTR_SCONN.SCONN60_C21100002(CHIPS)':
 'IO4': CDS_PINID='IO4';
NET_NAME
'TP_XDP_OBSDATA_A0'
 '@BASEBOARD_FAB2_LIB.BASEBOARD_FAB2(SCH_1):TP_XDP_OBSDATA_A0':
 C_SIGNAL='@baseboard_fab2_lib.baseboard_fab2(sch_1):tp_xdp_obsdata_a0';
NODE_NAME     J9A3 9
 '@BASEBOARD_FAB2_LIB.BASEBOARD_FAB2(SCH_1):PAGE111_I26@MSTR_SCONN.SCONN60_C21100002(CHIPS)':
 'IO9': CDS_PINID='IO9';
NET_NAME
'TP_XDP_OBSDATA_A1'
 '@BASEBOARD_FAB2_LIB.BASEBOARD_FAB2(SCH_1):TP_XDP_OBSDATA_A1':
 C_SIGNAL='@baseboard_fab2_lib.baseboard_fab2(sch_1):tp_xdp_obsdata_a1';
NODE_NAME     J9A3 11
 '@BASEBOARD_FAB2_LIB.BASEBOARD_FAB2(SCH_1):PAGE111_I26@MSTR_SCONN.SCONN60_C21100002(CHIPS)':
 'IO11': CDS_PINID='IO11';
NET_NAME
'TP_XDP_OBSDATA_A2'
 '@BASEBOARD_FAB2_LIB.BASEBOARD_FAB2(SCH_1):TP_XDP_OBSDATA_A2':
 C_SIGNAL='@baseboard_fab2_lib.baseboard_fab2(sch_1):tp_xdp_obsdata_a2';
NODE_NAME     J9A3 15
 '@BASEBOARD_FAB2_LIB.BASEBOARD_FAB2(SCH_1):PAGE111_I26@MSTR_SCONN.SCONN60_C21100002(CHIPS)':
 'IO15': CDS_PINID='IO15';
NET_NAME
'TP_XDP_OBSDATA_A3'
 '@BASEBOARD_FAB2_LIB.BASEBOARD_FAB2(SCH_1):TP_XDP_OBSDATA_A3':
 C_SIGNAL='@baseboard_fab2_lib.baseboard_fab2(sch_1):tp_xdp_obsdata_a3';
NODE_NAME     J9A3 17
 '@BASEBOARD_FAB2_LIB.BASEBOARD_FAB2(SCH_1):PAGE111_I26@MSTR_SCONN.SCONN60_C21100002(CHIPS)':
 'IO17': CDS_PINID='IO17';
NET_NAME
'TP_XDP_OBSDATA_B0'
 '@BASEBOARD_FAB2_LIB.BASEBOARD_FAB2(SCH_1):TP_XDP_OBSDATA_B0':
 C_SIGNAL='@baseboard_fab2_lib.baseboard_fab2(sch_1):tp_xdp_obsdata_b0';
NODE_NAME     J9A3 27
 '@BASEBOARD_FAB2_LIB.BASEBOARD_FAB2(SCH_1):PAGE111_I26@MSTR_SCONN.SCONN60_C21100002(CHIPS)':
 'IO27': CDS_PINID='IO27';
NET_NAME
'TP_XDP_OBSDATA_B1'
 '@BASEBOARD_FAB2_LIB.BASEBOARD_FAB2(SCH_1):TP_XDP_OBSDATA_B1':
 C_SIGNAL='@baseboard_fab2_lib.baseboard_fab2(sch_1):tp_xdp_obsdata_b1';
NODE_NAME     J9A3 29
 '@BASEBOARD_FAB2_LIB.BASEBOARD_FAB2(SCH_1):PAGE111_I26@MSTR_SCONN.SCONN60_C21100002(CHIPS)':
 'IO29': CDS_PINID='IO29';
NET_NAME
'TP_XDP_OBSDATA_B2'
 '@BASEBOARD_FAB2_LIB.BASEBOARD_FAB2(SCH_1):TP_XDP_OBSDATA_B2':
 C_SIGNAL='@baseboard_fab2_lib.baseboard_fab2(sch_1):tp_xdp_obsdata_b2';
NODE_NAME     J9A3 33
 '@BASEBOARD_FAB2_LIB.BASEBOARD_FAB2(SCH_1):PAGE111_I26@MSTR_SCONN.SCONN60_C21100002(CHIPS)':
 'IO33': CDS_PINID='IO33';
NET_NAME
'TP_XDP_OBSDATA_B3'
 '@BASEBOARD_FAB2_LIB.BASEBOARD_FAB2(SCH_1):TP_XDP_OBSDATA_B3':
 C_SIGNAL='@baseboard_fab2_lib.baseboard_fab2(sch_1):tp_xdp_obsdata_b3';
NODE_NAME     J9A3 35
 '@BASEBOARD_FAB2_LIB.BASEBOARD_FAB2(SCH_1):PAGE111_I26@MSTR_SCONN.SCONN60_C21100002(CHIPS)':
 'IO35': CDS_PINID='IO35';
NET_NAME
'TP_XDP_OBSFN_B0'
 '@BASEBOARD_FAB2_LIB.BASEBOARD_FAB2(SCH_1):TP_XDP_OBSFN_B0':
 C_SIGNAL='@baseboard_fab2_lib.baseboard_fab2(sch_1):tp_xdp_obsfn_b0';
NODE_NAME     J9A3 21
 '@BASEBOARD_FAB2_LIB.BASEBOARD_FAB2(SCH_1):PAGE111_I26@MSTR_SCONN.SCONN60_C21100002(CHIPS)':
 'IO21': CDS_PINID='IO21';
NET_NAME
'TP_XDP_OBSFN_B1'
 '@BASEBOARD_FAB2_LIB.BASEBOARD_FAB2(SCH_1):TP_XDP_OBSFN_B1':
 C_SIGNAL='@baseboard_fab2_lib.baseboard_fab2(sch_1):tp_xdp_obsfn_b1';
NODE_NAME     J9A3 23
 '@BASEBOARD_FAB2_LIB.BASEBOARD_FAB2(SCH_1):PAGE111_I26@MSTR_SCONN.SCONN60_C21100002(CHIPS)':
 'IO23': CDS_PINID='IO23';
NET_NAME
'UART_BMC_RXD5'
 '@BASEBOARD_FAB2_LIB.BASEBOARD_FAB2(SCH_1):UART_BMC_RXD5':
 C_SIGNAL='@baseboard_fab2_lib.baseboard_fab2(sch_1):uart_bmc_rxd5';
NODE_NAME     U9F1 2
 '@BASEBOARD_FAB2_LIB.BASEBOARD_FAB2(SCH_1):PAGE158_I75@MSTR_ANALOG.FSA3357(CHIPS)':
 'B1': CDS_PINID='B1';
NODE_NAME     U8D7 J5
 '@BASEBOARD_FAB2_LIB.BASEBOARD_FAB2(SCH_1):PAGE190_I179@MSTR_MEMORY.LCMXO2_A(CHIPS)':
 'PL10C': CDS_PINID='PL10C';
NODE_NAME     U25W4 K2
 '@BASEBOARD_FAB2_LIB.BASEBOARD_FAB2(SCH_1):PAGE145_I117@W_HDL.AST2520A1-GP-GP(CHIPS)':
 'RXD5': CDS_PINID='RXD5';
NODE_NAME     R9W34 2
 '@BASEBOARD_FAB2_LIB.BASEBOARD_FAB2(SCH_1):PAGE158_I154@MSTR_DISCRETE.RES(CHIPS)':
 'B': CDS_PINID='B';
NET_NAME
'UART_BMC_TXD5'
 '@BASEBOARD_FAB2_LIB.BASEBOARD_FAB2(SCH_1):UART_BMC_TXD5':
 C_SIGNAL='@baseboard_fab2_lib.baseboard_fab2(sch_1):uart_bmc_txd5';
NODE_NAME     U9F2 2
 '@BASEBOARD_FAB2_LIB.BASEBOARD_FAB2(SCH_1):PAGE158_I74@MSTR_ANALOG.FSA3357(CHIPS)':
 'B1': CDS_PINID='B1';
NODE_NAME     U8D7 K6
 '@BASEBOARD_FAB2_LIB.BASEBOARD_FAB2(SCH_1):PAGE190_I179@MSTR_MEMORY.LCMXO2_A(CHIPS)':
 'PL10D': CDS_PINID='PL10D';
NODE_NAME     U25W4 K1
 '@BASEBOARD_FAB2_LIB.BASEBOARD_FAB2(SCH_1):PAGE145_I117@W_HDL.AST2520A1-GP-GP(CHIPS)':
 'TXD5': CDS_PINID='TXD5';
NODE_NAME     R25W116 2
 '@BASEBOARD_FAB2_LIB.BASEBOARD_FAB2(SCH_1):PAGE150_I189@MSTR_DISCRETE.RES(CHIPS)':
 'B': CDS_PINID='B';
NODE_NAME     R25W156 2
 '@BASEBOARD_FAB2_LIB.BASEBOARD_FAB2(SCH_1):PAGE150_I240@MSTR_DISCRETE.RES(CHIPS)':
 'B': CDS_PINID='B';
NET_NAME
'UART_MUX_IN_R'
 '@BASEBOARD_FAB2_LIB.BASEBOARD_FAB2(SCH_1):UART_MUX_IN_R':
 C_SIGNAL='@baseboard_fab2_lib.baseboard_fab2(sch_1):uart_mux_in_r';
NODE_NAME     U9F1 7
 '@BASEBOARD_FAB2_LIB.BASEBOARD_FAB2(SCH_1):PAGE158_I75@MSTR_ANALOG.FSA3357(CHIPS)':
 'A': CDS_PINID='A';
NODE_NAME     R9F25 2
 '@BASEBOARD_FAB2_LIB.BASEBOARD_FAB2(SCH_1):PAGE158_I86@MSTR_DISCRETE.RES(CHIPS)':
 'B': CDS_PINID='B';
NET_NAME
'UART_MUX_OUT_R'
 '@BASEBOARD_FAB2_LIB.BASEBOARD_FAB2(SCH_1):UART_MUX_OUT_R':
 C_SIGNAL='@baseboard_fab2_lib.baseboard_fab2(sch_1):uart_mux_out_r';
NODE_NAME     U9F2 7
 '@BASEBOARD_FAB2_LIB.BASEBOARD_FAB2(SCH_1):PAGE158_I74@MSTR_ANALOG.FSA3357(CHIPS)':
 'A': CDS_PINID='A';
NODE_NAME     R9F27 1
 '@BASEBOARD_FAB2_LIB.BASEBOARD_FAB2(SCH_1):PAGE158_I91@MSTR_DISCRETE.RES(CHIPS)':
 'A': CDS_PINID='A';
NET_NAME
'UPI_CPU0_CPU1_P0P0_DN<0>'
 '@BASEBOARD_FAB2_LIB.BASEBOARD_FAB2(SCH_1):UPI_CPU0_CPU1_P0P0_DN'<0>:
 C_SIGNAL='@baseboard_fab2_lib.baseboard_fab2(sch_1):upi_cpu0_cpu1_p0p0_dn(0)';
NODE_NAME     U5D1 BG4
 '@BASEBOARD_FAB2_LIB.BASEBOARD_FAB2(SCH_1):PAGE33_I86@CHPSET_LIB.SKX_EXT_B(CHIPS)':
 'UPI0_TX_DN'<19>: CDS_PINID='UPI0_TX_DN(19)';
NODE_NAME     U2D1 AB9
 '@BASEBOARD_FAB2_LIB.BASEBOARD_FAB2(SCH_1):PAGE67_I132@CHPSET_LIB.SKX_EXT_B(CHIPS)':
 'UPI0_RX_DP'<0>: CDS_PINID='UPI0_RX_DP(0)';
NET_NAME
'UPI_CPU0_CPU1_P0P0_DN<10>'
 '@BASEBOARD_FAB2_LIB.BASEBOARD_FAB2(SCH_1):UPI_CPU0_CPU1_P0P0_DN'<10>:
 C_SIGNAL='@baseboard_fab2_lib.baseboard_fab2(sch_1):upi_cpu0_cpu1_p0p0_dn(10)';
NODE_NAME     U5D1 AL2
 '@BASEBOARD_FAB2_LIB.BASEBOARD_FAB2(SCH_1):PAGE33_I86@CHPSET_LIB.SKX_EXT_B(CHIPS)':
 'UPI0_TX_DN'<9>: CDS_PINID='UPI0_TX_DN(9)';
NODE_NAME     U2D1 AP7
 '@BASEBOARD_FAB2_LIB.BASEBOARD_FAB2(SCH_1):PAGE67_I132@CHPSET_LIB.SKX_EXT_B(CHIPS)':
 'UPI0_RX_DN'<10>: CDS_PINID='UPI0_RX_DN(10)';
NET_NAME
'UPI_CPU0_CPU1_P0P0_DN<11>'
 '@BASEBOARD_FAB2_LIB.BASEBOARD_FAB2(SCH_1):UPI_CPU0_CPU1_P0P0_DN'<11>:
 C_SIGNAL='@baseboard_fab2_lib.baseboard_fab2(sch_1):upi_cpu0_cpu1_p0p0_dn(11)';
NODE_NAME     U5D1 AH3
 '@BASEBOARD_FAB2_LIB.BASEBOARD_FAB2(SCH_1):PAGE33_I86@CHPSET_LIB.SKX_EXT_B(CHIPS)':
 'UPI0_TX_DN'<8>: CDS_PINID='UPI0_TX_DN(8)';
NODE_NAME     U2D1 AU8
 '@BASEBOARD_FAB2_LIB.BASEBOARD_FAB2(SCH_1):PAGE67_I132@CHPSET_LIB.SKX_EXT_B(CHIPS)':
 'UPI0_RX_DP'<11>: CDS_PINID='UPI0_RX_DP(11)';
NET_NAME
'UPI_CPU0_CPU1_P0P0_DN<12>'
 '@BASEBOARD_FAB2_LIB.BASEBOARD_FAB2(SCH_1):UPI_CPU0_CPU1_P0P0_DN'<12>:
 C_SIGNAL='@baseboard_fab2_lib.baseboard_fab2(sch_1):upi_cpu0_cpu1_p0p0_dn(12)';
NODE_NAME     U5D1 AE2
 '@BASEBOARD_FAB2_LIB.BASEBOARD_FAB2(SCH_1):PAGE33_I86@CHPSET_LIB.SKX_EXT_B(CHIPS)':
 'UPI0_TX_DN'<7>: CDS_PINID='UPI0_TX_DN(7)';
NODE_NAME     U2D1 AU10
 '@BASEBOARD_FAB2_LIB.BASEBOARD_FAB2(SCH_1):PAGE67_I132@CHPSET_LIB.SKX_EXT_B(CHIPS)':
 'UPI0_RX_DN'<12>: CDS_PINID='UPI0_RX_DN(12)';
NET_NAME
'UPI_CPU0_CPU1_P0P0_DN<13>'
 '@BASEBOARD_FAB2_LIB.BASEBOARD_FAB2(SCH_1):UPI_CPU0_CPU1_P0P0_DN'<13>:
 C_SIGNAL='@baseboard_fab2_lib.baseboard_fab2(sch_1):upi_cpu0_cpu1_p0p0_dn(13)';
NODE_NAME     U5D1 AG4
 '@BASEBOARD_FAB2_LIB.BASEBOARD_FAB2(SCH_1):PAGE33_I86@CHPSET_LIB.SKX_EXT_B(CHIPS)':
 'UPI0_TX_DN'<6>: CDS_PINID='UPI0_TX_DN(6)';
NODE_NAME     U2D1 BA8
 '@BASEBOARD_FAB2_LIB.BASEBOARD_FAB2(SCH_1):PAGE67_I132@CHPSET_LIB.SKX_EXT_B(CHIPS)':
 'UPI0_RX_DN'<13>: CDS_PINID='UPI0_RX_DN(13)';
NET_NAME
'UPI_CPU0_CPU1_P0P0_DN<14>'
 '@BASEBOARD_FAB2_LIB.BASEBOARD_FAB2(SCH_1):UPI_CPU0_CPU1_P0P0_DN'<14>:
 C_SIGNAL='@baseboard_fab2_lib.baseboard_fab2(sch_1):upi_cpu0_cpu1_p0p0_dn(14)';
NODE_NAME     U5D1 AC2
 '@BASEBOARD_FAB2_LIB.BASEBOARD_FAB2(SCH_1):PAGE33_I86@CHPSET_LIB.SKX_EXT_B(CHIPS)':
 'UPI0_TX_DN'<5>: CDS_PINID='UPI0_TX_DN(5)';
NODE_NAME     U2D1 BB7
 '@BASEBOARD_FAB2_LIB.BASEBOARD_FAB2(SCH_1):PAGE67_I132@CHPSET_LIB.SKX_EXT_B(CHIPS)':
 'UPI0_RX_DP'<14>: CDS_PINID='UPI0_RX_DP(14)';
NET_NAME
'UPI_CPU0_CPU1_P0P0_DN<15>'
 '@BASEBOARD_FAB2_LIB.BASEBOARD_FAB2(SCH_1):UPI_CPU0_CPU1_P0P0_DN'<15>:
 C_SIGNAL='@baseboard_fab2_lib.baseboard_fab2(sch_1):upi_cpu0_cpu1_p0p0_dn(15)';
NODE_NAME     U5D1 AB3
 '@BASEBOARD_FAB2_LIB.BASEBOARD_FAB2(SCH_1):PAGE33_I86@CHPSET_LIB.SKX_EXT_B(CHIPS)':
 'UPI0_TX_DN'<4>: CDS_PINID='UPI0_TX_DN(4)';
NODE_NAME     U2D1 BD7
 '@BASEBOARD_FAB2_LIB.BASEBOARD_FAB2(SCH_1):PAGE67_I132@CHPSET_LIB.SKX_EXT_B(CHIPS)':
 'UPI0_RX_DN'<15>: CDS_PINID='UPI0_RX_DN(15)';
NET_NAME
'UPI_CPU0_CPU1_P0P0_DN<16>'
 '@BASEBOARD_FAB2_LIB.BASEBOARD_FAB2(SCH_1):UPI_CPU0_CPU1_P0P0_DN'<16>:
 C_SIGNAL='@baseboard_fab2_lib.baseboard_fab2(sch_1):upi_cpu0_cpu1_p0p0_dn(16)';
NODE_NAME     U5D1 Y1
 '@BASEBOARD_FAB2_LIB.BASEBOARD_FAB2(SCH_1):PAGE33_I86@CHPSET_LIB.SKX_EXT_B(CHIPS)':
 'UPI0_TX_DN'<3>: CDS_PINID='UPI0_TX_DN(3)';
NODE_NAME     U2D1 AW8
 '@BASEBOARD_FAB2_LIB.BASEBOARD_FAB2(SCH_1):PAGE67_I132@CHPSET_LIB.SKX_EXT_B(CHIPS)':
 'UPI0_RX_DN'<16>: CDS_PINID='UPI0_RX_DN(16)';
NET_NAME
'UPI_CPU0_CPU1_P0P0_DN<17>'
 '@BASEBOARD_FAB2_LIB.BASEBOARD_FAB2(SCH_1):UPI_CPU0_CPU1_P0P0_DN'<17>:
 C_SIGNAL='@baseboard_fab2_lib.baseboard_fab2(sch_1):upi_cpu0_cpu1_p0p0_dn(17)';
NODE_NAME     U5D1 V3
 '@BASEBOARD_FAB2_LIB.BASEBOARD_FAB2(SCH_1):PAGE33_I86@CHPSET_LIB.SKX_EXT_B(CHIPS)':
 'UPI0_TX_DN'<2>: CDS_PINID='UPI0_TX_DN(2)';
NODE_NAME     U2D1 AY9
 '@BASEBOARD_FAB2_LIB.BASEBOARD_FAB2(SCH_1):PAGE67_I132@CHPSET_LIB.SKX_EXT_B(CHIPS)':
 'UPI0_RX_DN'<17>: CDS_PINID='UPI0_RX_DN(17)';
NET_NAME
'UPI_CPU0_CPU1_P0P0_DN<18>'
 '@BASEBOARD_FAB2_LIB.BASEBOARD_FAB2(SCH_1):UPI_CPU0_CPU1_P0P0_DN'<18>:
 C_SIGNAL='@baseboard_fab2_lib.baseboard_fab2(sch_1):upi_cpu0_cpu1_p0p0_dn(18)';
NODE_NAME     U5D1 P1
 '@BASEBOARD_FAB2_LIB.BASEBOARD_FAB2(SCH_1):PAGE33_I86@CHPSET_LIB.SKX_EXT_B(CHIPS)':
 'UPI0_TX_DN'<1>: CDS_PINID='UPI0_TX_DN(1)';
NODE_NAME     U2D1 BC10
 '@BASEBOARD_FAB2_LIB.BASEBOARD_FAB2(SCH_1):PAGE67_I132@CHPSET_LIB.SKX_EXT_B(CHIPS)':
 'UPI0_RX_DP'<18>: CDS_PINID='UPI0_RX_DP(18)';
NET_NAME
'UPI_CPU0_CPU1_P0P0_DN<19>'
 '@BASEBOARD_FAB2_LIB.BASEBOARD_FAB2(SCH_1):UPI_CPU0_CPU1_P0P0_DN'<19>:
 C_SIGNAL='@baseboard_fab2_lib.baseboard_fab2(sch_1):upi_cpu0_cpu1_p0p0_dn(19)';
NODE_NAME     U5D1 N2
 '@BASEBOARD_FAB2_LIB.BASEBOARD_FAB2(SCH_1):PAGE33_I86@CHPSET_LIB.SKX_EXT_B(CHIPS)':
 'UPI0_TX_DN'<0>: CDS_PINID='UPI0_TX_DN(0)';
NODE_NAME     U2D1 BA10
 '@BASEBOARD_FAB2_LIB.BASEBOARD_FAB2(SCH_1):PAGE67_I132@CHPSET_LIB.SKX_EXT_B(CHIPS)':
 'UPI0_RX_DP'<19>: CDS_PINID='UPI0_RX_DP(19)';
NET_NAME
'UPI_CPU0_CPU1_P0P0_DN<1>'
 '@BASEBOARD_FAB2_LIB.BASEBOARD_FAB2(SCH_1):UPI_CPU0_CPU1_P0P0_DN'<1>:
 C_SIGNAL='@baseboard_fab2_lib.baseboard_fab2(sch_1):upi_cpu0_cpu1_p0p0_dn(1)';
NODE_NAME     U5D1 BF3
 '@BASEBOARD_FAB2_LIB.BASEBOARD_FAB2(SCH_1):PAGE33_I86@CHPSET_LIB.SKX_EXT_B(CHIPS)':
 'UPI0_TX_DN'<18>: CDS_PINID='UPI0_TX_DN(18)';
NODE_NAME     U2D1 AA8
 '@BASEBOARD_FAB2_LIB.BASEBOARD_FAB2(SCH_1):PAGE67_I132@CHPSET_LIB.SKX_EXT_B(CHIPS)':
 'UPI0_RX_DN'<1>: CDS_PINID='UPI0_RX_DN(1)';
NET_NAME
'UPI_CPU0_CPU1_P0P0_DN<2>'
 '@BASEBOARD_FAB2_LIB.BASEBOARD_FAB2(SCH_1):UPI_CPU0_CPU1_P0P0_DN'<2>:
 C_SIGNAL='@baseboard_fab2_lib.baseboard_fab2(sch_1):upi_cpu0_cpu1_p0p0_dn(2)';
NODE_NAME     U5D1 BB3
 '@BASEBOARD_FAB2_LIB.BASEBOARD_FAB2(SCH_1):PAGE33_I86@CHPSET_LIB.SKX_EXT_B(CHIPS)':
 'UPI0_TX_DN'<17>: CDS_PINID='UPI0_TX_DN(17)';
NODE_NAME     U2D1 AB7
 '@BASEBOARD_FAB2_LIB.BASEBOARD_FAB2(SCH_1):PAGE67_I132@CHPSET_LIB.SKX_EXT_B(CHIPS)':
 'UPI0_RX_DN'<2>: CDS_PINID='UPI0_RX_DN(2)';
NET_NAME
'UPI_CPU0_CPU1_P0P0_DN<3>'
 '@BASEBOARD_FAB2_LIB.BASEBOARD_FAB2(SCH_1):UPI_CPU0_CPU1_P0P0_DN'<3>:
 C_SIGNAL='@baseboard_fab2_lib.baseboard_fab2(sch_1):upi_cpu0_cpu1_p0p0_dn(3)';
NODE_NAME     U5D1 BA4
 '@BASEBOARD_FAB2_LIB.BASEBOARD_FAB2(SCH_1):PAGE33_I86@CHPSET_LIB.SKX_EXT_B(CHIPS)':
 'UPI0_TX_DN'<16>: CDS_PINID='UPI0_TX_DN(16)';
NODE_NAME     U2D1 AC6
 '@BASEBOARD_FAB2_LIB.BASEBOARD_FAB2(SCH_1):PAGE67_I132@CHPSET_LIB.SKX_EXT_B(CHIPS)':
 'UPI0_RX_DP'<3>: CDS_PINID='UPI0_RX_DP(3)';
NET_NAME
'UPI_CPU0_CPU1_P0P0_DN<4>'
 '@BASEBOARD_FAB2_LIB.BASEBOARD_FAB2(SCH_1):UPI_CPU0_CPU1_P0P0_DN'<4>:
 C_SIGNAL='@baseboard_fab2_lib.baseboard_fab2(sch_1):upi_cpu0_cpu1_p0p0_dn(4)';
NODE_NAME     U5D1 AV5
 '@BASEBOARD_FAB2_LIB.BASEBOARD_FAB2(SCH_1):PAGE33_I86@CHPSET_LIB.SKX_EXT_B(CHIPS)':
 'UPI0_TX_DN'<15>: CDS_PINID='UPI0_TX_DN(15)';
NODE_NAME     U2D1 AG6
 '@BASEBOARD_FAB2_LIB.BASEBOARD_FAB2(SCH_1):PAGE67_I132@CHPSET_LIB.SKX_EXT_B(CHIPS)':
 'UPI0_RX_DP'<4>: CDS_PINID='UPI0_RX_DP(4)';
NET_NAME
'UPI_CPU0_CPU1_P0P0_DN<5>'
 '@BASEBOARD_FAB2_LIB.BASEBOARD_FAB2(SCH_1):UPI_CPU0_CPU1_P0P0_DN'<5>:
 C_SIGNAL='@baseboard_fab2_lib.baseboard_fab2(sch_1):upi_cpu0_cpu1_p0p0_dn(5)';
NODE_NAME     U5D1 AU4
 '@BASEBOARD_FAB2_LIB.BASEBOARD_FAB2(SCH_1):PAGE33_I86@CHPSET_LIB.SKX_EXT_B(CHIPS)':
 'UPI0_TX_DN'<14>: CDS_PINID='UPI0_TX_DN(14)';
NODE_NAME     U2D1 AF7
 '@BASEBOARD_FAB2_LIB.BASEBOARD_FAB2(SCH_1):PAGE67_I132@CHPSET_LIB.SKX_EXT_B(CHIPS)':
 'UPI0_RX_DP'<5>: CDS_PINID='UPI0_RX_DP(5)';
NET_NAME
'UPI_CPU0_CPU1_P0P0_DN<6>'
 '@BASEBOARD_FAB2_LIB.BASEBOARD_FAB2(SCH_1):UPI_CPU0_CPU1_P0P0_DN'<6>:
 C_SIGNAL='@baseboard_fab2_lib.baseboard_fab2(sch_1):upi_cpu0_cpu1_p0p0_dn(6)';
NODE_NAME     U5D1 AT3
 '@BASEBOARD_FAB2_LIB.BASEBOARD_FAB2(SCH_1):PAGE33_I86@CHPSET_LIB.SKX_EXT_B(CHIPS)':
 'UPI0_TX_DN'<13>: CDS_PINID='UPI0_TX_DN(13)';
NODE_NAME     U2D1 AH7
 '@BASEBOARD_FAB2_LIB.BASEBOARD_FAB2(SCH_1):PAGE67_I132@CHPSET_LIB.SKX_EXT_B(CHIPS)':
 'UPI0_RX_DP'<6>: CDS_PINID='UPI0_RX_DP(6)';
NET_NAME
'UPI_CPU0_CPU1_P0P0_DN<7>'
 '@BASEBOARD_FAB2_LIB.BASEBOARD_FAB2(SCH_1):UPI_CPU0_CPU1_P0P0_DN'<7>:
 C_SIGNAL='@baseboard_fab2_lib.baseboard_fab2(sch_1):upi_cpu0_cpu1_p0p0_dn(7)';
NODE_NAME     U5D1 AT1
 '@BASEBOARD_FAB2_LIB.BASEBOARD_FAB2(SCH_1):PAGE33_I86@CHPSET_LIB.SKX_EXT_B(CHIPS)':
 'UPI0_TX_DN'<12>: CDS_PINID='UPI0_TX_DN(12)';
NODE_NAME     U2D1 AK5
 '@BASEBOARD_FAB2_LIB.BASEBOARD_FAB2(SCH_1):PAGE67_I132@CHPSET_LIB.SKX_EXT_B(CHIPS)':
 'UPI0_RX_DP'<7>: CDS_PINID='UPI0_RX_DP(7)';
NET_NAME
'UPI_CPU0_CPU1_P0P0_DN<8>'
 '@BASEBOARD_FAB2_LIB.BASEBOARD_FAB2(SCH_1):UPI_CPU0_CPU1_P0P0_DN'<8>:
 C_SIGNAL='@baseboard_fab2_lib.baseboard_fab2(sch_1):upi_cpu0_cpu1_p0p0_dn(8)';
NODE_NAME     U5D1 AN4
 '@BASEBOARD_FAB2_LIB.BASEBOARD_FAB2(SCH_1):PAGE33_I86@CHPSET_LIB.SKX_EXT_B(CHIPS)':
 'UPI0_TX_DN'<11>: CDS_PINID='UPI0_TX_DN(11)';
NODE_NAME     U2D1 AM7
 '@BASEBOARD_FAB2_LIB.BASEBOARD_FAB2(SCH_1):PAGE67_I132@CHPSET_LIB.SKX_EXT_B(CHIPS)':
 'UPI0_RX_DP'<8>: CDS_PINID='UPI0_RX_DP(8)';
NET_NAME
'UPI_CPU0_CPU1_P0P0_DN<9>'
 '@BASEBOARD_FAB2_LIB.BASEBOARD_FAB2(SCH_1):UPI_CPU0_CPU1_P0P0_DN'<9>:
 C_SIGNAL='@baseboard_fab2_lib.baseboard_fab2(sch_1):upi_cpu0_cpu1_p0p0_dn(9)';
NODE_NAME     U5D1 AM3
 '@BASEBOARD_FAB2_LIB.BASEBOARD_FAB2(SCH_1):PAGE33_I86@CHPSET_LIB.SKX_EXT_B(CHIPS)':
 'UPI0_TX_DN'<10>: CDS_PINID='UPI0_TX_DN(10)';
NODE_NAME     U2D1 AL8
 '@BASEBOARD_FAB2_LIB.BASEBOARD_FAB2(SCH_1):PAGE67_I132@CHPSET_LIB.SKX_EXT_B(CHIPS)':
 'UPI0_RX_DP'<9>: CDS_PINID='UPI0_RX_DP(9)';
NET_NAME
'UPI_CPU0_CPU1_P0P0_DP<0>'
 '@BASEBOARD_FAB2_LIB.BASEBOARD_FAB2(SCH_1):UPI_CPU0_CPU1_P0P0_DP'<0>:
 C_SIGNAL='@baseboard_fab2_lib.baseboard_fab2(sch_1):upi_cpu0_cpu1_p0p0_dp(0)';
NODE_NAME     U5D1 BH3
 '@BASEBOARD_FAB2_LIB.BASEBOARD_FAB2(SCH_1):PAGE33_I86@CHPSET_LIB.SKX_EXT_B(CHIPS)':
 'UPI0_TX_DP'<19>: CDS_PINID='UPI0_TX_DP(19)';
NODE_NAME     U2D1 AC10
 '@BASEBOARD_FAB2_LIB.BASEBOARD_FAB2(SCH_1):PAGE67_I132@CHPSET_LIB.SKX_EXT_B(CHIPS)':
 'UPI0_RX_DN'<0>: CDS_PINID='UPI0_RX_DN(0)';
NET_NAME
'UPI_CPU0_CPU1_P0P0_DP<10>'
 '@BASEBOARD_FAB2_LIB.BASEBOARD_FAB2(SCH_1):UPI_CPU0_CPU1_P0P0_DP'<10>:
 C_SIGNAL='@baseboard_fab2_lib.baseboard_fab2(sch_1):upi_cpu0_cpu1_p0p0_dp(10)';
NODE_NAME     U5D1 AK1
 '@BASEBOARD_FAB2_LIB.BASEBOARD_FAB2(SCH_1):PAGE33_I86@CHPSET_LIB.SKX_EXT_B(CHIPS)':
 'UPI0_TX_DP'<9>: CDS_PINID='UPI0_TX_DP(9)';
NODE_NAME     U2D1 AN8
 '@BASEBOARD_FAB2_LIB.BASEBOARD_FAB2(SCH_1):PAGE67_I132@CHPSET_LIB.SKX_EXT_B(CHIPS)':
 'UPI0_RX_DP'<10>: CDS_PINID='UPI0_RX_DP(10)';
NET_NAME
'UPI_CPU0_CPU1_P0P0_DP<11>'
 '@BASEBOARD_FAB2_LIB.BASEBOARD_FAB2(SCH_1):UPI_CPU0_CPU1_P0P0_DP'<11>:
 C_SIGNAL='@baseboard_fab2_lib.baseboard_fab2(sch_1):upi_cpu0_cpu1_p0p0_dp(11)';
NODE_NAME     U5D1 AJ2
 '@BASEBOARD_FAB2_LIB.BASEBOARD_FAB2(SCH_1):PAGE33_I86@CHPSET_LIB.SKX_EXT_B(CHIPS)':
 'UPI0_TX_DP'<8>: CDS_PINID='UPI0_TX_DP(8)';
NODE_NAME     U2D1 AR8
 '@BASEBOARD_FAB2_LIB.BASEBOARD_FAB2(SCH_1):PAGE67_I132@CHPSET_LIB.SKX_EXT_B(CHIPS)':
 'UPI0_RX_DN'<11>: CDS_PINID='UPI0_RX_DN(11)';
NET_NAME
'UPI_CPU0_CPU1_P0P0_DP<12>'
 '@BASEBOARD_FAB2_LIB.BASEBOARD_FAB2(SCH_1):UPI_CPU0_CPU1_P0P0_DP'<12>:
 C_SIGNAL='@baseboard_fab2_lib.baseboard_fab2(sch_1):upi_cpu0_cpu1_p0p0_dp(12)';
NODE_NAME     U5D1 AG2
 '@BASEBOARD_FAB2_LIB.BASEBOARD_FAB2(SCH_1):PAGE33_I86@CHPSET_LIB.SKX_EXT_B(CHIPS)':
 'UPI0_TX_DP'<7>: CDS_PINID='UPI0_TX_DP(7)';
NODE_NAME     U2D1 AT9
 '@BASEBOARD_FAB2_LIB.BASEBOARD_FAB2(SCH_1):PAGE67_I132@CHPSET_LIB.SKX_EXT_B(CHIPS)':
 'UPI0_RX_DP'<12>: CDS_PINID='UPI0_RX_DP(12)';
NET_NAME
'UPI_CPU0_CPU1_P0P0_DP<13>'
 '@BASEBOARD_FAB2_LIB.BASEBOARD_FAB2(SCH_1):UPI_CPU0_CPU1_P0P0_DP'<13>:
 C_SIGNAL='@baseboard_fab2_lib.baseboard_fab2(sch_1):upi_cpu0_cpu1_p0p0_dp(13)';
NODE_NAME     U5D1 AF3
 '@BASEBOARD_FAB2_LIB.BASEBOARD_FAB2(SCH_1):PAGE33_I86@CHPSET_LIB.SKX_EXT_B(CHIPS)':
 'UPI0_TX_DP'<6>: CDS_PINID='UPI0_TX_DP(6)';
NODE_NAME     U2D1 AY7
 '@BASEBOARD_FAB2_LIB.BASEBOARD_FAB2(SCH_1):PAGE67_I132@CHPSET_LIB.SKX_EXT_B(CHIPS)':
 'UPI0_RX_DP'<13>: CDS_PINID='UPI0_RX_DP(13)';
NET_NAME
'UPI_CPU0_CPU1_P0P0_DP<14>'
 '@BASEBOARD_FAB2_LIB.BASEBOARD_FAB2(SCH_1):UPI_CPU0_CPU1_P0P0_DP'<14>:
 C_SIGNAL='@baseboard_fab2_lib.baseboard_fab2(sch_1):upi_cpu0_cpu1_p0p0_dp(14)';
NODE_NAME     U5D1 AD1
 '@BASEBOARD_FAB2_LIB.BASEBOARD_FAB2(SCH_1):PAGE33_I86@CHPSET_LIB.SKX_EXT_B(CHIPS)':
 'UPI0_TX_DP'<5>: CDS_PINID='UPI0_TX_DP(5)';
NODE_NAME     U2D1 BC6
 '@BASEBOARD_FAB2_LIB.BASEBOARD_FAB2(SCH_1):PAGE67_I132@CHPSET_LIB.SKX_EXT_B(CHIPS)':
 'UPI0_RX_DN'<14>: CDS_PINID='UPI0_RX_DN(14)';
NET_NAME
'UPI_CPU0_CPU1_P0P0_DP<15>'
 '@BASEBOARD_FAB2_LIB.BASEBOARD_FAB2(SCH_1):UPI_CPU0_CPU1_P0P0_DP'<15>:
 C_SIGNAL='@baseboard_fab2_lib.baseboard_fab2(sch_1):upi_cpu0_cpu1_p0p0_dp(15)';
NODE_NAME     U5D1 AA2
 '@BASEBOARD_FAB2_LIB.BASEBOARD_FAB2(SCH_1):PAGE33_I86@CHPSET_LIB.SKX_EXT_B(CHIPS)':
 'UPI0_TX_DP'<4>: CDS_PINID='UPI0_TX_DP(4)';
NODE_NAME     U2D1 BF7
 '@BASEBOARD_FAB2_LIB.BASEBOARD_FAB2(SCH_1):PAGE67_I132@CHPSET_LIB.SKX_EXT_B(CHIPS)':
 'UPI0_RX_DP'<15>: CDS_PINID='UPI0_RX_DP(15)';
NET_NAME
'UPI_CPU0_CPU1_P0P0_DP<16>'
 '@BASEBOARD_FAB2_LIB.BASEBOARD_FAB2(SCH_1):UPI_CPU0_CPU1_P0P0_DP'<16>:
 C_SIGNAL='@baseboard_fab2_lib.baseboard_fab2(sch_1):upi_cpu0_cpu1_p0p0_dp(16)';
NODE_NAME     U5D1 W2
 '@BASEBOARD_FAB2_LIB.BASEBOARD_FAB2(SCH_1):PAGE33_I86@CHPSET_LIB.SKX_EXT_B(CHIPS)':
 'UPI0_TX_DP'<3>: CDS_PINID='UPI0_TX_DP(3)';
NODE_NAME     U2D1 AV9
 '@BASEBOARD_FAB2_LIB.BASEBOARD_FAB2(SCH_1):PAGE67_I132@CHPSET_LIB.SKX_EXT_B(CHIPS)':
 'UPI0_RX_DP'<16>: CDS_PINID='UPI0_RX_DP(16)';
NET_NAME
'UPI_CPU0_CPU1_P0P0_DP<17>'
 '@BASEBOARD_FAB2_LIB.BASEBOARD_FAB2(SCH_1):UPI_CPU0_CPU1_P0P0_DP'<17>:
 C_SIGNAL='@baseboard_fab2_lib.baseboard_fab2(sch_1):upi_cpu0_cpu1_p0p0_dp(17)';
NODE_NAME     U5D1 Y3
 '@BASEBOARD_FAB2_LIB.BASEBOARD_FAB2(SCH_1):PAGE33_I86@CHPSET_LIB.SKX_EXT_B(CHIPS)':
 'UPI0_TX_DP'<2>: CDS_PINID='UPI0_TX_DP(2)';
NODE_NAME     U2D1 BB9
 '@BASEBOARD_FAB2_LIB.BASEBOARD_FAB2(SCH_1):PAGE67_I132@CHPSET_LIB.SKX_EXT_B(CHIPS)':
 'UPI0_RX_DP'<17>: CDS_PINID='UPI0_RX_DP(17)';
NET_NAME
'UPI_CPU0_CPU1_P0P0_DP<18>'
 '@BASEBOARD_FAB2_LIB.BASEBOARD_FAB2(SCH_1):UPI_CPU0_CPU1_P0P0_DP'<18>:
 C_SIGNAL='@baseboard_fab2_lib.baseboard_fab2(sch_1):upi_cpu0_cpu1_p0p0_dp(18)';
NODE_NAME     U5D1 T1
 '@BASEBOARD_FAB2_LIB.BASEBOARD_FAB2(SCH_1):PAGE33_I86@CHPSET_LIB.SKX_EXT_B(CHIPS)':
 'UPI0_TX_DP'<1>: CDS_PINID='UPI0_TX_DP(1)';
NODE_NAME     U2D1 BD9
 '@BASEBOARD_FAB2_LIB.BASEBOARD_FAB2(SCH_1):PAGE67_I132@CHPSET_LIB.SKX_EXT_B(CHIPS)':
 'UPI0_RX_DN'<18>: CDS_PINID='UPI0_RX_DN(18)';
NET_NAME
'UPI_CPU0_CPU1_P0P0_DP<19>'
 '@BASEBOARD_FAB2_LIB.BASEBOARD_FAB2(SCH_1):UPI_CPU0_CPU1_P0P0_DP'<19>:
 C_SIGNAL='@baseboard_fab2_lib.baseboard_fab2(sch_1):upi_cpu0_cpu1_p0p0_dp(19)';
NODE_NAME     U5D1 M1
 '@BASEBOARD_FAB2_LIB.BASEBOARD_FAB2(SCH_1):PAGE33_I86@CHPSET_LIB.SKX_EXT_B(CHIPS)':
 'UPI0_TX_DP'<0>: CDS_PINID='UPI0_TX_DP(0)';
NODE_NAME     U2D1 BB11
 '@BASEBOARD_FAB2_LIB.BASEBOARD_FAB2(SCH_1):PAGE67_I132@CHPSET_LIB.SKX_EXT_B(CHIPS)':
 'UPI0_RX_DN'<19>: CDS_PINID='UPI0_RX_DN(19)';
NET_NAME
'UPI_CPU0_CPU1_P0P0_DP<1>'
 '@BASEBOARD_FAB2_LIB.BASEBOARD_FAB2(SCH_1):UPI_CPU0_CPU1_P0P0_DP'<1>:
 C_SIGNAL='@baseboard_fab2_lib.baseboard_fab2(sch_1):upi_cpu0_cpu1_p0p0_dp(1)';
NODE_NAME     U5D1 BD3
 '@BASEBOARD_FAB2_LIB.BASEBOARD_FAB2(SCH_1):PAGE33_I86@CHPSET_LIB.SKX_EXT_B(CHIPS)':
 'UPI0_TX_DP'<18>: CDS_PINID='UPI0_TX_DP(18)';
NODE_NAME     U2D1 AC8
 '@BASEBOARD_FAB2_LIB.BASEBOARD_FAB2(SCH_1):PAGE67_I132@CHPSET_LIB.SKX_EXT_B(CHIPS)':
 'UPI0_RX_DP'<1>: CDS_PINID='UPI0_RX_DP(1)';
NET_NAME
'UPI_CPU0_CPU1_P0P0_DP<2>'
 '@BASEBOARD_FAB2_LIB.BASEBOARD_FAB2(SCH_1):UPI_CPU0_CPU1_P0P0_DP'<2>:
 C_SIGNAL='@baseboard_fab2_lib.baseboard_fab2(sch_1):upi_cpu0_cpu1_p0p0_dp(2)';
NODE_NAME     U5D1 BC2
 '@BASEBOARD_FAB2_LIB.BASEBOARD_FAB2(SCH_1):PAGE33_I86@CHPSET_LIB.SKX_EXT_B(CHIPS)':
 'UPI0_TX_DP'<17>: CDS_PINID='UPI0_TX_DP(17)';
NODE_NAME     U2D1 AA6
 '@BASEBOARD_FAB2_LIB.BASEBOARD_FAB2(SCH_1):PAGE67_I132@CHPSET_LIB.SKX_EXT_B(CHIPS)':
 'UPI0_RX_DP'<2>: CDS_PINID='UPI0_RX_DP(2)';
NET_NAME
'UPI_CPU0_CPU1_P0P0_DP<3>'
 '@BASEBOARD_FAB2_LIB.BASEBOARD_FAB2(SCH_1):UPI_CPU0_CPU1_P0P0_DP'<3>:
 C_SIGNAL='@baseboard_fab2_lib.baseboard_fab2(sch_1):upi_cpu0_cpu1_p0p0_dp(3)';
NODE_NAME     U5D1 AY3
 '@BASEBOARD_FAB2_LIB.BASEBOARD_FAB2(SCH_1):PAGE33_I86@CHPSET_LIB.SKX_EXT_B(CHIPS)':
 'UPI0_TX_DP'<16>: CDS_PINID='UPI0_TX_DP(16)';
NODE_NAME     U2D1 AD5
 '@BASEBOARD_FAB2_LIB.BASEBOARD_FAB2(SCH_1):PAGE67_I132@CHPSET_LIB.SKX_EXT_B(CHIPS)':
 'UPI0_RX_DN'<3>: CDS_PINID='UPI0_RX_DN(3)';
NET_NAME
'UPI_CPU0_CPU1_P0P0_DP<4>'
 '@BASEBOARD_FAB2_LIB.BASEBOARD_FAB2(SCH_1):UPI_CPU0_CPU1_P0P0_DP'<4>:
 C_SIGNAL='@baseboard_fab2_lib.baseboard_fab2(sch_1):upi_cpu0_cpu1_p0p0_dp(4)';
NODE_NAME     U5D1 AW4
 '@BASEBOARD_FAB2_LIB.BASEBOARD_FAB2(SCH_1):PAGE33_I86@CHPSET_LIB.SKX_EXT_B(CHIPS)':
 'UPI0_TX_DP'<15>: CDS_PINID='UPI0_TX_DP(15)';
NODE_NAME     U2D1 AE6
 '@BASEBOARD_FAB2_LIB.BASEBOARD_FAB2(SCH_1):PAGE67_I132@CHPSET_LIB.SKX_EXT_B(CHIPS)':
 'UPI0_RX_DN'<4>: CDS_PINID='UPI0_RX_DN(4)';
NET_NAME
'UPI_CPU0_CPU1_P0P0_DP<5>'
 '@BASEBOARD_FAB2_LIB.BASEBOARD_FAB2(SCH_1):UPI_CPU0_CPU1_P0P0_DP'<5>:
 C_SIGNAL='@baseboard_fab2_lib.baseboard_fab2(sch_1):upi_cpu0_cpu1_p0p0_dp(5)';
NODE_NAME     U5D1 AR4
 '@BASEBOARD_FAB2_LIB.BASEBOARD_FAB2(SCH_1):PAGE33_I86@CHPSET_LIB.SKX_EXT_B(CHIPS)':
 'UPI0_TX_DP'<14>: CDS_PINID='UPI0_TX_DP(14)';
NODE_NAME     U2D1 AG8
 '@BASEBOARD_FAB2_LIB.BASEBOARD_FAB2(SCH_1):PAGE67_I132@CHPSET_LIB.SKX_EXT_B(CHIPS)':
 'UPI0_RX_DN'<5>: CDS_PINID='UPI0_RX_DN(5)';
NET_NAME
'UPI_CPU0_CPU1_P0P0_DP<6>'
 '@BASEBOARD_FAB2_LIB.BASEBOARD_FAB2(SCH_1):UPI_CPU0_CPU1_P0P0_DP'<6>:
 C_SIGNAL='@baseboard_fab2_lib.baseboard_fab2(sch_1):upi_cpu0_cpu1_p0p0_dp(6)';
NODE_NAME     U5D1 AR2
 '@BASEBOARD_FAB2_LIB.BASEBOARD_FAB2(SCH_1):PAGE33_I86@CHPSET_LIB.SKX_EXT_B(CHIPS)':
 'UPI0_TX_DP'<13>: CDS_PINID='UPI0_TX_DP(13)';
NODE_NAME     U2D1 AJ6
 '@BASEBOARD_FAB2_LIB.BASEBOARD_FAB2(SCH_1):PAGE67_I132@CHPSET_LIB.SKX_EXT_B(CHIPS)':
 'UPI0_RX_DN'<6>: CDS_PINID='UPI0_RX_DN(6)';
NET_NAME
'UPI_CPU0_CPU1_P0P0_DP<7>'
 '@BASEBOARD_FAB2_LIB.BASEBOARD_FAB2(SCH_1):UPI_CPU0_CPU1_P0P0_DP'<7>:
 C_SIGNAL='@baseboard_fab2_lib.baseboard_fab2(sch_1):upi_cpu0_cpu1_p0p0_dp(7)';
NODE_NAME     U5D1 AP1
 '@BASEBOARD_FAB2_LIB.BASEBOARD_FAB2(SCH_1):PAGE33_I86@CHPSET_LIB.SKX_EXT_B(CHIPS)':
 'UPI0_TX_DP'<12>: CDS_PINID='UPI0_TX_DP(12)';
NODE_NAME     U2D1 AL6
 '@BASEBOARD_FAB2_LIB.BASEBOARD_FAB2(SCH_1):PAGE67_I132@CHPSET_LIB.SKX_EXT_B(CHIPS)':
 'UPI0_RX_DN'<7>: CDS_PINID='UPI0_RX_DN(7)';
NET_NAME
'UPI_CPU0_CPU1_P0P0_DP<8>'
 '@BASEBOARD_FAB2_LIB.BASEBOARD_FAB2(SCH_1):UPI_CPU0_CPU1_P0P0_DP'<8>:
 C_SIGNAL='@baseboard_fab2_lib.baseboard_fab2(sch_1):upi_cpu0_cpu1_p0p0_dp(8)';
NODE_NAME     U5D1 AP3
 '@BASEBOARD_FAB2_LIB.BASEBOARD_FAB2(SCH_1):PAGE33_I86@CHPSET_LIB.SKX_EXT_B(CHIPS)':
 'UPI0_TX_DP'<11>: CDS_PINID='UPI0_TX_DP(11)';
NODE_NAME     U2D1 AK7
 '@BASEBOARD_FAB2_LIB.BASEBOARD_FAB2(SCH_1):PAGE67_I132@CHPSET_LIB.SKX_EXT_B(CHIPS)':
 'UPI0_RX_DN'<8>: CDS_PINID='UPI0_RX_DN(8)';
NET_NAME
'UPI_CPU0_CPU1_P0P0_DP<9>'
 '@BASEBOARD_FAB2_LIB.BASEBOARD_FAB2(SCH_1):UPI_CPU0_CPU1_P0P0_DP'<9>:
 C_SIGNAL='@baseboard_fab2_lib.baseboard_fab2(sch_1):upi_cpu0_cpu1_p0p0_dp(9)';
NODE_NAME     U5D1 AK3
 '@BASEBOARD_FAB2_LIB.BASEBOARD_FAB2(SCH_1):PAGE33_I86@CHPSET_LIB.SKX_EXT_B(CHIPS)':
 'UPI0_TX_DP'<10>: CDS_PINID='UPI0_TX_DP(10)';
NODE_NAME     U2D1 AM9
 '@BASEBOARD_FAB2_LIB.BASEBOARD_FAB2(SCH_1):PAGE67_I132@CHPSET_LIB.SKX_EXT_B(CHIPS)':
 'UPI0_RX_DN'<9>: CDS_PINID='UPI0_RX_DN(9)';
NET_NAME
'UPI_CPU0_CPU1_P1P1_DN<0>'
 '@BASEBOARD_FAB2_LIB.BASEBOARD_FAB2(SCH_1):UPI_CPU0_CPU1_P1P1_DN'<0>:
 C_SIGNAL='@baseboard_fab2_lib.baseboard_fab2(sch_1):upi_cpu0_cpu1_p1p1_dn(0)';
NODE_NAME     U5D1 H21
 '@BASEBOARD_FAB2_LIB.BASEBOARD_FAB2(SCH_1):PAGE34_I86@CHPSET_LIB.SKX_EXT_B(CHIPS)':
 'UPI1_TX_DN'<19>: CDS_PINID='UPI1_TX_DN(19)';
NODE_NAME     U2D1 R6
 '@BASEBOARD_FAB2_LIB.BASEBOARD_FAB2(SCH_1):PAGE68_I125@CHPSET_LIB.SKX_EXT_B(CHIPS)':
 'UPI1_RX_DP'<0>: CDS_PINID='UPI1_RX_DP(0)';
NET_NAME
'UPI_CPU0_CPU1_P1P1_DN<10>'
 '@BASEBOARD_FAB2_LIB.BASEBOARD_FAB2(SCH_1):UPI_CPU0_CPU1_P1P1_DN'<10>:
 C_SIGNAL='@baseboard_fab2_lib.baseboard_fab2(sch_1):upi_cpu0_cpu1_p1p1_dn(10)';
NODE_NAME     U5D1 G10
 '@BASEBOARD_FAB2_LIB.BASEBOARD_FAB2(SCH_1):PAGE34_I86@CHPSET_LIB.SKX_EXT_B(CHIPS)':
 'UPI1_TX_DN'<9>: CDS_PINID='UPI1_TX_DN(9)';
NODE_NAME     U2D1 R16
 '@BASEBOARD_FAB2_LIB.BASEBOARD_FAB2(SCH_1):PAGE68_I125@CHPSET_LIB.SKX_EXT_B(CHIPS)':
 'UPI1_RX_DN'<10>: CDS_PINID='UPI1_RX_DN(10)';
NET_NAME
'UPI_CPU0_CPU1_P1P1_DN<11>'
 '@BASEBOARD_FAB2_LIB.BASEBOARD_FAB2(SCH_1):UPI_CPU0_CPU1_P1P1_DN'<11>:
 C_SIGNAL='@baseboard_fab2_lib.baseboard_fab2(sch_1):upi_cpu0_cpu1_p1p1_dn(11)';
NODE_NAME     U5D1 F11
 '@BASEBOARD_FAB2_LIB.BASEBOARD_FAB2(SCH_1):PAGE34_I86@CHPSET_LIB.SKX_EXT_B(CHIPS)':
 'UPI1_TX_DN'<8>: CDS_PINID='UPI1_TX_DN(8)';
NODE_NAME     U2D1 N16
 '@BASEBOARD_FAB2_LIB.BASEBOARD_FAB2(SCH_1):PAGE68_I125@CHPSET_LIB.SKX_EXT_B(CHIPS)':
 'UPI1_RX_DP'<11>: CDS_PINID='UPI1_RX_DP(11)';
NET_NAME
'UPI_CPU0_CPU1_P1P1_DN<12>'
 '@BASEBOARD_FAB2_LIB.BASEBOARD_FAB2(SCH_1):UPI_CPU0_CPU1_P1P1_DN'<12>:
 C_SIGNAL='@baseboard_fab2_lib.baseboard_fab2(sch_1):upi_cpu0_cpu1_p1p1_dn(12)';
NODE_NAME     U5D1 D9
 '@BASEBOARD_FAB2_LIB.BASEBOARD_FAB2(SCH_1):PAGE34_I86@CHPSET_LIB.SKX_EXT_B(CHIPS)':
 'UPI1_TX_DN'<7>: CDS_PINID='UPI1_TX_DN(7)';
NODE_NAME     U2D1 W16
 '@BASEBOARD_FAB2_LIB.BASEBOARD_FAB2(SCH_1):PAGE68_I125@CHPSET_LIB.SKX_EXT_B(CHIPS)':
 'UPI1_RX_DP'<12>: CDS_PINID='UPI1_RX_DP(12)';
NET_NAME
'UPI_CPU0_CPU1_P1P1_DN<13>'
 '@BASEBOARD_FAB2_LIB.BASEBOARD_FAB2(SCH_1):UPI_CPU0_CPU1_P1P1_DN'<13>:
 C_SIGNAL='@baseboard_fab2_lib.baseboard_fab2(sch_1):upi_cpu0_cpu1_p1p1_dn(13)';
NODE_NAME     U5D1 K9
 '@BASEBOARD_FAB2_LIB.BASEBOARD_FAB2(SCH_1):PAGE34_I86@CHPSET_LIB.SKX_EXT_B(CHIPS)':
 'UPI1_TX_DN'<6>: CDS_PINID='UPI1_TX_DN(6)';
NODE_NAME     U2D1 V17
 '@BASEBOARD_FAB2_LIB.BASEBOARD_FAB2(SCH_1):PAGE68_I125@CHPSET_LIB.SKX_EXT_B(CHIPS)':
 'UPI1_RX_DP'<13>: CDS_PINID='UPI1_RX_DP(13)';
NET_NAME
'UPI_CPU0_CPU1_P1P1_DN<14>'
 '@BASEBOARD_FAB2_LIB.BASEBOARD_FAB2(SCH_1):UPI_CPU0_CPU1_P1P1_DN'<14>:
 C_SIGNAL='@baseboard_fab2_lib.baseboard_fab2(sch_1):upi_cpu0_cpu1_p1p1_dn(14)';
NODE_NAME     U5D1 H7
 '@BASEBOARD_FAB2_LIB.BASEBOARD_FAB2(SCH_1):PAGE34_I86@CHPSET_LIB.SKX_EXT_B(CHIPS)':
 'UPI1_TX_DN'<5>: CDS_PINID='UPI1_TX_DN(5)';
NODE_NAME     U2D1 R20
 '@BASEBOARD_FAB2_LIB.BASEBOARD_FAB2(SCH_1):PAGE68_I125@CHPSET_LIB.SKX_EXT_B(CHIPS)':
 'UPI1_RX_DN'<14>: CDS_PINID='UPI1_RX_DN(14)';
NET_NAME
'UPI_CPU0_CPU1_P1P1_DN<15>'
 '@BASEBOARD_FAB2_LIB.BASEBOARD_FAB2(SCH_1):UPI_CPU0_CPU1_P1P1_DN'<15>:
 C_SIGNAL='@baseboard_fab2_lib.baseboard_fab2(sch_1):upi_cpu0_cpu1_p1p1_dn(15)';
NODE_NAME     U5D1 G6
 '@BASEBOARD_FAB2_LIB.BASEBOARD_FAB2(SCH_1):PAGE34_I86@CHPSET_LIB.SKX_EXT_B(CHIPS)':
 'UPI1_TX_DN'<4>: CDS_PINID='UPI1_TX_DN(4)';
NODE_NAME     U2D1 U18
 '@BASEBOARD_FAB2_LIB.BASEBOARD_FAB2(SCH_1):PAGE68_I125@CHPSET_LIB.SKX_EXT_B(CHIPS)':
 'UPI1_RX_DN'<15>: CDS_PINID='UPI1_RX_DN(15)';
NET_NAME
'UPI_CPU0_CPU1_P1P1_DN<16>'
 '@BASEBOARD_FAB2_LIB.BASEBOARD_FAB2(SCH_1):UPI_CPU0_CPU1_P1P1_DN'<16>:
 C_SIGNAL='@baseboard_fab2_lib.baseboard_fab2(sch_1):upi_cpu0_cpu1_p1p1_dn(16)';
NODE_NAME     U5D1 J6
 '@BASEBOARD_FAB2_LIB.BASEBOARD_FAB2(SCH_1):PAGE34_I86@CHPSET_LIB.SKX_EXT_B(CHIPS)':
 'UPI1_TX_DN'<3>: CDS_PINID='UPI1_TX_DN(3)';
NODE_NAME     U2D1 P21
 '@BASEBOARD_FAB2_LIB.BASEBOARD_FAB2(SCH_1):PAGE68_I125@CHPSET_LIB.SKX_EXT_B(CHIPS)':
 'UPI1_RX_DN'<16>: CDS_PINID='UPI1_RX_DN(16)';
NET_NAME
'UPI_CPU0_CPU1_P1P1_DN<17>'
 '@BASEBOARD_FAB2_LIB.BASEBOARD_FAB2(SCH_1):UPI_CPU0_CPU1_P1P1_DN'<17>:
 C_SIGNAL='@baseboard_fab2_lib.baseboard_fab2(sch_1):upi_cpu0_cpu1_p1p1_dn(17)';
NODE_NAME     U5D1 K5
 '@BASEBOARD_FAB2_LIB.BASEBOARD_FAB2(SCH_1):PAGE34_I86@CHPSET_LIB.SKX_EXT_B(CHIPS)':
 'UPI1_TX_DN'<2>: CDS_PINID='UPI1_TX_DN(2)';
NODE_NAME     U2D1 V19
 '@BASEBOARD_FAB2_LIB.BASEBOARD_FAB2(SCH_1):PAGE68_I125@CHPSET_LIB.SKX_EXT_B(CHIPS)':
 'UPI1_RX_DN'<17>: CDS_PINID='UPI1_RX_DN(17)';
NET_NAME
'UPI_CPU0_CPU1_P1P1_DN<18>'
 '@BASEBOARD_FAB2_LIB.BASEBOARD_FAB2(SCH_1):UPI_CPU0_CPU1_P1P1_DN'<18>:
 C_SIGNAL='@baseboard_fab2_lib.baseboard_fab2(sch_1):upi_cpu0_cpu1_p1p1_dn(18)';
NODE_NAME     U5D1 L4
 '@BASEBOARD_FAB2_LIB.BASEBOARD_FAB2(SCH_1):PAGE34_I86@CHPSET_LIB.SKX_EXT_B(CHIPS)':
 'UPI1_TX_DN'<1>: CDS_PINID='UPI1_TX_DN(1)';
NODE_NAME     U2D1 W20
 '@BASEBOARD_FAB2_LIB.BASEBOARD_FAB2(SCH_1):PAGE68_I125@CHPSET_LIB.SKX_EXT_B(CHIPS)':
 'UPI1_RX_DP'<18>: CDS_PINID='UPI1_RX_DP(18)';
NET_NAME
'UPI_CPU0_CPU1_P1P1_DN<19>'
 '@BASEBOARD_FAB2_LIB.BASEBOARD_FAB2(SCH_1):UPI_CPU0_CPU1_P1P1_DN'<19>:
 C_SIGNAL='@baseboard_fab2_lib.baseboard_fab2(sch_1):upi_cpu0_cpu1_p1p1_dn(19)';
NODE_NAME     U5D1 M3
 '@BASEBOARD_FAB2_LIB.BASEBOARD_FAB2(SCH_1):PAGE34_I86@CHPSET_LIB.SKX_EXT_B(CHIPS)':
 'UPI1_TX_DN'<0>: CDS_PINID='UPI1_TX_DN(0)';
NODE_NAME     U2D1 AA20
 '@BASEBOARD_FAB2_LIB.BASEBOARD_FAB2(SCH_1):PAGE68_I125@CHPSET_LIB.SKX_EXT_B(CHIPS)':
 'UPI1_RX_DP'<19>: CDS_PINID='UPI1_RX_DP(19)';
NET_NAME
'UPI_CPU0_CPU1_P1P1_DN<1>'
 '@BASEBOARD_FAB2_LIB.BASEBOARD_FAB2(SCH_1):UPI_CPU0_CPU1_P1P1_DN'<1>:
 C_SIGNAL='@baseboard_fab2_lib.baseboard_fab2(sch_1):upi_cpu0_cpu1_p1p1_dn(1)';
NODE_NAME     U5D1 F21
 '@BASEBOARD_FAB2_LIB.BASEBOARD_FAB2(SCH_1):PAGE34_I86@CHPSET_LIB.SKX_EXT_B(CHIPS)':
 'UPI1_TX_DN'<18>: CDS_PINID='UPI1_TX_DN(18)';
NODE_NAME     U2D1 P7
 '@BASEBOARD_FAB2_LIB.BASEBOARD_FAB2(SCH_1):PAGE68_I125@CHPSET_LIB.SKX_EXT_B(CHIPS)':
 'UPI1_RX_DN'<1>: CDS_PINID='UPI1_RX_DN(1)';
NET_NAME
'UPI_CPU0_CPU1_P1P1_DN<2>'
 '@BASEBOARD_FAB2_LIB.BASEBOARD_FAB2(SCH_1):UPI_CPU0_CPU1_P1P1_DN'<2>:
 C_SIGNAL='@baseboard_fab2_lib.baseboard_fab2(sch_1):upi_cpu0_cpu1_p1p1_dn(2)';
NODE_NAME     U5D1 J20
 '@BASEBOARD_FAB2_LIB.BASEBOARD_FAB2(SCH_1):PAGE34_I86@CHPSET_LIB.SKX_EXT_B(CHIPS)':
 'UPI1_TX_DN'<17>: CDS_PINID='UPI1_TX_DN(17)';
NODE_NAME     U2D1 V7
 '@BASEBOARD_FAB2_LIB.BASEBOARD_FAB2(SCH_1):PAGE68_I125@CHPSET_LIB.SKX_EXT_B(CHIPS)':
 'UPI1_RX_DN'<2>: CDS_PINID='UPI1_RX_DN(2)';
NET_NAME
'UPI_CPU0_CPU1_P1P1_DN<3>'
 '@BASEBOARD_FAB2_LIB.BASEBOARD_FAB2(SCH_1):UPI_CPU0_CPU1_P1P1_DN'<3>:
 C_SIGNAL='@baseboard_fab2_lib.baseboard_fab2(sch_1):upi_cpu0_cpu1_p1p1_dn(3)';
NODE_NAME     U5D1 G18
 '@BASEBOARD_FAB2_LIB.BASEBOARD_FAB2(SCH_1):PAGE34_I86@CHPSET_LIB.SKX_EXT_B(CHIPS)':
 'UPI1_TX_DN'<16>: CDS_PINID='UPI1_TX_DN(16)';
NODE_NAME     U2D1 T9
 '@BASEBOARD_FAB2_LIB.BASEBOARD_FAB2(SCH_1):PAGE68_I125@CHPSET_LIB.SKX_EXT_B(CHIPS)':
 'UPI1_RX_DN'<3>: CDS_PINID='UPI1_RX_DN(3)';
NET_NAME
'UPI_CPU0_CPU1_P1P1_DN<4>'
 '@BASEBOARD_FAB2_LIB.BASEBOARD_FAB2(SCH_1):UPI_CPU0_CPU1_P1P1_DN'<4>:
 C_SIGNAL='@baseboard_fab2_lib.baseboard_fab2(sch_1):upi_cpu0_cpu1_p1p1_dn(4)';
NODE_NAME     U5D1 K19
 '@BASEBOARD_FAB2_LIB.BASEBOARD_FAB2(SCH_1):PAGE34_I86@CHPSET_LIB.SKX_EXT_B(CHIPS)':
 'UPI1_TX_DN'<15>: CDS_PINID='UPI1_TX_DN(15)';
NODE_NAME     U2D1 P9
 '@BASEBOARD_FAB2_LIB.BASEBOARD_FAB2(SCH_1):PAGE68_I125@CHPSET_LIB.SKX_EXT_B(CHIPS)':
 'UPI1_RX_DN'<4>: CDS_PINID='UPI1_RX_DN(4)';
NET_NAME
'UPI_CPU0_CPU1_P1P1_DN<5>'
 '@BASEBOARD_FAB2_LIB.BASEBOARD_FAB2(SCH_1):UPI_CPU0_CPU1_P1P1_DN'<5>:
 C_SIGNAL='@baseboard_fab2_lib.baseboard_fab2(sch_1):upi_cpu0_cpu1_p1p1_dn(5)';
NODE_NAME     U5D1 H17
 '@BASEBOARD_FAB2_LIB.BASEBOARD_FAB2(SCH_1):PAGE34_I86@CHPSET_LIB.SKX_EXT_B(CHIPS)':
 'UPI1_TX_DN'<14>: CDS_PINID='UPI1_TX_DN(14)';
NODE_NAME     U2D1 R10
 '@BASEBOARD_FAB2_LIB.BASEBOARD_FAB2(SCH_1):PAGE68_I125@CHPSET_LIB.SKX_EXT_B(CHIPS)':
 'UPI1_RX_DN'<5>: CDS_PINID='UPI1_RX_DN(5)';
NET_NAME
'UPI_CPU0_CPU1_P1P1_DN<6>'
 '@BASEBOARD_FAB2_LIB.BASEBOARD_FAB2(SCH_1):UPI_CPU0_CPU1_P1P1_DN'<6>:
 C_SIGNAL='@baseboard_fab2_lib.baseboard_fab2(sch_1):upi_cpu0_cpu1_p1p1_dn(6)';
NODE_NAME     U5D1 F15
 '@BASEBOARD_FAB2_LIB.BASEBOARD_FAB2(SCH_1):PAGE34_I86@CHPSET_LIB.SKX_EXT_B(CHIPS)':
 'UPI1_TX_DN'<13>: CDS_PINID='UPI1_TX_DN(13)';
NODE_NAME     U2D1 U12
 '@BASEBOARD_FAB2_LIB.BASEBOARD_FAB2(SCH_1):PAGE68_I125@CHPSET_LIB.SKX_EXT_B(CHIPS)':
 'UPI1_RX_DN'<6>: CDS_PINID='UPI1_RX_DN(6)';
NET_NAME
'UPI_CPU0_CPU1_P1P1_DN<7>'
 '@BASEBOARD_FAB2_LIB.BASEBOARD_FAB2(SCH_1):UPI_CPU0_CPU1_P1P1_DN'<7>:
 C_SIGNAL='@baseboard_fab2_lib.baseboard_fab2(sch_1):upi_cpu0_cpu1_p1p1_dn(7)';
NODE_NAME     U5D1 D15
 '@BASEBOARD_FAB2_LIB.BASEBOARD_FAB2(SCH_1):PAGE34_I86@CHPSET_LIB.SKX_EXT_B(CHIPS)':
 'UPI1_TX_DN'<12>: CDS_PINID='UPI1_TX_DN(12)';
NODE_NAME     U2D1 L12
 '@BASEBOARD_FAB2_LIB.BASEBOARD_FAB2(SCH_1):PAGE68_I125@CHPSET_LIB.SKX_EXT_B(CHIPS)':
 'UPI1_RX_DN'<7>: CDS_PINID='UPI1_RX_DN(7)';
NET_NAME
'UPI_CPU0_CPU1_P1P1_DN<8>'
 '@BASEBOARD_FAB2_LIB.BASEBOARD_FAB2(SCH_1):UPI_CPU0_CPU1_P1P1_DN'<8>:
 C_SIGNAL='@baseboard_fab2_lib.baseboard_fab2(sch_1):upi_cpu0_cpu1_p1p1_dn(8)';
NODE_NAME     U5D1 G14
 '@BASEBOARD_FAB2_LIB.BASEBOARD_FAB2(SCH_1):PAGE34_I86@CHPSET_LIB.SKX_EXT_B(CHIPS)':
 'UPI1_TX_DN'<11>: CDS_PINID='UPI1_TX_DN(11)';
NODE_NAME     U2D1 M13
 '@BASEBOARD_FAB2_LIB.BASEBOARD_FAB2(SCH_1):PAGE68_I125@CHPSET_LIB.SKX_EXT_B(CHIPS)':
 'UPI1_RX_DP'<8>: CDS_PINID='UPI1_RX_DP(8)';
NET_NAME
'UPI_CPU0_CPU1_P1P1_DN<9>'
 '@BASEBOARD_FAB2_LIB.BASEBOARD_FAB2(SCH_1):UPI_CPU0_CPU1_P1P1_DN'<9>:
 C_SIGNAL='@baseboard_fab2_lib.baseboard_fab2(sch_1):upi_cpu0_cpu1_p1p1_dn(9)';
NODE_NAME     U5D1 E12
 '@BASEBOARD_FAB2_LIB.BASEBOARD_FAB2(SCH_1):PAGE34_I86@CHPSET_LIB.SKX_EXT_B(CHIPS)':
 'UPI1_TX_DN'<10>: CDS_PINID='UPI1_TX_DN(10)';
NODE_NAME     U2D1 R12
 '@BASEBOARD_FAB2_LIB.BASEBOARD_FAB2(SCH_1):PAGE68_I125@CHPSET_LIB.SKX_EXT_B(CHIPS)':
 'UPI1_RX_DN'<9>: CDS_PINID='UPI1_RX_DN(9)';
NET_NAME
'UPI_CPU0_CPU1_P1P1_DP<0>'
 '@BASEBOARD_FAB2_LIB.BASEBOARD_FAB2(SCH_1):UPI_CPU0_CPU1_P1P1_DP'<0>:
 C_SIGNAL='@baseboard_fab2_lib.baseboard_fab2(sch_1):upi_cpu0_cpu1_p1p1_dp(0)';
NODE_NAME     U5D1 K21
 '@BASEBOARD_FAB2_LIB.BASEBOARD_FAB2(SCH_1):PAGE34_I86@CHPSET_LIB.SKX_EXT_B(CHIPS)':
 'UPI1_TX_DP'<19>: CDS_PINID='UPI1_TX_DP(19)';
NODE_NAME     U2D1 T5
 '@BASEBOARD_FAB2_LIB.BASEBOARD_FAB2(SCH_1):PAGE68_I125@CHPSET_LIB.SKX_EXT_B(CHIPS)':
 'UPI1_RX_DN'<0>: CDS_PINID='UPI1_RX_DN(0)';
NET_NAME
'UPI_CPU0_CPU1_P1P1_DP<10>'
 '@BASEBOARD_FAB2_LIB.BASEBOARD_FAB2(SCH_1):UPI_CPU0_CPU1_P1P1_DP'<10>:
 C_SIGNAL='@baseboard_fab2_lib.baseboard_fab2(sch_1):upi_cpu0_cpu1_p1p1_dp(10)';
NODE_NAME     U5D1 H9
 '@BASEBOARD_FAB2_LIB.BASEBOARD_FAB2(SCH_1):PAGE34_I86@CHPSET_LIB.SKX_EXT_B(CHIPS)':
 'UPI1_TX_DP'<9>: CDS_PINID='UPI1_TX_DP(9)';
NODE_NAME     U2D1 T15
 '@BASEBOARD_FAB2_LIB.BASEBOARD_FAB2(SCH_1):PAGE68_I125@CHPSET_LIB.SKX_EXT_B(CHIPS)':
 'UPI1_RX_DP'<10>: CDS_PINID='UPI1_RX_DP(10)';
NET_NAME
'UPI_CPU0_CPU1_P1P1_DP<11>'
 '@BASEBOARD_FAB2_LIB.BASEBOARD_FAB2(SCH_1):UPI_CPU0_CPU1_P1P1_DP'<11>:
 C_SIGNAL='@baseboard_fab2_lib.baseboard_fab2(sch_1):upi_cpu0_cpu1_p1p1_dp(11)';
NODE_NAME     U5D1 E10
 '@BASEBOARD_FAB2_LIB.BASEBOARD_FAB2(SCH_1):PAGE34_I86@CHPSET_LIB.SKX_EXT_B(CHIPS)':
 'UPI1_TX_DP'<8>: CDS_PINID='UPI1_TX_DP(8)';
NODE_NAME     U2D1 P17
 '@BASEBOARD_FAB2_LIB.BASEBOARD_FAB2(SCH_1):PAGE68_I125@CHPSET_LIB.SKX_EXT_B(CHIPS)':
 'UPI1_RX_DN'<11>: CDS_PINID='UPI1_RX_DN(11)';
NET_NAME
'UPI_CPU0_CPU1_P1P1_DP<12>'
 '@BASEBOARD_FAB2_LIB.BASEBOARD_FAB2(SCH_1):UPI_CPU0_CPU1_P1P1_DP'<12>:
 C_SIGNAL='@baseboard_fab2_lib.baseboard_fab2(sch_1):upi_cpu0_cpu1_p1p1_dp(12)';
NODE_NAME     U5D1 F9
 '@BASEBOARD_FAB2_LIB.BASEBOARD_FAB2(SCH_1):PAGE34_I86@CHPSET_LIB.SKX_EXT_B(CHIPS)':
 'UPI1_TX_DP'<7>: CDS_PINID='UPI1_TX_DP(7)';
NODE_NAME     U2D1 U16
 '@BASEBOARD_FAB2_LIB.BASEBOARD_FAB2(SCH_1):PAGE68_I125@CHPSET_LIB.SKX_EXT_B(CHIPS)':
 'UPI1_RX_DN'<12>: CDS_PINID='UPI1_RX_DN(12)';
NET_NAME
'UPI_CPU0_CPU1_P1P1_DP<13>'
 '@BASEBOARD_FAB2_LIB.BASEBOARD_FAB2(SCH_1):UPI_CPU0_CPU1_P1P1_DP'<13>:
 C_SIGNAL='@baseboard_fab2_lib.baseboard_fab2(sch_1):upi_cpu0_cpu1_p1p1_dp(13)';
NODE_NAME     U5D1 J8
 '@BASEBOARD_FAB2_LIB.BASEBOARD_FAB2(SCH_1):PAGE34_I86@CHPSET_LIB.SKX_EXT_B(CHIPS)':
 'UPI1_TX_DP'<6>: CDS_PINID='UPI1_TX_DP(6)';
NODE_NAME     U2D1 W18
 '@BASEBOARD_FAB2_LIB.BASEBOARD_FAB2(SCH_1):PAGE68_I125@CHPSET_LIB.SKX_EXT_B(CHIPS)':
 'UPI1_RX_DN'<13>: CDS_PINID='UPI1_RX_DN(13)';
NET_NAME
'UPI_CPU0_CPU1_P1P1_DP<14>'
 '@BASEBOARD_FAB2_LIB.BASEBOARD_FAB2(SCH_1):UPI_CPU0_CPU1_P1P1_DP'<14>:
 C_SIGNAL='@baseboard_fab2_lib.baseboard_fab2(sch_1):upi_cpu0_cpu1_p1p1_dp(14)';
NODE_NAME     U5D1 K7
 '@BASEBOARD_FAB2_LIB.BASEBOARD_FAB2(SCH_1):PAGE34_I86@CHPSET_LIB.SKX_EXT_B(CHIPS)':
 'UPI1_TX_DP'<5>: CDS_PINID='UPI1_TX_DP(5)';
NODE_NAME     U2D1 P19
 '@BASEBOARD_FAB2_LIB.BASEBOARD_FAB2(SCH_1):PAGE68_I125@CHPSET_LIB.SKX_EXT_B(CHIPS)':
 'UPI1_RX_DP'<14>: CDS_PINID='UPI1_RX_DP(14)';
NET_NAME
'UPI_CPU0_CPU1_P1P1_DP<15>'
 '@BASEBOARD_FAB2_LIB.BASEBOARD_FAB2(SCH_1):UPI_CPU0_CPU1_P1P1_DP'<15>:
 C_SIGNAL='@baseboard_fab2_lib.baseboard_fab2(sch_1):upi_cpu0_cpu1_p1p1_dp(15)';
NODE_NAME     U5D1 F7
 '@BASEBOARD_FAB2_LIB.BASEBOARD_FAB2(SCH_1):PAGE34_I86@CHPSET_LIB.SKX_EXT_B(CHIPS)':
 'UPI1_TX_DP'<4>: CDS_PINID='UPI1_TX_DP(4)';
NODE_NAME     U2D1 T19
 '@BASEBOARD_FAB2_LIB.BASEBOARD_FAB2(SCH_1):PAGE68_I125@CHPSET_LIB.SKX_EXT_B(CHIPS)':
 'UPI1_RX_DP'<15>: CDS_PINID='UPI1_RX_DP(15)';
NET_NAME
'UPI_CPU0_CPU1_P1P1_DP<16>'
 '@BASEBOARD_FAB2_LIB.BASEBOARD_FAB2(SCH_1):UPI_CPU0_CPU1_P1P1_DP'<16>:
 C_SIGNAL='@baseboard_fab2_lib.baseboard_fab2(sch_1):upi_cpu0_cpu1_p1p1_dp(16)';
NODE_NAME     U5D1 H5
 '@BASEBOARD_FAB2_LIB.BASEBOARD_FAB2(SCH_1):PAGE34_I86@CHPSET_LIB.SKX_EXT_B(CHIPS)':
 'UPI1_TX_DP'<3>: CDS_PINID='UPI1_TX_DP(3)';
NODE_NAME     U2D1 T21
 '@BASEBOARD_FAB2_LIB.BASEBOARD_FAB2(SCH_1):PAGE68_I125@CHPSET_LIB.SKX_EXT_B(CHIPS)':
 'UPI1_RX_DP'<16>: CDS_PINID='UPI1_RX_DP(16)';
NET_NAME
'UPI_CPU0_CPU1_P1P1_DP<17>'
 '@BASEBOARD_FAB2_LIB.BASEBOARD_FAB2(SCH_1):UPI_CPU0_CPU1_P1P1_DP'<17>:
 C_SIGNAL='@baseboard_fab2_lib.baseboard_fab2(sch_1):upi_cpu0_cpu1_p1p1_dp(17)';
NODE_NAME     U5D1 M5
 '@BASEBOARD_FAB2_LIB.BASEBOARD_FAB2(SCH_1):PAGE34_I86@CHPSET_LIB.SKX_EXT_B(CHIPS)':
 'UPI1_TX_DP'<2>: CDS_PINID='UPI1_TX_DP(2)';
NODE_NAME     U2D1 Y19
 '@BASEBOARD_FAB2_LIB.BASEBOARD_FAB2(SCH_1):PAGE68_I125@CHPSET_LIB.SKX_EXT_B(CHIPS)':
 'UPI1_RX_DP'<17>: CDS_PINID='UPI1_RX_DP(17)';
NET_NAME
'UPI_CPU0_CPU1_P1P1_DP<18>'
 '@BASEBOARD_FAB2_LIB.BASEBOARD_FAB2(SCH_1):UPI_CPU0_CPU1_P1P1_DP'<18>:
 C_SIGNAL='@baseboard_fab2_lib.baseboard_fab2(sch_1):upi_cpu0_cpu1_p1p1_dp(18)';
NODE_NAME     U5D1 K3
 '@BASEBOARD_FAB2_LIB.BASEBOARD_FAB2(SCH_1):PAGE34_I86@CHPSET_LIB.SKX_EXT_B(CHIPS)':
 'UPI1_TX_DP'<1>: CDS_PINID='UPI1_TX_DP(1)';
NODE_NAME     U2D1 Y21
 '@BASEBOARD_FAB2_LIB.BASEBOARD_FAB2(SCH_1):PAGE68_I125@CHPSET_LIB.SKX_EXT_B(CHIPS)':
 'UPI1_RX_DN'<18>: CDS_PINID='UPI1_RX_DN(18)';
NET_NAME
'UPI_CPU0_CPU1_P1P1_DP<19>'
 '@BASEBOARD_FAB2_LIB.BASEBOARD_FAB2(SCH_1):UPI_CPU0_CPU1_P1P1_DP'<19>:
 C_SIGNAL='@baseboard_fab2_lib.baseboard_fab2(sch_1):upi_cpu0_cpu1_p1p1_dp(19)';
NODE_NAME     U5D1 P3
 '@BASEBOARD_FAB2_LIB.BASEBOARD_FAB2(SCH_1):PAGE34_I86@CHPSET_LIB.SKX_EXT_B(CHIPS)':
 'UPI1_TX_DP'<0>: CDS_PINID='UPI1_TX_DP(0)';
NODE_NAME     U2D1 AB19
 '@BASEBOARD_FAB2_LIB.BASEBOARD_FAB2(SCH_1):PAGE68_I125@CHPSET_LIB.SKX_EXT_B(CHIPS)':
 'UPI1_RX_DN'<19>: CDS_PINID='UPI1_RX_DN(19)';
NET_NAME
'UPI_CPU0_CPU1_P1P1_DP<1>'
 '@BASEBOARD_FAB2_LIB.BASEBOARD_FAB2(SCH_1):UPI_CPU0_CPU1_P1P1_DP'<1>:
 C_SIGNAL='@baseboard_fab2_lib.baseboard_fab2(sch_1):upi_cpu0_cpu1_p1p1_dp(1)';
NODE_NAME     U5D1 G20
 '@BASEBOARD_FAB2_LIB.BASEBOARD_FAB2(SCH_1):PAGE34_I86@CHPSET_LIB.SKX_EXT_B(CHIPS)':
 'UPI1_TX_DP'<18>: CDS_PINID='UPI1_TX_DP(18)';
NODE_NAME     U2D1 T7
 '@BASEBOARD_FAB2_LIB.BASEBOARD_FAB2(SCH_1):PAGE68_I125@CHPSET_LIB.SKX_EXT_B(CHIPS)':
 'UPI1_RX_DP'<1>: CDS_PINID='UPI1_RX_DP(1)';
NET_NAME
'UPI_CPU0_CPU1_P1P1_DP<2>'
 '@BASEBOARD_FAB2_LIB.BASEBOARD_FAB2(SCH_1):UPI_CPU0_CPU1_P1P1_DP'<2>:
 C_SIGNAL='@baseboard_fab2_lib.baseboard_fab2(sch_1):upi_cpu0_cpu1_p1p1_dp(2)';
NODE_NAME     U5D1 H19
 '@BASEBOARD_FAB2_LIB.BASEBOARD_FAB2(SCH_1):PAGE34_I86@CHPSET_LIB.SKX_EXT_B(CHIPS)':
 'UPI1_TX_DP'<17>: CDS_PINID='UPI1_TX_DP(17)';
NODE_NAME     U2D1 U8
 '@BASEBOARD_FAB2_LIB.BASEBOARD_FAB2(SCH_1):PAGE68_I125@CHPSET_LIB.SKX_EXT_B(CHIPS)':
 'UPI1_RX_DP'<2>: CDS_PINID='UPI1_RX_DP(2)';
NET_NAME
'UPI_CPU0_CPU1_P1P1_DP<3>'
 '@BASEBOARD_FAB2_LIB.BASEBOARD_FAB2(SCH_1):UPI_CPU0_CPU1_P1P1_DP'<3>:
 C_SIGNAL='@baseboard_fab2_lib.baseboard_fab2(sch_1):upi_cpu0_cpu1_p1p1_dp(3)';
NODE_NAME     U5D1 J18
 '@BASEBOARD_FAB2_LIB.BASEBOARD_FAB2(SCH_1):PAGE34_I86@CHPSET_LIB.SKX_EXT_B(CHIPS)':
 'UPI1_TX_DP'<16>: CDS_PINID='UPI1_TX_DP(16)';
NODE_NAME     U2D1 R8
 '@BASEBOARD_FAB2_LIB.BASEBOARD_FAB2(SCH_1):PAGE68_I125@CHPSET_LIB.SKX_EXT_B(CHIPS)':
 'UPI1_RX_DP'<3>: CDS_PINID='UPI1_RX_DP(3)';
NET_NAME
'UPI_CPU0_CPU1_P1P1_DP<4>'
 '@BASEBOARD_FAB2_LIB.BASEBOARD_FAB2(SCH_1):UPI_CPU0_CPU1_P1P1_DP'<4>:
 C_SIGNAL='@baseboard_fab2_lib.baseboard_fab2(sch_1):upi_cpu0_cpu1_p1p1_dp(4)';
NODE_NAME     U5D1 L18
 '@BASEBOARD_FAB2_LIB.BASEBOARD_FAB2(SCH_1):PAGE34_I86@CHPSET_LIB.SKX_EXT_B(CHIPS)':
 'UPI1_TX_DP'<15>: CDS_PINID='UPI1_TX_DP(15)';
NODE_NAME     U2D1 N10
 '@BASEBOARD_FAB2_LIB.BASEBOARD_FAB2(SCH_1):PAGE68_I125@CHPSET_LIB.SKX_EXT_B(CHIPS)':
 'UPI1_RX_DP'<4>: CDS_PINID='UPI1_RX_DP(4)';
NET_NAME
'UPI_CPU0_CPU1_P1P1_DP<5>'
 '@BASEBOARD_FAB2_LIB.BASEBOARD_FAB2(SCH_1):UPI_CPU0_CPU1_P1P1_DP'<5>:
 C_SIGNAL='@baseboard_fab2_lib.baseboard_fab2(sch_1):upi_cpu0_cpu1_p1p1_dp(5)';
NODE_NAME     U5D1 G16
 '@BASEBOARD_FAB2_LIB.BASEBOARD_FAB2(SCH_1):PAGE34_I86@CHPSET_LIB.SKX_EXT_B(CHIPS)':
 'UPI1_TX_DP'<14>: CDS_PINID='UPI1_TX_DP(14)';
NODE_NAME     U2D1 U10
 '@BASEBOARD_FAB2_LIB.BASEBOARD_FAB2(SCH_1):PAGE68_I125@CHPSET_LIB.SKX_EXT_B(CHIPS)':
 'UPI1_RX_DP'<5>: CDS_PINID='UPI1_RX_DP(5)';
NET_NAME
'UPI_CPU0_CPU1_P1P1_DP<6>'
 '@BASEBOARD_FAB2_LIB.BASEBOARD_FAB2(SCH_1):UPI_CPU0_CPU1_P1P1_DP'<6>:
 C_SIGNAL='@baseboard_fab2_lib.baseboard_fab2(sch_1):upi_cpu0_cpu1_p1p1_dp(6)';
NODE_NAME     U5D1 H15
 '@BASEBOARD_FAB2_LIB.BASEBOARD_FAB2(SCH_1):PAGE34_I86@CHPSET_LIB.SKX_EXT_B(CHIPS)':
 'UPI1_TX_DP'<13>: CDS_PINID='UPI1_TX_DP(13)';
NODE_NAME     U2D1 T11
 '@BASEBOARD_FAB2_LIB.BASEBOARD_FAB2(SCH_1):PAGE68_I125@CHPSET_LIB.SKX_EXT_B(CHIPS)':
 'UPI1_RX_DP'<6>: CDS_PINID='UPI1_RX_DP(6)';
NET_NAME
'UPI_CPU0_CPU1_P1P1_DP<7>'
 '@BASEBOARD_FAB2_LIB.BASEBOARD_FAB2(SCH_1):UPI_CPU0_CPU1_P1P1_DP'<7>:
 C_SIGNAL='@baseboard_fab2_lib.baseboard_fab2(sch_1):upi_cpu0_cpu1_p1p1_dp(7)';
NODE_NAME     U5D1 E14
 '@BASEBOARD_FAB2_LIB.BASEBOARD_FAB2(SCH_1):PAGE34_I86@CHPSET_LIB.SKX_EXT_B(CHIPS)':
 'UPI1_TX_DP'<12>: CDS_PINID='UPI1_TX_DP(12)';
NODE_NAME     U2D1 N12
 '@BASEBOARD_FAB2_LIB.BASEBOARD_FAB2(SCH_1):PAGE68_I125@CHPSET_LIB.SKX_EXT_B(CHIPS)':
 'UPI1_RX_DP'<7>: CDS_PINID='UPI1_RX_DP(7)';
NET_NAME
'UPI_CPU0_CPU1_P1P1_DP<8>'
 '@BASEBOARD_FAB2_LIB.BASEBOARD_FAB2(SCH_1):UPI_CPU0_CPU1_P1P1_DP'<8>:
 C_SIGNAL='@baseboard_fab2_lib.baseboard_fab2(sch_1):upi_cpu0_cpu1_p1p1_dp(8)';
NODE_NAME     U5D1 F13
 '@BASEBOARD_FAB2_LIB.BASEBOARD_FAB2(SCH_1):PAGE34_I86@CHPSET_LIB.SKX_EXT_B(CHIPS)':
 'UPI1_TX_DP'<11>: CDS_PINID='UPI1_TX_DP(11)';
NODE_NAME     U2D1 N14
 '@BASEBOARD_FAB2_LIB.BASEBOARD_FAB2(SCH_1):PAGE68_I125@CHPSET_LIB.SKX_EXT_B(CHIPS)':
 'UPI1_RX_DN'<8>: CDS_PINID='UPI1_RX_DN(8)';
NET_NAME
'UPI_CPU0_CPU1_P1P1_DP<9>'
 '@BASEBOARD_FAB2_LIB.BASEBOARD_FAB2(SCH_1):UPI_CPU0_CPU1_P1P1_DP'<9>:
 C_SIGNAL='@baseboard_fab2_lib.baseboard_fab2(sch_1):upi_cpu0_cpu1_p1p1_dp(9)';
NODE_NAME     U5D1 G12
 '@BASEBOARD_FAB2_LIB.BASEBOARD_FAB2(SCH_1):PAGE34_I86@CHPSET_LIB.SKX_EXT_B(CHIPS)':
 'UPI1_TX_DP'<10>: CDS_PINID='UPI1_TX_DP(10)';
NODE_NAME     U2D1 P13
 '@BASEBOARD_FAB2_LIB.BASEBOARD_FAB2(SCH_1):PAGE68_I125@CHPSET_LIB.SKX_EXT_B(CHIPS)':
 'UPI1_RX_DP'<9>: CDS_PINID='UPI1_RX_DP(9)';
NET_NAME
'UPI_CPU1_CPU0_P0P0_DN<0>'
 '@BASEBOARD_FAB2_LIB.BASEBOARD_FAB2(SCH_1):UPI_CPU1_CPU0_P0P0_DN'<0>:
 C_SIGNAL='@baseboard_fab2_lib.baseboard_fab2(sch_1):upi_cpu1_cpu0_p0p0_dn(0)';
NODE_NAME     U5D1 BB11
 '@BASEBOARD_FAB2_LIB.BASEBOARD_FAB2(SCH_1):PAGE33_I86@CHPSET_LIB.SKX_EXT_B(CHIPS)':
 'UPI0_RX_DN'<19>: CDS_PINID='UPI0_RX_DN(19)';
NODE_NAME     U2D1 M1
 '@BASEBOARD_FAB2_LIB.BASEBOARD_FAB2(SCH_1):PAGE67_I132@CHPSET_LIB.SKX_EXT_B(CHIPS)':
 'UPI0_TX_DP'<0>: CDS_PINID='UPI0_TX_DP(0)';
NET_NAME
'UPI_CPU1_CPU0_P0P0_DN<10>'
 '@BASEBOARD_FAB2_LIB.BASEBOARD_FAB2(SCH_1):UPI_CPU1_CPU0_P0P0_DN'<10>:
 C_SIGNAL='@baseboard_fab2_lib.baseboard_fab2(sch_1):upi_cpu1_cpu0_p0p0_dn(10)';
NODE_NAME     U5D1 AM9
 '@BASEBOARD_FAB2_LIB.BASEBOARD_FAB2(SCH_1):PAGE33_I86@CHPSET_LIB.SKX_EXT_B(CHIPS)':
 'UPI0_RX_DN'<9>: CDS_PINID='UPI0_RX_DN(9)';
NODE_NAME     U2D1 AK3
 '@BASEBOARD_FAB2_LIB.BASEBOARD_FAB2(SCH_1):PAGE67_I132@CHPSET_LIB.SKX_EXT_B(CHIPS)':
 'UPI0_TX_DP'<10>: CDS_PINID='UPI0_TX_DP(10)';
NET_NAME
'UPI_CPU1_CPU0_P0P0_DN<11>'
 '@BASEBOARD_FAB2_LIB.BASEBOARD_FAB2(SCH_1):UPI_CPU1_CPU0_P0P0_DN'<11>:
 C_SIGNAL='@baseboard_fab2_lib.baseboard_fab2(sch_1):upi_cpu1_cpu0_p0p0_dn(11)';
NODE_NAME     U5D1 AK7
 '@BASEBOARD_FAB2_LIB.BASEBOARD_FAB2(SCH_1):PAGE33_I86@CHPSET_LIB.SKX_EXT_B(CHIPS)':
 'UPI0_RX_DN'<8>: CDS_PINID='UPI0_RX_DN(8)';
NODE_NAME     U2D1 AP3
 '@BASEBOARD_FAB2_LIB.BASEBOARD_FAB2(SCH_1):PAGE67_I132@CHPSET_LIB.SKX_EXT_B(CHIPS)':
 'UPI0_TX_DP'<11>: CDS_PINID='UPI0_TX_DP(11)';
NET_NAME
'UPI_CPU1_CPU0_P0P0_DN<12>'
 '@BASEBOARD_FAB2_LIB.BASEBOARD_FAB2(SCH_1):UPI_CPU1_CPU0_P0P0_DN'<12>:
 C_SIGNAL='@baseboard_fab2_lib.baseboard_fab2(sch_1):upi_cpu1_cpu0_p0p0_dn(12)';
NODE_NAME     U5D1 AL6
 '@BASEBOARD_FAB2_LIB.BASEBOARD_FAB2(SCH_1):PAGE33_I86@CHPSET_LIB.SKX_EXT_B(CHIPS)':
 'UPI0_RX_DN'<7>: CDS_PINID='UPI0_RX_DN(7)';
NODE_NAME     U2D1 AP1
 '@BASEBOARD_FAB2_LIB.BASEBOARD_FAB2(SCH_1):PAGE67_I132@CHPSET_LIB.SKX_EXT_B(CHIPS)':
 'UPI0_TX_DP'<12>: CDS_PINID='UPI0_TX_DP(12)';
NET_NAME
'UPI_CPU1_CPU0_P0P0_DN<13>'
 '@BASEBOARD_FAB2_LIB.BASEBOARD_FAB2(SCH_1):UPI_CPU1_CPU0_P0P0_DN'<13>:
 C_SIGNAL='@baseboard_fab2_lib.baseboard_fab2(sch_1):upi_cpu1_cpu0_p0p0_dn(13)';
NODE_NAME     U5D1 AJ6
 '@BASEBOARD_FAB2_LIB.BASEBOARD_FAB2(SCH_1):PAGE33_I86@CHPSET_LIB.SKX_EXT_B(CHIPS)':
 'UPI0_RX_DN'<6>: CDS_PINID='UPI0_RX_DN(6)';
NODE_NAME     U2D1 AR2
 '@BASEBOARD_FAB2_LIB.BASEBOARD_FAB2(SCH_1):PAGE67_I132@CHPSET_LIB.SKX_EXT_B(CHIPS)':
 'UPI0_TX_DP'<13>: CDS_PINID='UPI0_TX_DP(13)';
NET_NAME
'UPI_CPU1_CPU0_P0P0_DN<14>'
 '@BASEBOARD_FAB2_LIB.BASEBOARD_FAB2(SCH_1):UPI_CPU1_CPU0_P0P0_DN'<14>:
 C_SIGNAL='@baseboard_fab2_lib.baseboard_fab2(sch_1):upi_cpu1_cpu0_p0p0_dn(14)';
NODE_NAME     U5D1 AG8
 '@BASEBOARD_FAB2_LIB.BASEBOARD_FAB2(SCH_1):PAGE33_I86@CHPSET_LIB.SKX_EXT_B(CHIPS)':
 'UPI0_RX_DN'<5>: CDS_PINID='UPI0_RX_DN(5)';
NODE_NAME     U2D1 AR4
 '@BASEBOARD_FAB2_LIB.BASEBOARD_FAB2(SCH_1):PAGE67_I132@CHPSET_LIB.SKX_EXT_B(CHIPS)':
 'UPI0_TX_DP'<14>: CDS_PINID='UPI0_TX_DP(14)';
NET_NAME
'UPI_CPU1_CPU0_P0P0_DN<15>'
 '@BASEBOARD_FAB2_LIB.BASEBOARD_FAB2(SCH_1):UPI_CPU1_CPU0_P0P0_DN'<15>:
 C_SIGNAL='@baseboard_fab2_lib.baseboard_fab2(sch_1):upi_cpu1_cpu0_p0p0_dn(15)';
NODE_NAME     U5D1 AE6
 '@BASEBOARD_FAB2_LIB.BASEBOARD_FAB2(SCH_1):PAGE33_I86@CHPSET_LIB.SKX_EXT_B(CHIPS)':
 'UPI0_RX_DN'<4>: CDS_PINID='UPI0_RX_DN(4)';
NODE_NAME     U2D1 AW4
 '@BASEBOARD_FAB2_LIB.BASEBOARD_FAB2(SCH_1):PAGE67_I132@CHPSET_LIB.SKX_EXT_B(CHIPS)':
 'UPI0_TX_DP'<15>: CDS_PINID='UPI0_TX_DP(15)';
NET_NAME
'UPI_CPU1_CPU0_P0P0_DN<16>'
 '@BASEBOARD_FAB2_LIB.BASEBOARD_FAB2(SCH_1):UPI_CPU1_CPU0_P0P0_DN'<16>:
 C_SIGNAL='@baseboard_fab2_lib.baseboard_fab2(sch_1):upi_cpu1_cpu0_p0p0_dn(16)';
NODE_NAME     U5D1 AD5
 '@BASEBOARD_FAB2_LIB.BASEBOARD_FAB2(SCH_1):PAGE33_I86@CHPSET_LIB.SKX_EXT_B(CHIPS)':
 'UPI0_RX_DN'<3>: CDS_PINID='UPI0_RX_DN(3)';
NODE_NAME     U2D1 AY3
 '@BASEBOARD_FAB2_LIB.BASEBOARD_FAB2(SCH_1):PAGE67_I132@CHPSET_LIB.SKX_EXT_B(CHIPS)':
 'UPI0_TX_DP'<16>: CDS_PINID='UPI0_TX_DP(16)';
NET_NAME
'UPI_CPU1_CPU0_P0P0_DN<17>'
 '@BASEBOARD_FAB2_LIB.BASEBOARD_FAB2(SCH_1):UPI_CPU1_CPU0_P0P0_DN'<17>:
 C_SIGNAL='@baseboard_fab2_lib.baseboard_fab2(sch_1):upi_cpu1_cpu0_p0p0_dn(17)';
NODE_NAME     U5D1 AB7
 '@BASEBOARD_FAB2_LIB.BASEBOARD_FAB2(SCH_1):PAGE33_I86@CHPSET_LIB.SKX_EXT_B(CHIPS)':
 'UPI0_RX_DN'<2>: CDS_PINID='UPI0_RX_DN(2)';
NODE_NAME     U2D1 BB3
 '@BASEBOARD_FAB2_LIB.BASEBOARD_FAB2(SCH_1):PAGE67_I132@CHPSET_LIB.SKX_EXT_B(CHIPS)':
 'UPI0_TX_DN'<17>: CDS_PINID='UPI0_TX_DN(17)';
NET_NAME
'UPI_CPU1_CPU0_P0P0_DN<18>'
 '@BASEBOARD_FAB2_LIB.BASEBOARD_FAB2(SCH_1):UPI_CPU1_CPU0_P0P0_DN'<18>:
 C_SIGNAL='@baseboard_fab2_lib.baseboard_fab2(sch_1):upi_cpu1_cpu0_p0p0_dn(18)';
NODE_NAME     U5D1 AA8
 '@BASEBOARD_FAB2_LIB.BASEBOARD_FAB2(SCH_1):PAGE33_I86@CHPSET_LIB.SKX_EXT_B(CHIPS)':
 'UPI0_RX_DN'<1>: CDS_PINID='UPI0_RX_DN(1)';
NODE_NAME     U2D1 BF3
 '@BASEBOARD_FAB2_LIB.BASEBOARD_FAB2(SCH_1):PAGE67_I132@CHPSET_LIB.SKX_EXT_B(CHIPS)':
 'UPI0_TX_DN'<18>: CDS_PINID='UPI0_TX_DN(18)';
NET_NAME
'UPI_CPU1_CPU0_P0P0_DN<19>'
 '@BASEBOARD_FAB2_LIB.BASEBOARD_FAB2(SCH_1):UPI_CPU1_CPU0_P0P0_DN'<19>:
 C_SIGNAL='@baseboard_fab2_lib.baseboard_fab2(sch_1):upi_cpu1_cpu0_p0p0_dn(19)';
NODE_NAME     U5D1 AC10
 '@BASEBOARD_FAB2_LIB.BASEBOARD_FAB2(SCH_1):PAGE33_I86@CHPSET_LIB.SKX_EXT_B(CHIPS)':
 'UPI0_RX_DN'<0>: CDS_PINID='UPI0_RX_DN(0)';
NODE_NAME     U2D1 BH3
 '@BASEBOARD_FAB2_LIB.BASEBOARD_FAB2(SCH_1):PAGE67_I132@CHPSET_LIB.SKX_EXT_B(CHIPS)':
 'UPI0_TX_DP'<19>: CDS_PINID='UPI0_TX_DP(19)';
NET_NAME
'UPI_CPU1_CPU0_P0P0_DN<1>'
 '@BASEBOARD_FAB2_LIB.BASEBOARD_FAB2(SCH_1):UPI_CPU1_CPU0_P0P0_DN'<1>:
 C_SIGNAL='@baseboard_fab2_lib.baseboard_fab2(sch_1):upi_cpu1_cpu0_p0p0_dn(1)';
NODE_NAME     U5D1 BD9
 '@BASEBOARD_FAB2_LIB.BASEBOARD_FAB2(SCH_1):PAGE33_I86@CHPSET_LIB.SKX_EXT_B(CHIPS)':
 'UPI0_RX_DN'<18>: CDS_PINID='UPI0_RX_DN(18)';
NODE_NAME     U2D1 T1
 '@BASEBOARD_FAB2_LIB.BASEBOARD_FAB2(SCH_1):PAGE67_I132@CHPSET_LIB.SKX_EXT_B(CHIPS)':
 'UPI0_TX_DP'<1>: CDS_PINID='UPI0_TX_DP(1)';
NET_NAME
'UPI_CPU1_CPU0_P0P0_DN<2>'
 '@BASEBOARD_FAB2_LIB.BASEBOARD_FAB2(SCH_1):UPI_CPU1_CPU0_P0P0_DN'<2>:
 C_SIGNAL='@baseboard_fab2_lib.baseboard_fab2(sch_1):upi_cpu1_cpu0_p0p0_dn(2)';
NODE_NAME     U5D1 AY9
 '@BASEBOARD_FAB2_LIB.BASEBOARD_FAB2(SCH_1):PAGE33_I86@CHPSET_LIB.SKX_EXT_B(CHIPS)':
 'UPI0_RX_DN'<17>: CDS_PINID='UPI0_RX_DN(17)';
NODE_NAME     U2D1 V3
 '@BASEBOARD_FAB2_LIB.BASEBOARD_FAB2(SCH_1):PAGE67_I132@CHPSET_LIB.SKX_EXT_B(CHIPS)':
 'UPI0_TX_DN'<2>: CDS_PINID='UPI0_TX_DN(2)';
NET_NAME
'UPI_CPU1_CPU0_P0P0_DN<3>'
 '@BASEBOARD_FAB2_LIB.BASEBOARD_FAB2(SCH_1):UPI_CPU1_CPU0_P0P0_DN'<3>:
 C_SIGNAL='@baseboard_fab2_lib.baseboard_fab2(sch_1):upi_cpu1_cpu0_p0p0_dn(3)';
NODE_NAME     U5D1 AW8
 '@BASEBOARD_FAB2_LIB.BASEBOARD_FAB2(SCH_1):PAGE33_I86@CHPSET_LIB.SKX_EXT_B(CHIPS)':
 'UPI0_RX_DN'<16>: CDS_PINID='UPI0_RX_DN(16)';
NODE_NAME     U2D1 Y1
 '@BASEBOARD_FAB2_LIB.BASEBOARD_FAB2(SCH_1):PAGE67_I132@CHPSET_LIB.SKX_EXT_B(CHIPS)':
 'UPI0_TX_DN'<3>: CDS_PINID='UPI0_TX_DN(3)';
NET_NAME
'UPI_CPU1_CPU0_P0P0_DN<4>'
 '@BASEBOARD_FAB2_LIB.BASEBOARD_FAB2(SCH_1):UPI_CPU1_CPU0_P0P0_DN'<4>:
 C_SIGNAL='@baseboard_fab2_lib.baseboard_fab2(sch_1):upi_cpu1_cpu0_p0p0_dn(4)';
NODE_NAME     U5D1 BD7
 '@BASEBOARD_FAB2_LIB.BASEBOARD_FAB2(SCH_1):PAGE33_I86@CHPSET_LIB.SKX_EXT_B(CHIPS)':
 'UPI0_RX_DN'<15>: CDS_PINID='UPI0_RX_DN(15)';
NODE_NAME     U2D1 AB3
 '@BASEBOARD_FAB2_LIB.BASEBOARD_FAB2(SCH_1):PAGE67_I132@CHPSET_LIB.SKX_EXT_B(CHIPS)':
 'UPI0_TX_DN'<4>: CDS_PINID='UPI0_TX_DN(4)';
NET_NAME
'UPI_CPU1_CPU0_P0P0_DN<5>'
 '@BASEBOARD_FAB2_LIB.BASEBOARD_FAB2(SCH_1):UPI_CPU1_CPU0_P0P0_DN'<5>:
 C_SIGNAL='@baseboard_fab2_lib.baseboard_fab2(sch_1):upi_cpu1_cpu0_p0p0_dn(5)';
NODE_NAME     U5D1 BC6
 '@BASEBOARD_FAB2_LIB.BASEBOARD_FAB2(SCH_1):PAGE33_I86@CHPSET_LIB.SKX_EXT_B(CHIPS)':
 'UPI0_RX_DN'<14>: CDS_PINID='UPI0_RX_DN(14)';
NODE_NAME     U2D1 AD1
 '@BASEBOARD_FAB2_LIB.BASEBOARD_FAB2(SCH_1):PAGE67_I132@CHPSET_LIB.SKX_EXT_B(CHIPS)':
 'UPI0_TX_DP'<5>: CDS_PINID='UPI0_TX_DP(5)';
NET_NAME
'UPI_CPU1_CPU0_P0P0_DN<6>'
 '@BASEBOARD_FAB2_LIB.BASEBOARD_FAB2(SCH_1):UPI_CPU1_CPU0_P0P0_DN'<6>:
 C_SIGNAL='@baseboard_fab2_lib.baseboard_fab2(sch_1):upi_cpu1_cpu0_p0p0_dn(6)';
NODE_NAME     U5D1 BA8
 '@BASEBOARD_FAB2_LIB.BASEBOARD_FAB2(SCH_1):PAGE33_I86@CHPSET_LIB.SKX_EXT_B(CHIPS)':
 'UPI0_RX_DN'<13>: CDS_PINID='UPI0_RX_DN(13)';
NODE_NAME     U2D1 AG4
 '@BASEBOARD_FAB2_LIB.BASEBOARD_FAB2(SCH_1):PAGE67_I132@CHPSET_LIB.SKX_EXT_B(CHIPS)':
 'UPI0_TX_DN'<6>: CDS_PINID='UPI0_TX_DN(6)';
NET_NAME
'UPI_CPU1_CPU0_P0P0_DN<7>'
 '@BASEBOARD_FAB2_LIB.BASEBOARD_FAB2(SCH_1):UPI_CPU1_CPU0_P0P0_DN'<7>:
 C_SIGNAL='@baseboard_fab2_lib.baseboard_fab2(sch_1):upi_cpu1_cpu0_p0p0_dn(7)';
NODE_NAME     U5D1 AU10
 '@BASEBOARD_FAB2_LIB.BASEBOARD_FAB2(SCH_1):PAGE33_I86@CHPSET_LIB.SKX_EXT_B(CHIPS)':
 'UPI0_RX_DN'<12>: CDS_PINID='UPI0_RX_DN(12)';
NODE_NAME     U2D1 AE2
 '@BASEBOARD_FAB2_LIB.BASEBOARD_FAB2(SCH_1):PAGE67_I132@CHPSET_LIB.SKX_EXT_B(CHIPS)':
 'UPI0_TX_DN'<7>: CDS_PINID='UPI0_TX_DN(7)';
NET_NAME
'UPI_CPU1_CPU0_P0P0_DN<8>'
 '@BASEBOARD_FAB2_LIB.BASEBOARD_FAB2(SCH_1):UPI_CPU1_CPU0_P0P0_DN'<8>:
 C_SIGNAL='@baseboard_fab2_lib.baseboard_fab2(sch_1):upi_cpu1_cpu0_p0p0_dn(8)';
NODE_NAME     U5D1 AR8
 '@BASEBOARD_FAB2_LIB.BASEBOARD_FAB2(SCH_1):PAGE33_I86@CHPSET_LIB.SKX_EXT_B(CHIPS)':
 'UPI0_RX_DN'<11>: CDS_PINID='UPI0_RX_DN(11)';
NODE_NAME     U2D1 AJ2
 '@BASEBOARD_FAB2_LIB.BASEBOARD_FAB2(SCH_1):PAGE67_I132@CHPSET_LIB.SKX_EXT_B(CHIPS)':
 'UPI0_TX_DP'<8>: CDS_PINID='UPI0_TX_DP(8)';
NET_NAME
'UPI_CPU1_CPU0_P0P0_DN<9>'
 '@BASEBOARD_FAB2_LIB.BASEBOARD_FAB2(SCH_1):UPI_CPU1_CPU0_P0P0_DN'<9>:
 C_SIGNAL='@baseboard_fab2_lib.baseboard_fab2(sch_1):upi_cpu1_cpu0_p0p0_dn(9)';
NODE_NAME     U5D1 AP7
 '@BASEBOARD_FAB2_LIB.BASEBOARD_FAB2(SCH_1):PAGE33_I86@CHPSET_LIB.SKX_EXT_B(CHIPS)':
 'UPI0_RX_DN'<10>: CDS_PINID='UPI0_RX_DN(10)';
NODE_NAME     U2D1 AL2
 '@BASEBOARD_FAB2_LIB.BASEBOARD_FAB2(SCH_1):PAGE67_I132@CHPSET_LIB.SKX_EXT_B(CHIPS)':
 'UPI0_TX_DN'<9>: CDS_PINID='UPI0_TX_DN(9)';
NET_NAME
'UPI_CPU1_CPU0_P0P0_DP<0>'
 '@BASEBOARD_FAB2_LIB.BASEBOARD_FAB2(SCH_1):UPI_CPU1_CPU0_P0P0_DP'<0>:
 C_SIGNAL='@baseboard_fab2_lib.baseboard_fab2(sch_1):upi_cpu1_cpu0_p0p0_dp(0)';
NODE_NAME     U5D1 BA10
 '@BASEBOARD_FAB2_LIB.BASEBOARD_FAB2(SCH_1):PAGE33_I86@CHPSET_LIB.SKX_EXT_B(CHIPS)':
 'UPI0_RX_DP'<19>: CDS_PINID='UPI0_RX_DP(19)';
NODE_NAME     U2D1 N2
 '@BASEBOARD_FAB2_LIB.BASEBOARD_FAB2(SCH_1):PAGE67_I132@CHPSET_LIB.SKX_EXT_B(CHIPS)':
 'UPI0_TX_DN'<0>: CDS_PINID='UPI0_TX_DN(0)';
NET_NAME
'UPI_CPU1_CPU0_P0P0_DP<10>'
 '@BASEBOARD_FAB2_LIB.BASEBOARD_FAB2(SCH_1):UPI_CPU1_CPU0_P0P0_DP'<10>:
 C_SIGNAL='@baseboard_fab2_lib.baseboard_fab2(sch_1):upi_cpu1_cpu0_p0p0_dp(10)';
NODE_NAME     U5D1 AL8
 '@BASEBOARD_FAB2_LIB.BASEBOARD_FAB2(SCH_1):PAGE33_I86@CHPSET_LIB.SKX_EXT_B(CHIPS)':
 'UPI0_RX_DP'<9>: CDS_PINID='UPI0_RX_DP(9)';
NODE_NAME     U2D1 AM3
 '@BASEBOARD_FAB2_LIB.BASEBOARD_FAB2(SCH_1):PAGE67_I132@CHPSET_LIB.SKX_EXT_B(CHIPS)':
 'UPI0_TX_DN'<10>: CDS_PINID='UPI0_TX_DN(10)';
NET_NAME
'UPI_CPU1_CPU0_P0P0_DP<11>'
 '@BASEBOARD_FAB2_LIB.BASEBOARD_FAB2(SCH_1):UPI_CPU1_CPU0_P0P0_DP'<11>:
 C_SIGNAL='@baseboard_fab2_lib.baseboard_fab2(sch_1):upi_cpu1_cpu0_p0p0_dp(11)';
NODE_NAME     U5D1 AM7
 '@BASEBOARD_FAB2_LIB.BASEBOARD_FAB2(SCH_1):PAGE33_I86@CHPSET_LIB.SKX_EXT_B(CHIPS)':
 'UPI0_RX_DP'<8>: CDS_PINID='UPI0_RX_DP(8)';
NODE_NAME     U2D1 AN4
 '@BASEBOARD_FAB2_LIB.BASEBOARD_FAB2(SCH_1):PAGE67_I132@CHPSET_LIB.SKX_EXT_B(CHIPS)':
 'UPI0_TX_DN'<11>: CDS_PINID='UPI0_TX_DN(11)';
NET_NAME
'UPI_CPU1_CPU0_P0P0_DP<12>'
 '@BASEBOARD_FAB2_LIB.BASEBOARD_FAB2(SCH_1):UPI_CPU1_CPU0_P0P0_DP'<12>:
 C_SIGNAL='@baseboard_fab2_lib.baseboard_fab2(sch_1):upi_cpu1_cpu0_p0p0_dp(12)';
NODE_NAME     U5D1 AK5
 '@BASEBOARD_FAB2_LIB.BASEBOARD_FAB2(SCH_1):PAGE33_I86@CHPSET_LIB.SKX_EXT_B(CHIPS)':
 'UPI0_RX_DP'<7>: CDS_PINID='UPI0_RX_DP(7)';
NODE_NAME     U2D1 AT1
 '@BASEBOARD_FAB2_LIB.BASEBOARD_FAB2(SCH_1):PAGE67_I132@CHPSET_LIB.SKX_EXT_B(CHIPS)':
 'UPI0_TX_DN'<12>: CDS_PINID='UPI0_TX_DN(12)';
NET_NAME
'UPI_CPU1_CPU0_P0P0_DP<13>'
 '@BASEBOARD_FAB2_LIB.BASEBOARD_FAB2(SCH_1):UPI_CPU1_CPU0_P0P0_DP'<13>:
 C_SIGNAL='@baseboard_fab2_lib.baseboard_fab2(sch_1):upi_cpu1_cpu0_p0p0_dp(13)';
NODE_NAME     U5D1 AH7
 '@BASEBOARD_FAB2_LIB.BASEBOARD_FAB2(SCH_1):PAGE33_I86@CHPSET_LIB.SKX_EXT_B(CHIPS)':
 'UPI0_RX_DP'<6>: CDS_PINID='UPI0_RX_DP(6)';
NODE_NAME     U2D1 AT3
 '@BASEBOARD_FAB2_LIB.BASEBOARD_FAB2(SCH_1):PAGE67_I132@CHPSET_LIB.SKX_EXT_B(CHIPS)':
 'UPI0_TX_DN'<13>: CDS_PINID='UPI0_TX_DN(13)';
NET_NAME
'UPI_CPU1_CPU0_P0P0_DP<14>'
 '@BASEBOARD_FAB2_LIB.BASEBOARD_FAB2(SCH_1):UPI_CPU1_CPU0_P0P0_DP'<14>:
 C_SIGNAL='@baseboard_fab2_lib.baseboard_fab2(sch_1):upi_cpu1_cpu0_p0p0_dp(14)';
NODE_NAME     U5D1 AF7
 '@BASEBOARD_FAB2_LIB.BASEBOARD_FAB2(SCH_1):PAGE33_I86@CHPSET_LIB.SKX_EXT_B(CHIPS)':
 'UPI0_RX_DP'<5>: CDS_PINID='UPI0_RX_DP(5)';
NODE_NAME     U2D1 AU4
 '@BASEBOARD_FAB2_LIB.BASEBOARD_FAB2(SCH_1):PAGE67_I132@CHPSET_LIB.SKX_EXT_B(CHIPS)':
 'UPI0_TX_DN'<14>: CDS_PINID='UPI0_TX_DN(14)';
NET_NAME
'UPI_CPU1_CPU0_P0P0_DP<15>'
 '@BASEBOARD_FAB2_LIB.BASEBOARD_FAB2(SCH_1):UPI_CPU1_CPU0_P0P0_DP'<15>:
 C_SIGNAL='@baseboard_fab2_lib.baseboard_fab2(sch_1):upi_cpu1_cpu0_p0p0_dp(15)';
NODE_NAME     U5D1 AG6
 '@BASEBOARD_FAB2_LIB.BASEBOARD_FAB2(SCH_1):PAGE33_I86@CHPSET_LIB.SKX_EXT_B(CHIPS)':
 'UPI0_RX_DP'<4>: CDS_PINID='UPI0_RX_DP(4)';
NODE_NAME     U2D1 AV5
 '@BASEBOARD_FAB2_LIB.BASEBOARD_FAB2(SCH_1):PAGE67_I132@CHPSET_LIB.SKX_EXT_B(CHIPS)':
 'UPI0_TX_DN'<15>: CDS_PINID='UPI0_TX_DN(15)';
NET_NAME
'UPI_CPU1_CPU0_P0P0_DP<16>'
 '@BASEBOARD_FAB2_LIB.BASEBOARD_FAB2(SCH_1):UPI_CPU1_CPU0_P0P0_DP'<16>:
 C_SIGNAL='@baseboard_fab2_lib.baseboard_fab2(sch_1):upi_cpu1_cpu0_p0p0_dp(16)';
NODE_NAME     U5D1 AC6
 '@BASEBOARD_FAB2_LIB.BASEBOARD_FAB2(SCH_1):PAGE33_I86@CHPSET_LIB.SKX_EXT_B(CHIPS)':
 'UPI0_RX_DP'<3>: CDS_PINID='UPI0_RX_DP(3)';
NODE_NAME     U2D1 BA4
 '@BASEBOARD_FAB2_LIB.BASEBOARD_FAB2(SCH_1):PAGE67_I132@CHPSET_LIB.SKX_EXT_B(CHIPS)':
 'UPI0_TX_DN'<16>: CDS_PINID='UPI0_TX_DN(16)';
NET_NAME
'UPI_CPU1_CPU0_P0P0_DP<17>'
 '@BASEBOARD_FAB2_LIB.BASEBOARD_FAB2(SCH_1):UPI_CPU1_CPU0_P0P0_DP'<17>:
 C_SIGNAL='@baseboard_fab2_lib.baseboard_fab2(sch_1):upi_cpu1_cpu0_p0p0_dp(17)';
NODE_NAME     U5D1 AA6
 '@BASEBOARD_FAB2_LIB.BASEBOARD_FAB2(SCH_1):PAGE33_I86@CHPSET_LIB.SKX_EXT_B(CHIPS)':
 'UPI0_RX_DP'<2>: CDS_PINID='UPI0_RX_DP(2)';
NODE_NAME     U2D1 BC2
 '@BASEBOARD_FAB2_LIB.BASEBOARD_FAB2(SCH_1):PAGE67_I132@CHPSET_LIB.SKX_EXT_B(CHIPS)':
 'UPI0_TX_DP'<17>: CDS_PINID='UPI0_TX_DP(17)';
NET_NAME
'UPI_CPU1_CPU0_P0P0_DP<18>'
 '@BASEBOARD_FAB2_LIB.BASEBOARD_FAB2(SCH_1):UPI_CPU1_CPU0_P0P0_DP'<18>:
 C_SIGNAL='@baseboard_fab2_lib.baseboard_fab2(sch_1):upi_cpu1_cpu0_p0p0_dp(18)';
NODE_NAME     U5D1 AC8
 '@BASEBOARD_FAB2_LIB.BASEBOARD_FAB2(SCH_1):PAGE33_I86@CHPSET_LIB.SKX_EXT_B(CHIPS)':
 'UPI0_RX_DP'<1>: CDS_PINID='UPI0_RX_DP(1)';
NODE_NAME     U2D1 BD3
 '@BASEBOARD_FAB2_LIB.BASEBOARD_FAB2(SCH_1):PAGE67_I132@CHPSET_LIB.SKX_EXT_B(CHIPS)':
 'UPI0_TX_DP'<18>: CDS_PINID='UPI0_TX_DP(18)';
NET_NAME
'UPI_CPU1_CPU0_P0P0_DP<19>'
 '@BASEBOARD_FAB2_LIB.BASEBOARD_FAB2(SCH_1):UPI_CPU1_CPU0_P0P0_DP'<19>:
 C_SIGNAL='@baseboard_fab2_lib.baseboard_fab2(sch_1):upi_cpu1_cpu0_p0p0_dp(19)';
NODE_NAME     U5D1 AB9
 '@BASEBOARD_FAB2_LIB.BASEBOARD_FAB2(SCH_1):PAGE33_I86@CHPSET_LIB.SKX_EXT_B(CHIPS)':
 'UPI0_RX_DP'<0>: CDS_PINID='UPI0_RX_DP(0)';
NODE_NAME     U2D1 BG4
 '@BASEBOARD_FAB2_LIB.BASEBOARD_FAB2(SCH_1):PAGE67_I132@CHPSET_LIB.SKX_EXT_B(CHIPS)':
 'UPI0_TX_DN'<19>: CDS_PINID='UPI0_TX_DN(19)';
NET_NAME
'UPI_CPU1_CPU0_P0P0_DP<1>'
 '@BASEBOARD_FAB2_LIB.BASEBOARD_FAB2(SCH_1):UPI_CPU1_CPU0_P0P0_DP'<1>:
 C_SIGNAL='@baseboard_fab2_lib.baseboard_fab2(sch_1):upi_cpu1_cpu0_p0p0_dp(1)';
NODE_NAME     U5D1 BC10
 '@BASEBOARD_FAB2_LIB.BASEBOARD_FAB2(SCH_1):PAGE33_I86@CHPSET_LIB.SKX_EXT_B(CHIPS)':
 'UPI0_RX_DP'<18>: CDS_PINID='UPI0_RX_DP(18)';
NODE_NAME     U2D1 P1
 '@BASEBOARD_FAB2_LIB.BASEBOARD_FAB2(SCH_1):PAGE67_I132@CHPSET_LIB.SKX_EXT_B(CHIPS)':
 'UPI0_TX_DN'<1>: CDS_PINID='UPI0_TX_DN(1)';
NET_NAME
'UPI_CPU1_CPU0_P0P0_DP<2>'
 '@BASEBOARD_FAB2_LIB.BASEBOARD_FAB2(SCH_1):UPI_CPU1_CPU0_P0P0_DP'<2>:
 C_SIGNAL='@baseboard_fab2_lib.baseboard_fab2(sch_1):upi_cpu1_cpu0_p0p0_dp(2)';
NODE_NAME     U5D1 BB9
 '@BASEBOARD_FAB2_LIB.BASEBOARD_FAB2(SCH_1):PAGE33_I86@CHPSET_LIB.SKX_EXT_B(CHIPS)':
 'UPI0_RX_DP'<17>: CDS_PINID='UPI0_RX_DP(17)';
NODE_NAME     U2D1 Y3
 '@BASEBOARD_FAB2_LIB.BASEBOARD_FAB2(SCH_1):PAGE67_I132@CHPSET_LIB.SKX_EXT_B(CHIPS)':
 'UPI0_TX_DP'<2>: CDS_PINID='UPI0_TX_DP(2)';
NET_NAME
'UPI_CPU1_CPU0_P0P0_DP<3>'
 '@BASEBOARD_FAB2_LIB.BASEBOARD_FAB2(SCH_1):UPI_CPU1_CPU0_P0P0_DP'<3>:
 C_SIGNAL='@baseboard_fab2_lib.baseboard_fab2(sch_1):upi_cpu1_cpu0_p0p0_dp(3)';
NODE_NAME     U5D1 AV9
 '@BASEBOARD_FAB2_LIB.BASEBOARD_FAB2(SCH_1):PAGE33_I86@CHPSET_LIB.SKX_EXT_B(CHIPS)':
 'UPI0_RX_DP'<16>: CDS_PINID='UPI0_RX_DP(16)';
NODE_NAME     U2D1 W2
 '@BASEBOARD_FAB2_LIB.BASEBOARD_FAB2(SCH_1):PAGE67_I132@CHPSET_LIB.SKX_EXT_B(CHIPS)':
 'UPI0_TX_DP'<3>: CDS_PINID='UPI0_TX_DP(3)';
NET_NAME
'UPI_CPU1_CPU0_P0P0_DP<4>'
 '@BASEBOARD_FAB2_LIB.BASEBOARD_FAB2(SCH_1):UPI_CPU1_CPU0_P0P0_DP'<4>:
 C_SIGNAL='@baseboard_fab2_lib.baseboard_fab2(sch_1):upi_cpu1_cpu0_p0p0_dp(4)';
NODE_NAME     U5D1 BF7
 '@BASEBOARD_FAB2_LIB.BASEBOARD_FAB2(SCH_1):PAGE33_I86@CHPSET_LIB.SKX_EXT_B(CHIPS)':
 'UPI0_RX_DP'<15>: CDS_PINID='UPI0_RX_DP(15)';
NODE_NAME     U2D1 AA2
 '@BASEBOARD_FAB2_LIB.BASEBOARD_FAB2(SCH_1):PAGE67_I132@CHPSET_LIB.SKX_EXT_B(CHIPS)':
 'UPI0_TX_DP'<4>: CDS_PINID='UPI0_TX_DP(4)';
NET_NAME
'UPI_CPU1_CPU0_P0P0_DP<5>'
 '@BASEBOARD_FAB2_LIB.BASEBOARD_FAB2(SCH_1):UPI_CPU1_CPU0_P0P0_DP'<5>:
 C_SIGNAL='@baseboard_fab2_lib.baseboard_fab2(sch_1):upi_cpu1_cpu0_p0p0_dp(5)';
NODE_NAME     U5D1 BB7
 '@BASEBOARD_FAB2_LIB.BASEBOARD_FAB2(SCH_1):PAGE33_I86@CHPSET_LIB.SKX_EXT_B(CHIPS)':
 'UPI0_RX_DP'<14>: CDS_PINID='UPI0_RX_DP(14)';
NODE_NAME     U2D1 AC2
 '@BASEBOARD_FAB2_LIB.BASEBOARD_FAB2(SCH_1):PAGE67_I132@CHPSET_LIB.SKX_EXT_B(CHIPS)':
 'UPI0_TX_DN'<5>: CDS_PINID='UPI0_TX_DN(5)';
NET_NAME
'UPI_CPU1_CPU0_P0P0_DP<6>'
 '@BASEBOARD_FAB2_LIB.BASEBOARD_FAB2(SCH_1):UPI_CPU1_CPU0_P0P0_DP'<6>:
 C_SIGNAL='@baseboard_fab2_lib.baseboard_fab2(sch_1):upi_cpu1_cpu0_p0p0_dp(6)';
NODE_NAME     U5D1 AY7
 '@BASEBOARD_FAB2_LIB.BASEBOARD_FAB2(SCH_1):PAGE33_I86@CHPSET_LIB.SKX_EXT_B(CHIPS)':
 'UPI0_RX_DP'<13>: CDS_PINID='UPI0_RX_DP(13)';
NODE_NAME     U2D1 AF3
 '@BASEBOARD_FAB2_LIB.BASEBOARD_FAB2(SCH_1):PAGE67_I132@CHPSET_LIB.SKX_EXT_B(CHIPS)':
 'UPI0_TX_DP'<6>: CDS_PINID='UPI0_TX_DP(6)';
NET_NAME
'UPI_CPU1_CPU0_P0P0_DP<7>'
 '@BASEBOARD_FAB2_LIB.BASEBOARD_FAB2(SCH_1):UPI_CPU1_CPU0_P0P0_DP'<7>:
 C_SIGNAL='@baseboard_fab2_lib.baseboard_fab2(sch_1):upi_cpu1_cpu0_p0p0_dp(7)';
NODE_NAME     U5D1 AT9
 '@BASEBOARD_FAB2_LIB.BASEBOARD_FAB2(SCH_1):PAGE33_I86@CHPSET_LIB.SKX_EXT_B(CHIPS)':
 'UPI0_RX_DP'<12>: CDS_PINID='UPI0_RX_DP(12)';
NODE_NAME     U2D1 AG2
 '@BASEBOARD_FAB2_LIB.BASEBOARD_FAB2(SCH_1):PAGE67_I132@CHPSET_LIB.SKX_EXT_B(CHIPS)':
 'UPI0_TX_DP'<7>: CDS_PINID='UPI0_TX_DP(7)';
NET_NAME
'UPI_CPU1_CPU0_P0P0_DP<8>'
 '@BASEBOARD_FAB2_LIB.BASEBOARD_FAB2(SCH_1):UPI_CPU1_CPU0_P0P0_DP'<8>:
 C_SIGNAL='@baseboard_fab2_lib.baseboard_fab2(sch_1):upi_cpu1_cpu0_p0p0_dp(8)';
NODE_NAME     U5D1 AU8
 '@BASEBOARD_FAB2_LIB.BASEBOARD_FAB2(SCH_1):PAGE33_I86@CHPSET_LIB.SKX_EXT_B(CHIPS)':
 'UPI0_RX_DP'<11>: CDS_PINID='UPI0_RX_DP(11)';
NODE_NAME     U2D1 AH3
 '@BASEBOARD_FAB2_LIB.BASEBOARD_FAB2(SCH_1):PAGE67_I132@CHPSET_LIB.SKX_EXT_B(CHIPS)':
 'UPI0_TX_DN'<8>: CDS_PINID='UPI0_TX_DN(8)';
NET_NAME
'UPI_CPU1_CPU0_P0P0_DP<9>'
 '@BASEBOARD_FAB2_LIB.BASEBOARD_FAB2(SCH_1):UPI_CPU1_CPU0_P0P0_DP'<9>:
 C_SIGNAL='@baseboard_fab2_lib.baseboard_fab2(sch_1):upi_cpu1_cpu0_p0p0_dp(9)';
NODE_NAME     U5D1 AN8
 '@BASEBOARD_FAB2_LIB.BASEBOARD_FAB2(SCH_1):PAGE33_I86@CHPSET_LIB.SKX_EXT_B(CHIPS)':
 'UPI0_RX_DP'<10>: CDS_PINID='UPI0_RX_DP(10)';
NODE_NAME     U2D1 AK1
 '@BASEBOARD_FAB2_LIB.BASEBOARD_FAB2(SCH_1):PAGE67_I132@CHPSET_LIB.SKX_EXT_B(CHIPS)':
 'UPI0_TX_DP'<9>: CDS_PINID='UPI0_TX_DP(9)';
NET_NAME
'UPI_CPU1_CPU0_P1P1_DN<0>'
 '@BASEBOARD_FAB2_LIB.BASEBOARD_FAB2(SCH_1):UPI_CPU1_CPU0_P1P1_DN'<0>:
 C_SIGNAL='@baseboard_fab2_lib.baseboard_fab2(sch_1):upi_cpu1_cpu0_p1p1_dn(0)';
NODE_NAME     U5D1 AB19
 '@BASEBOARD_FAB2_LIB.BASEBOARD_FAB2(SCH_1):PAGE34_I86@CHPSET_LIB.SKX_EXT_B(CHIPS)':
 'UPI1_RX_DN'<19>: CDS_PINID='UPI1_RX_DN(19)';
NODE_NAME     U2D1 P3
 '@BASEBOARD_FAB2_LIB.BASEBOARD_FAB2(SCH_1):PAGE68_I125@CHPSET_LIB.SKX_EXT_B(CHIPS)':
 'UPI1_TX_DP'<0>: CDS_PINID='UPI1_TX_DP(0)';
NET_NAME
'UPI_CPU1_CPU0_P1P1_DN<10>'
 '@BASEBOARD_FAB2_LIB.BASEBOARD_FAB2(SCH_1):UPI_CPU1_CPU0_P1P1_DN'<10>:
 C_SIGNAL='@baseboard_fab2_lib.baseboard_fab2(sch_1):upi_cpu1_cpu0_p1p1_dn(10)';
NODE_NAME     U5D1 R12
 '@BASEBOARD_FAB2_LIB.BASEBOARD_FAB2(SCH_1):PAGE34_I86@CHPSET_LIB.SKX_EXT_B(CHIPS)':
 'UPI1_RX_DN'<9>: CDS_PINID='UPI1_RX_DN(9)';
NODE_NAME     U2D1 E12
 '@BASEBOARD_FAB2_LIB.BASEBOARD_FAB2(SCH_1):PAGE68_I125@CHPSET_LIB.SKX_EXT_B(CHIPS)':
 'UPI1_TX_DN'<10>: CDS_PINID='UPI1_TX_DN(10)';
NET_NAME
'UPI_CPU1_CPU0_P1P1_DN<11>'
 '@BASEBOARD_FAB2_LIB.BASEBOARD_FAB2(SCH_1):UPI_CPU1_CPU0_P1P1_DN'<11>:
 C_SIGNAL='@baseboard_fab2_lib.baseboard_fab2(sch_1):upi_cpu1_cpu0_p1p1_dn(11)';
NODE_NAME     U5D1 N14
 '@BASEBOARD_FAB2_LIB.BASEBOARD_FAB2(SCH_1):PAGE34_I86@CHPSET_LIB.SKX_EXT_B(CHIPS)':
 'UPI1_RX_DN'<8>: CDS_PINID='UPI1_RX_DN(8)';
NODE_NAME     U2D1 F13
 '@BASEBOARD_FAB2_LIB.BASEBOARD_FAB2(SCH_1):PAGE68_I125@CHPSET_LIB.SKX_EXT_B(CHIPS)':
 'UPI1_TX_DP'<11>: CDS_PINID='UPI1_TX_DP(11)';
NET_NAME
'UPI_CPU1_CPU0_P1P1_DN<12>'
 '@BASEBOARD_FAB2_LIB.BASEBOARD_FAB2(SCH_1):UPI_CPU1_CPU0_P1P1_DN'<12>:
 C_SIGNAL='@baseboard_fab2_lib.baseboard_fab2(sch_1):upi_cpu1_cpu0_p1p1_dn(12)';
NODE_NAME     U5D1 L12
 '@BASEBOARD_FAB2_LIB.BASEBOARD_FAB2(SCH_1):PAGE34_I86@CHPSET_LIB.SKX_EXT_B(CHIPS)':
 'UPI1_RX_DN'<7>: CDS_PINID='UPI1_RX_DN(7)';
NODE_NAME     U2D1 D15
 '@BASEBOARD_FAB2_LIB.BASEBOARD_FAB2(SCH_1):PAGE68_I125@CHPSET_LIB.SKX_EXT_B(CHIPS)':
 'UPI1_TX_DN'<12>: CDS_PINID='UPI1_TX_DN(12)';
NET_NAME
'UPI_CPU1_CPU0_P1P1_DN<13>'
 '@BASEBOARD_FAB2_LIB.BASEBOARD_FAB2(SCH_1):UPI_CPU1_CPU0_P1P1_DN'<13>:
 C_SIGNAL='@baseboard_fab2_lib.baseboard_fab2(sch_1):upi_cpu1_cpu0_p1p1_dn(13)';
NODE_NAME     U5D1 U12
 '@BASEBOARD_FAB2_LIB.BASEBOARD_FAB2(SCH_1):PAGE34_I86@CHPSET_LIB.SKX_EXT_B(CHIPS)':
 'UPI1_RX_DN'<6>: CDS_PINID='UPI1_RX_DN(6)';
NODE_NAME     U2D1 F15
 '@BASEBOARD_FAB2_LIB.BASEBOARD_FAB2(SCH_1):PAGE68_I125@CHPSET_LIB.SKX_EXT_B(CHIPS)':
 'UPI1_TX_DN'<13>: CDS_PINID='UPI1_TX_DN(13)';
NET_NAME
'UPI_CPU1_CPU0_P1P1_DN<14>'
 '@BASEBOARD_FAB2_LIB.BASEBOARD_FAB2(SCH_1):UPI_CPU1_CPU0_P1P1_DN'<14>:
 C_SIGNAL='@baseboard_fab2_lib.baseboard_fab2(sch_1):upi_cpu1_cpu0_p1p1_dn(14)';
NODE_NAME     U5D1 R10
 '@BASEBOARD_FAB2_LIB.BASEBOARD_FAB2(SCH_1):PAGE34_I86@CHPSET_LIB.SKX_EXT_B(CHIPS)':
 'UPI1_RX_DN'<5>: CDS_PINID='UPI1_RX_DN(5)';
NODE_NAME     U2D1 H17
 '@BASEBOARD_FAB2_LIB.BASEBOARD_FAB2(SCH_1):PAGE68_I125@CHPSET_LIB.SKX_EXT_B(CHIPS)':
 'UPI1_TX_DN'<14>: CDS_PINID='UPI1_TX_DN(14)';
NET_NAME
'UPI_CPU1_CPU0_P1P1_DN<15>'
 '@BASEBOARD_FAB2_LIB.BASEBOARD_FAB2(SCH_1):UPI_CPU1_CPU0_P1P1_DN'<15>:
 C_SIGNAL='@baseboard_fab2_lib.baseboard_fab2(sch_1):upi_cpu1_cpu0_p1p1_dn(15)';
NODE_NAME     U5D1 P9
 '@BASEBOARD_FAB2_LIB.BASEBOARD_FAB2(SCH_1):PAGE34_I86@CHPSET_LIB.SKX_EXT_B(CHIPS)':
 'UPI1_RX_DN'<4>: CDS_PINID='UPI1_RX_DN(4)';
NODE_NAME     U2D1 K19
 '@BASEBOARD_FAB2_LIB.BASEBOARD_FAB2(SCH_1):PAGE68_I125@CHPSET_LIB.SKX_EXT_B(CHIPS)':
 'UPI1_TX_DN'<15>: CDS_PINID='UPI1_TX_DN(15)';
NET_NAME
'UPI_CPU1_CPU0_P1P1_DN<16>'
 '@BASEBOARD_FAB2_LIB.BASEBOARD_FAB2(SCH_1):UPI_CPU1_CPU0_P1P1_DN'<16>:
 C_SIGNAL='@baseboard_fab2_lib.baseboard_fab2(sch_1):upi_cpu1_cpu0_p1p1_dn(16)';
NODE_NAME     U5D1 T9
 '@BASEBOARD_FAB2_LIB.BASEBOARD_FAB2(SCH_1):PAGE34_I86@CHPSET_LIB.SKX_EXT_B(CHIPS)':
 'UPI1_RX_DN'<3>: CDS_PINID='UPI1_RX_DN(3)';
NODE_NAME     U2D1 G18
 '@BASEBOARD_FAB2_LIB.BASEBOARD_FAB2(SCH_1):PAGE68_I125@CHPSET_LIB.SKX_EXT_B(CHIPS)':
 'UPI1_TX_DN'<16>: CDS_PINID='UPI1_TX_DN(16)';
NET_NAME
'UPI_CPU1_CPU0_P1P1_DN<17>'
 '@BASEBOARD_FAB2_LIB.BASEBOARD_FAB2(SCH_1):UPI_CPU1_CPU0_P1P1_DN'<17>:
 C_SIGNAL='@baseboard_fab2_lib.baseboard_fab2(sch_1):upi_cpu1_cpu0_p1p1_dn(17)';
NODE_NAME     U5D1 V7
 '@BASEBOARD_FAB2_LIB.BASEBOARD_FAB2(SCH_1):PAGE34_I86@CHPSET_LIB.SKX_EXT_B(CHIPS)':
 'UPI1_RX_DN'<2>: CDS_PINID='UPI1_RX_DN(2)';
NODE_NAME     U2D1 J20
 '@BASEBOARD_FAB2_LIB.BASEBOARD_FAB2(SCH_1):PAGE68_I125@CHPSET_LIB.SKX_EXT_B(CHIPS)':
 'UPI1_TX_DN'<17>: CDS_PINID='UPI1_TX_DN(17)';
NET_NAME
'UPI_CPU1_CPU0_P1P1_DN<18>'
 '@BASEBOARD_FAB2_LIB.BASEBOARD_FAB2(SCH_1):UPI_CPU1_CPU0_P1P1_DN'<18>:
 C_SIGNAL='@baseboard_fab2_lib.baseboard_fab2(sch_1):upi_cpu1_cpu0_p1p1_dn(18)';
NODE_NAME     U5D1 P7
 '@BASEBOARD_FAB2_LIB.BASEBOARD_FAB2(SCH_1):PAGE34_I86@CHPSET_LIB.SKX_EXT_B(CHIPS)':
 'UPI1_RX_DN'<1>: CDS_PINID='UPI1_RX_DN(1)';
NODE_NAME     U2D1 G20
 '@BASEBOARD_FAB2_LIB.BASEBOARD_FAB2(SCH_1):PAGE68_I125@CHPSET_LIB.SKX_EXT_B(CHIPS)':
 'UPI1_TX_DP'<18>: CDS_PINID='UPI1_TX_DP(18)';
NET_NAME
'UPI_CPU1_CPU0_P1P1_DN<19>'
 '@BASEBOARD_FAB2_LIB.BASEBOARD_FAB2(SCH_1):UPI_CPU1_CPU0_P1P1_DN'<19>:
 C_SIGNAL='@baseboard_fab2_lib.baseboard_fab2(sch_1):upi_cpu1_cpu0_p1p1_dn(19)';
NODE_NAME     U5D1 T5
 '@BASEBOARD_FAB2_LIB.BASEBOARD_FAB2(SCH_1):PAGE34_I86@CHPSET_LIB.SKX_EXT_B(CHIPS)':
 'UPI1_RX_DN'<0>: CDS_PINID='UPI1_RX_DN(0)';
NODE_NAME     U2D1 K21
 '@BASEBOARD_FAB2_LIB.BASEBOARD_FAB2(SCH_1):PAGE68_I125@CHPSET_LIB.SKX_EXT_B(CHIPS)':
 'UPI1_TX_DP'<19>: CDS_PINID='UPI1_TX_DP(19)';
NET_NAME
'UPI_CPU1_CPU0_P1P1_DN<1>'
 '@BASEBOARD_FAB2_LIB.BASEBOARD_FAB2(SCH_1):UPI_CPU1_CPU0_P1P1_DN'<1>:
 C_SIGNAL='@baseboard_fab2_lib.baseboard_fab2(sch_1):upi_cpu1_cpu0_p1p1_dn(1)';
NODE_NAME     U5D1 Y21
 '@BASEBOARD_FAB2_LIB.BASEBOARD_FAB2(SCH_1):PAGE34_I86@CHPSET_LIB.SKX_EXT_B(CHIPS)':
 'UPI1_RX_DN'<18>: CDS_PINID='UPI1_RX_DN(18)';
NODE_NAME     U2D1 K3
 '@BASEBOARD_FAB2_LIB.BASEBOARD_FAB2(SCH_1):PAGE68_I125@CHPSET_LIB.SKX_EXT_B(CHIPS)':
 'UPI1_TX_DP'<1>: CDS_PINID='UPI1_TX_DP(1)';
NET_NAME
'UPI_CPU1_CPU0_P1P1_DN<2>'
 '@BASEBOARD_FAB2_LIB.BASEBOARD_FAB2(SCH_1):UPI_CPU1_CPU0_P1P1_DN'<2>:
 C_SIGNAL='@baseboard_fab2_lib.baseboard_fab2(sch_1):upi_cpu1_cpu0_p1p1_dn(2)';
NODE_NAME     U5D1 V19
 '@BASEBOARD_FAB2_LIB.BASEBOARD_FAB2(SCH_1):PAGE34_I86@CHPSET_LIB.SKX_EXT_B(CHIPS)':
 'UPI1_RX_DN'<17>: CDS_PINID='UPI1_RX_DN(17)';
NODE_NAME     U2D1 K5
 '@BASEBOARD_FAB2_LIB.BASEBOARD_FAB2(SCH_1):PAGE68_I125@CHPSET_LIB.SKX_EXT_B(CHIPS)':
 'UPI1_TX_DN'<2>: CDS_PINID='UPI1_TX_DN(2)';
NET_NAME
'UPI_CPU1_CPU0_P1P1_DN<3>'
 '@BASEBOARD_FAB2_LIB.BASEBOARD_FAB2(SCH_1):UPI_CPU1_CPU0_P1P1_DN'<3>:
 C_SIGNAL='@baseboard_fab2_lib.baseboard_fab2(sch_1):upi_cpu1_cpu0_p1p1_dn(3)';
NODE_NAME     U5D1 P21
 '@BASEBOARD_FAB2_LIB.BASEBOARD_FAB2(SCH_1):PAGE34_I86@CHPSET_LIB.SKX_EXT_B(CHIPS)':
 'UPI1_RX_DN'<16>: CDS_PINID='UPI1_RX_DN(16)';
NODE_NAME     U2D1 J6
 '@BASEBOARD_FAB2_LIB.BASEBOARD_FAB2(SCH_1):PAGE68_I125@CHPSET_LIB.SKX_EXT_B(CHIPS)':
 'UPI1_TX_DN'<3>: CDS_PINID='UPI1_TX_DN(3)';
NET_NAME
'UPI_CPU1_CPU0_P1P1_DN<4>'
 '@BASEBOARD_FAB2_LIB.BASEBOARD_FAB2(SCH_1):UPI_CPU1_CPU0_P1P1_DN'<4>:
 C_SIGNAL='@baseboard_fab2_lib.baseboard_fab2(sch_1):upi_cpu1_cpu0_p1p1_dn(4)';
NODE_NAME     U5D1 U18
 '@BASEBOARD_FAB2_LIB.BASEBOARD_FAB2(SCH_1):PAGE34_I86@CHPSET_LIB.SKX_EXT_B(CHIPS)':
 'UPI1_RX_DN'<15>: CDS_PINID='UPI1_RX_DN(15)';
NODE_NAME     U2D1 G6
 '@BASEBOARD_FAB2_LIB.BASEBOARD_FAB2(SCH_1):PAGE68_I125@CHPSET_LIB.SKX_EXT_B(CHIPS)':
 'UPI1_TX_DN'<4>: CDS_PINID='UPI1_TX_DN(4)';
NET_NAME
'UPI_CPU1_CPU0_P1P1_DN<5>'
 '@BASEBOARD_FAB2_LIB.BASEBOARD_FAB2(SCH_1):UPI_CPU1_CPU0_P1P1_DN'<5>:
 C_SIGNAL='@baseboard_fab2_lib.baseboard_fab2(sch_1):upi_cpu1_cpu0_p1p1_dn(5)';
NODE_NAME     U5D1 R20
 '@BASEBOARD_FAB2_LIB.BASEBOARD_FAB2(SCH_1):PAGE34_I86@CHPSET_LIB.SKX_EXT_B(CHIPS)':
 'UPI1_RX_DN'<14>: CDS_PINID='UPI1_RX_DN(14)';
NODE_NAME     U2D1 H7
 '@BASEBOARD_FAB2_LIB.BASEBOARD_FAB2(SCH_1):PAGE68_I125@CHPSET_LIB.SKX_EXT_B(CHIPS)':
 'UPI1_TX_DN'<5>: CDS_PINID='UPI1_TX_DN(5)';
NET_NAME
'UPI_CPU1_CPU0_P1P1_DN<6>'
 '@BASEBOARD_FAB2_LIB.BASEBOARD_FAB2(SCH_1):UPI_CPU1_CPU0_P1P1_DN'<6>:
 C_SIGNAL='@baseboard_fab2_lib.baseboard_fab2(sch_1):upi_cpu1_cpu0_p1p1_dn(6)';
NODE_NAME     U5D1 W18
 '@BASEBOARD_FAB2_LIB.BASEBOARD_FAB2(SCH_1):PAGE34_I86@CHPSET_LIB.SKX_EXT_B(CHIPS)':
 'UPI1_RX_DN'<13>: CDS_PINID='UPI1_RX_DN(13)';
NODE_NAME     U2D1 J8
 '@BASEBOARD_FAB2_LIB.BASEBOARD_FAB2(SCH_1):PAGE68_I125@CHPSET_LIB.SKX_EXT_B(CHIPS)':
 'UPI1_TX_DP'<6>: CDS_PINID='UPI1_TX_DP(6)';
NET_NAME
'UPI_CPU1_CPU0_P1P1_DN<7>'
 '@BASEBOARD_FAB2_LIB.BASEBOARD_FAB2(SCH_1):UPI_CPU1_CPU0_P1P1_DN'<7>:
 C_SIGNAL='@baseboard_fab2_lib.baseboard_fab2(sch_1):upi_cpu1_cpu0_p1p1_dn(7)';
NODE_NAME     U5D1 U16
 '@BASEBOARD_FAB2_LIB.BASEBOARD_FAB2(SCH_1):PAGE34_I86@CHPSET_LIB.SKX_EXT_B(CHIPS)':
 'UPI1_RX_DN'<12>: CDS_PINID='UPI1_RX_DN(12)';
NODE_NAME     U2D1 F9
 '@BASEBOARD_FAB2_LIB.BASEBOARD_FAB2(SCH_1):PAGE68_I125@CHPSET_LIB.SKX_EXT_B(CHIPS)':
 'UPI1_TX_DP'<7>: CDS_PINID='UPI1_TX_DP(7)';
NET_NAME
'UPI_CPU1_CPU0_P1P1_DN<8>'
 '@BASEBOARD_FAB2_LIB.BASEBOARD_FAB2(SCH_1):UPI_CPU1_CPU0_P1P1_DN'<8>:
 C_SIGNAL='@baseboard_fab2_lib.baseboard_fab2(sch_1):upi_cpu1_cpu0_p1p1_dn(8)';
NODE_NAME     U5D1 P17
 '@BASEBOARD_FAB2_LIB.BASEBOARD_FAB2(SCH_1):PAGE34_I86@CHPSET_LIB.SKX_EXT_B(CHIPS)':
 'UPI1_RX_DN'<11>: CDS_PINID='UPI1_RX_DN(11)';
NODE_NAME     U2D1 E10
 '@BASEBOARD_FAB2_LIB.BASEBOARD_FAB2(SCH_1):PAGE68_I125@CHPSET_LIB.SKX_EXT_B(CHIPS)':
 'UPI1_TX_DP'<8>: CDS_PINID='UPI1_TX_DP(8)';
NET_NAME
'UPI_CPU1_CPU0_P1P1_DN<9>'
 '@BASEBOARD_FAB2_LIB.BASEBOARD_FAB2(SCH_1):UPI_CPU1_CPU0_P1P1_DN'<9>:
 C_SIGNAL='@baseboard_fab2_lib.baseboard_fab2(sch_1):upi_cpu1_cpu0_p1p1_dn(9)';
NODE_NAME     U5D1 R16
 '@BASEBOARD_FAB2_LIB.BASEBOARD_FAB2(SCH_1):PAGE34_I86@CHPSET_LIB.SKX_EXT_B(CHIPS)':
 'UPI1_RX_DN'<10>: CDS_PINID='UPI1_RX_DN(10)';
NODE_NAME     U2D1 G10
 '@BASEBOARD_FAB2_LIB.BASEBOARD_FAB2(SCH_1):PAGE68_I125@CHPSET_LIB.SKX_EXT_B(CHIPS)':
 'UPI1_TX_DN'<9>: CDS_PINID='UPI1_TX_DN(9)';
NET_NAME
'UPI_CPU1_CPU0_P1P1_DP<0>'
 '@BASEBOARD_FAB2_LIB.BASEBOARD_FAB2(SCH_1):UPI_CPU1_CPU0_P1P1_DP'<0>:
 C_SIGNAL='@baseboard_fab2_lib.baseboard_fab2(sch_1):upi_cpu1_cpu0_p1p1_dp(0)';
NODE_NAME     U5D1 AA20
 '@BASEBOARD_FAB2_LIB.BASEBOARD_FAB2(SCH_1):PAGE34_I86@CHPSET_LIB.SKX_EXT_B(CHIPS)':
 'UPI1_RX_DP'<19>: CDS_PINID='UPI1_RX_DP(19)';
NODE_NAME     U2D1 M3
 '@BASEBOARD_FAB2_LIB.BASEBOARD_FAB2(SCH_1):PAGE68_I125@CHPSET_LIB.SKX_EXT_B(CHIPS)':
 'UPI1_TX_DN'<0>: CDS_PINID='UPI1_TX_DN(0)';
NET_NAME
'UPI_CPU1_CPU0_P1P1_DP<10>'
 '@BASEBOARD_FAB2_LIB.BASEBOARD_FAB2(SCH_1):UPI_CPU1_CPU0_P1P1_DP'<10>:
 C_SIGNAL='@baseboard_fab2_lib.baseboard_fab2(sch_1):upi_cpu1_cpu0_p1p1_dp(10)';
NODE_NAME     U5D1 P13
 '@BASEBOARD_FAB2_LIB.BASEBOARD_FAB2(SCH_1):PAGE34_I86@CHPSET_LIB.SKX_EXT_B(CHIPS)':
 'UPI1_RX_DP'<9>: CDS_PINID='UPI1_RX_DP(9)';
NODE_NAME     U2D1 G12
 '@BASEBOARD_FAB2_LIB.BASEBOARD_FAB2(SCH_1):PAGE68_I125@CHPSET_LIB.SKX_EXT_B(CHIPS)':
 'UPI1_TX_DP'<10>: CDS_PINID='UPI1_TX_DP(10)';
NET_NAME
'UPI_CPU1_CPU0_P1P1_DP<11>'
 '@BASEBOARD_FAB2_LIB.BASEBOARD_FAB2(SCH_1):UPI_CPU1_CPU0_P1P1_DP'<11>:
 C_SIGNAL='@baseboard_fab2_lib.baseboard_fab2(sch_1):upi_cpu1_cpu0_p1p1_dp(11)';
NODE_NAME     U5D1 M13
 '@BASEBOARD_FAB2_LIB.BASEBOARD_FAB2(SCH_1):PAGE34_I86@CHPSET_LIB.SKX_EXT_B(CHIPS)':
 'UPI1_RX_DP'<8>: CDS_PINID='UPI1_RX_DP(8)';
NODE_NAME     U2D1 G14
 '@BASEBOARD_FAB2_LIB.BASEBOARD_FAB2(SCH_1):PAGE68_I125@CHPSET_LIB.SKX_EXT_B(CHIPS)':
 'UPI1_TX_DN'<11>: CDS_PINID='UPI1_TX_DN(11)';
NET_NAME
'UPI_CPU1_CPU0_P1P1_DP<12>'
 '@BASEBOARD_FAB2_LIB.BASEBOARD_FAB2(SCH_1):UPI_CPU1_CPU0_P1P1_DP'<12>:
 C_SIGNAL='@baseboard_fab2_lib.baseboard_fab2(sch_1):upi_cpu1_cpu0_p1p1_dp(12)';
NODE_NAME     U5D1 N12
 '@BASEBOARD_FAB2_LIB.BASEBOARD_FAB2(SCH_1):PAGE34_I86@CHPSET_LIB.SKX_EXT_B(CHIPS)':
 'UPI1_RX_DP'<7>: CDS_PINID='UPI1_RX_DP(7)';
NODE_NAME     U2D1 E14
 '@BASEBOARD_FAB2_LIB.BASEBOARD_FAB2(SCH_1):PAGE68_I125@CHPSET_LIB.SKX_EXT_B(CHIPS)':
 'UPI1_TX_DP'<12>: CDS_PINID='UPI1_TX_DP(12)';
NET_NAME
'UPI_CPU1_CPU0_P1P1_DP<13>'
 '@BASEBOARD_FAB2_LIB.BASEBOARD_FAB2(SCH_1):UPI_CPU1_CPU0_P1P1_DP'<13>:
 C_SIGNAL='@baseboard_fab2_lib.baseboard_fab2(sch_1):upi_cpu1_cpu0_p1p1_dp(13)';
NODE_NAME     U5D1 T11
 '@BASEBOARD_FAB2_LIB.BASEBOARD_FAB2(SCH_1):PAGE34_I86@CHPSET_LIB.SKX_EXT_B(CHIPS)':
 'UPI1_RX_DP'<6>: CDS_PINID='UPI1_RX_DP(6)';
NODE_NAME     U2D1 H15
 '@BASEBOARD_FAB2_LIB.BASEBOARD_FAB2(SCH_1):PAGE68_I125@CHPSET_LIB.SKX_EXT_B(CHIPS)':
 'UPI1_TX_DP'<13>: CDS_PINID='UPI1_TX_DP(13)';
NET_NAME
'UPI_CPU1_CPU0_P1P1_DP<14>'
 '@BASEBOARD_FAB2_LIB.BASEBOARD_FAB2(SCH_1):UPI_CPU1_CPU0_P1P1_DP'<14>:
 C_SIGNAL='@baseboard_fab2_lib.baseboard_fab2(sch_1):upi_cpu1_cpu0_p1p1_dp(14)';
NODE_NAME     U5D1 U10
 '@BASEBOARD_FAB2_LIB.BASEBOARD_FAB2(SCH_1):PAGE34_I86@CHPSET_LIB.SKX_EXT_B(CHIPS)':
 'UPI1_RX_DP'<5>: CDS_PINID='UPI1_RX_DP(5)';
NODE_NAME     U2D1 G16
 '@BASEBOARD_FAB2_LIB.BASEBOARD_FAB2(SCH_1):PAGE68_I125@CHPSET_LIB.SKX_EXT_B(CHIPS)':
 'UPI1_TX_DP'<14>: CDS_PINID='UPI1_TX_DP(14)';
NET_NAME
'UPI_CPU1_CPU0_P1P1_DP<15>'
 '@BASEBOARD_FAB2_LIB.BASEBOARD_FAB2(SCH_1):UPI_CPU1_CPU0_P1P1_DP'<15>:
 C_SIGNAL='@baseboard_fab2_lib.baseboard_fab2(sch_1):upi_cpu1_cpu0_p1p1_dp(15)';
NODE_NAME     U5D1 N10
 '@BASEBOARD_FAB2_LIB.BASEBOARD_FAB2(SCH_1):PAGE34_I86@CHPSET_LIB.SKX_EXT_B(CHIPS)':
 'UPI1_RX_DP'<4>: CDS_PINID='UPI1_RX_DP(4)';
NODE_NAME     U2D1 L18
 '@BASEBOARD_FAB2_LIB.BASEBOARD_FAB2(SCH_1):PAGE68_I125@CHPSET_LIB.SKX_EXT_B(CHIPS)':
 'UPI1_TX_DP'<15>: CDS_PINID='UPI1_TX_DP(15)';
NET_NAME
'UPI_CPU1_CPU0_P1P1_DP<16>'
 '@BASEBOARD_FAB2_LIB.BASEBOARD_FAB2(SCH_1):UPI_CPU1_CPU0_P1P1_DP'<16>:
 C_SIGNAL='@baseboard_fab2_lib.baseboard_fab2(sch_1):upi_cpu1_cpu0_p1p1_dp(16)';
NODE_NAME     U5D1 R8
 '@BASEBOARD_FAB2_LIB.BASEBOARD_FAB2(SCH_1):PAGE34_I86@CHPSET_LIB.SKX_EXT_B(CHIPS)':
 'UPI1_RX_DP'<3>: CDS_PINID='UPI1_RX_DP(3)';
NODE_NAME     U2D1 J18
 '@BASEBOARD_FAB2_LIB.BASEBOARD_FAB2(SCH_1):PAGE68_I125@CHPSET_LIB.SKX_EXT_B(CHIPS)':
 'UPI1_TX_DP'<16>: CDS_PINID='UPI1_TX_DP(16)';
NET_NAME
'UPI_CPU1_CPU0_P1P1_DP<17>'
 '@BASEBOARD_FAB2_LIB.BASEBOARD_FAB2(SCH_1):UPI_CPU1_CPU0_P1P1_DP'<17>:
 C_SIGNAL='@baseboard_fab2_lib.baseboard_fab2(sch_1):upi_cpu1_cpu0_p1p1_dp(17)';
NODE_NAME     U5D1 U8
 '@BASEBOARD_FAB2_LIB.BASEBOARD_FAB2(SCH_1):PAGE34_I86@CHPSET_LIB.SKX_EXT_B(CHIPS)':
 'UPI1_RX_DP'<2>: CDS_PINID='UPI1_RX_DP(2)';
NODE_NAME     U2D1 H19
 '@BASEBOARD_FAB2_LIB.BASEBOARD_FAB2(SCH_1):PAGE68_I125@CHPSET_LIB.SKX_EXT_B(CHIPS)':
 'UPI1_TX_DP'<17>: CDS_PINID='UPI1_TX_DP(17)';
NET_NAME
'UPI_CPU1_CPU0_P1P1_DP<18>'
 '@BASEBOARD_FAB2_LIB.BASEBOARD_FAB2(SCH_1):UPI_CPU1_CPU0_P1P1_DP'<18>:
 C_SIGNAL='@baseboard_fab2_lib.baseboard_fab2(sch_1):upi_cpu1_cpu0_p1p1_dp(18)';
NODE_NAME     U5D1 T7
 '@BASEBOARD_FAB2_LIB.BASEBOARD_FAB2(SCH_1):PAGE34_I86@CHPSET_LIB.SKX_EXT_B(CHIPS)':
 'UPI1_RX_DP'<1>: CDS_PINID='UPI1_RX_DP(1)';
NODE_NAME     U2D1 F21
 '@BASEBOARD_FAB2_LIB.BASEBOARD_FAB2(SCH_1):PAGE68_I125@CHPSET_LIB.SKX_EXT_B(CHIPS)':
 'UPI1_TX_DN'<18>: CDS_PINID='UPI1_TX_DN(18)';
NET_NAME
'UPI_CPU1_CPU0_P1P1_DP<19>'
 '@BASEBOARD_FAB2_LIB.BASEBOARD_FAB2(SCH_1):UPI_CPU1_CPU0_P1P1_DP'<19>:
 C_SIGNAL='@baseboard_fab2_lib.baseboard_fab2(sch_1):upi_cpu1_cpu0_p1p1_dp(19)';
NODE_NAME     U5D1 R6
 '@BASEBOARD_FAB2_LIB.BASEBOARD_FAB2(SCH_1):PAGE34_I86@CHPSET_LIB.SKX_EXT_B(CHIPS)':
 'UPI1_RX_DP'<0>: CDS_PINID='UPI1_RX_DP(0)';
NODE_NAME     U2D1 H21
 '@BASEBOARD_FAB2_LIB.BASEBOARD_FAB2(SCH_1):PAGE68_I125@CHPSET_LIB.SKX_EXT_B(CHIPS)':
 'UPI1_TX_DN'<19>: CDS_PINID='UPI1_TX_DN(19)';
NET_NAME
'UPI_CPU1_CPU0_P1P1_DP<1>'
 '@BASEBOARD_FAB2_LIB.BASEBOARD_FAB2(SCH_1):UPI_CPU1_CPU0_P1P1_DP'<1>:
 C_SIGNAL='@baseboard_fab2_lib.baseboard_fab2(sch_1):upi_cpu1_cpu0_p1p1_dp(1)';
NODE_NAME     U5D1 W20
 '@BASEBOARD_FAB2_LIB.BASEBOARD_FAB2(SCH_1):PAGE34_I86@CHPSET_LIB.SKX_EXT_B(CHIPS)':
 'UPI1_RX_DP'<18>: CDS_PINID='UPI1_RX_DP(18)';
NODE_NAME     U2D1 L4
 '@BASEBOARD_FAB2_LIB.BASEBOARD_FAB2(SCH_1):PAGE68_I125@CHPSET_LIB.SKX_EXT_B(CHIPS)':
 'UPI1_TX_DN'<1>: CDS_PINID='UPI1_TX_DN(1)';
NET_NAME
'UPI_CPU1_CPU0_P1P1_DP<2>'
 '@BASEBOARD_FAB2_LIB.BASEBOARD_FAB2(SCH_1):UPI_CPU1_CPU0_P1P1_DP'<2>:
 C_SIGNAL='@baseboard_fab2_lib.baseboard_fab2(sch_1):upi_cpu1_cpu0_p1p1_dp(2)';
NODE_NAME     U5D1 Y19
 '@BASEBOARD_FAB2_LIB.BASEBOARD_FAB2(SCH_1):PAGE34_I86@CHPSET_LIB.SKX_EXT_B(CHIPS)':
 'UPI1_RX_DP'<17>: CDS_PINID='UPI1_RX_DP(17)';
NODE_NAME     U2D1 M5
 '@BASEBOARD_FAB2_LIB.BASEBOARD_FAB2(SCH_1):PAGE68_I125@CHPSET_LIB.SKX_EXT_B(CHIPS)':
 'UPI1_TX_DP'<2>: CDS_PINID='UPI1_TX_DP(2)';
NET_NAME
'UPI_CPU1_CPU0_P1P1_DP<3>'
 '@BASEBOARD_FAB2_LIB.BASEBOARD_FAB2(SCH_1):UPI_CPU1_CPU0_P1P1_DP'<3>:
 C_SIGNAL='@baseboard_fab2_lib.baseboard_fab2(sch_1):upi_cpu1_cpu0_p1p1_dp(3)';
NODE_NAME     U5D1 T21
 '@BASEBOARD_FAB2_LIB.BASEBOARD_FAB2(SCH_1):PAGE34_I86@CHPSET_LIB.SKX_EXT_B(CHIPS)':
 'UPI1_RX_DP'<16>: CDS_PINID='UPI1_RX_DP(16)';
NODE_NAME     U2D1 H5
 '@BASEBOARD_FAB2_LIB.BASEBOARD_FAB2(SCH_1):PAGE68_I125@CHPSET_LIB.SKX_EXT_B(CHIPS)':
 'UPI1_TX_DP'<3>: CDS_PINID='UPI1_TX_DP(3)';
NET_NAME
'UPI_CPU1_CPU0_P1P1_DP<4>'
 '@BASEBOARD_FAB2_LIB.BASEBOARD_FAB2(SCH_1):UPI_CPU1_CPU0_P1P1_DP'<4>:
 C_SIGNAL='@baseboard_fab2_lib.baseboard_fab2(sch_1):upi_cpu1_cpu0_p1p1_dp(4)';
NODE_NAME     U5D1 T19
 '@BASEBOARD_FAB2_LIB.BASEBOARD_FAB2(SCH_1):PAGE34_I86@CHPSET_LIB.SKX_EXT_B(CHIPS)':
 'UPI1_RX_DP'<15>: CDS_PINID='UPI1_RX_DP(15)';
NODE_NAME     U2D1 F7
 '@BASEBOARD_FAB2_LIB.BASEBOARD_FAB2(SCH_1):PAGE68_I125@CHPSET_LIB.SKX_EXT_B(CHIPS)':
 'UPI1_TX_DP'<4>: CDS_PINID='UPI1_TX_DP(4)';
NET_NAME
'UPI_CPU1_CPU0_P1P1_DP<5>'
 '@BASEBOARD_FAB2_LIB.BASEBOARD_FAB2(SCH_1):UPI_CPU1_CPU0_P1P1_DP'<5>:
 C_SIGNAL='@baseboard_fab2_lib.baseboard_fab2(sch_1):upi_cpu1_cpu0_p1p1_dp(5)';
NODE_NAME     U5D1 P19
 '@BASEBOARD_FAB2_LIB.BASEBOARD_FAB2(SCH_1):PAGE34_I86@CHPSET_LIB.SKX_EXT_B(CHIPS)':
 'UPI1_RX_DP'<14>: CDS_PINID='UPI1_RX_DP(14)';
NODE_NAME     U2D1 K7
 '@BASEBOARD_FAB2_LIB.BASEBOARD_FAB2(SCH_1):PAGE68_I125@CHPSET_LIB.SKX_EXT_B(CHIPS)':
 'UPI1_TX_DP'<5>: CDS_PINID='UPI1_TX_DP(5)';
NET_NAME
'UPI_CPU1_CPU0_P1P1_DP<6>'
 '@BASEBOARD_FAB2_LIB.BASEBOARD_FAB2(SCH_1):UPI_CPU1_CPU0_P1P1_DP'<6>:
 C_SIGNAL='@baseboard_fab2_lib.baseboard_fab2(sch_1):upi_cpu1_cpu0_p1p1_dp(6)';
NODE_NAME     U5D1 V17
 '@BASEBOARD_FAB2_LIB.BASEBOARD_FAB2(SCH_1):PAGE34_I86@CHPSET_LIB.SKX_EXT_B(CHIPS)':
 'UPI1_RX_DP'<13>: CDS_PINID='UPI1_RX_DP(13)';
NODE_NAME     U2D1 K9
 '@BASEBOARD_FAB2_LIB.BASEBOARD_FAB2(SCH_1):PAGE68_I125@CHPSET_LIB.SKX_EXT_B(CHIPS)':
 'UPI1_TX_DN'<6>: CDS_PINID='UPI1_TX_DN(6)';
NET_NAME
'UPI_CPU1_CPU0_P1P1_DP<7>'
 '@BASEBOARD_FAB2_LIB.BASEBOARD_FAB2(SCH_1):UPI_CPU1_CPU0_P1P1_DP'<7>:
 C_SIGNAL='@baseboard_fab2_lib.baseboard_fab2(sch_1):upi_cpu1_cpu0_p1p1_dp(7)';
NODE_NAME     U5D1 W16
 '@BASEBOARD_FAB2_LIB.BASEBOARD_FAB2(SCH_1):PAGE34_I86@CHPSET_LIB.SKX_EXT_B(CHIPS)':
 'UPI1_RX_DP'<12>: CDS_PINID='UPI1_RX_DP(12)';
NODE_NAME     U2D1 D9
 '@BASEBOARD_FAB2_LIB.BASEBOARD_FAB2(SCH_1):PAGE68_I125@CHPSET_LIB.SKX_EXT_B(CHIPS)':
 'UPI1_TX_DN'<7>: CDS_PINID='UPI1_TX_DN(7)';
NET_NAME
'UPI_CPU1_CPU0_P1P1_DP<8>'
 '@BASEBOARD_FAB2_LIB.BASEBOARD_FAB2(SCH_1):UPI_CPU1_CPU0_P1P1_DP'<8>:
 C_SIGNAL='@baseboard_fab2_lib.baseboard_fab2(sch_1):upi_cpu1_cpu0_p1p1_dp(8)';
NODE_NAME     U5D1 N16
 '@BASEBOARD_FAB2_LIB.BASEBOARD_FAB2(SCH_1):PAGE34_I86@CHPSET_LIB.SKX_EXT_B(CHIPS)':
 'UPI1_RX_DP'<11>: CDS_PINID='UPI1_RX_DP(11)';
NODE_NAME     U2D1 F11
 '@BASEBOARD_FAB2_LIB.BASEBOARD_FAB2(SCH_1):PAGE68_I125@CHPSET_LIB.SKX_EXT_B(CHIPS)':
 'UPI1_TX_DN'<8>: CDS_PINID='UPI1_TX_DN(8)';
NET_NAME
'UPI_CPU1_CPU0_P1P1_DP<9>'
 '@BASEBOARD_FAB2_LIB.BASEBOARD_FAB2(SCH_1):UPI_CPU1_CPU0_P1P1_DP'<9>:
 C_SIGNAL='@baseboard_fab2_lib.baseboard_fab2(sch_1):upi_cpu1_cpu0_p1p1_dp(9)';
NODE_NAME     U5D1 T15
 '@BASEBOARD_FAB2_LIB.BASEBOARD_FAB2(SCH_1):PAGE34_I86@CHPSET_LIB.SKX_EXT_B(CHIPS)':
 'UPI1_RX_DP'<10>: CDS_PINID='UPI1_RX_DP(10)';
NODE_NAME     U2D1 H9
 '@BASEBOARD_FAB2_LIB.BASEBOARD_FAB2(SCH_1):PAGE68_I125@CHPSET_LIB.SKX_EXT_B(CHIPS)':
 'UPI1_TX_DP'<9>: CDS_PINID='UPI1_TX_DP(9)';
NET_NAME
'USB2_P01_DN'
 '@BASEBOARD_FAB2_LIB.BASEBOARD_FAB2(SCH_1):USB2_P01_DN':
 C_SIGNAL='@baseboard_fab2_lib.baseboard_fab2(sch_1):usb2_p01_dn';
NODE_NAME     U7C1 BY60
 '@BASEBOARD_FAB2_LIB.BASEBOARD_FAB2(SCH_1):PAGE115_I74@MSTR_U_PROC.LBG_CORE_QAT_EXT_D(CHIPS)':
 'USB2N_1': CDS_PINID='USB2N_1';
NODE_NAME     R1M6 1
 '@BASEBOARD_FAB2_LIB.BASEBOARD_FAB2(SCH_1):PAGE176_I31@MSTR_DISCRETE.RES(CHIPS)':
 'A': CDS_PINID='A';
NODE_NAME     L1M2 1
 '@BASEBOARD_FAB2_LIB.BASEBOARD_FAB2(SCH_1):PAGE176_I181@MSTR_DISCRETE.CHOKE_4PIN(CHIPS)':
 'A1': CDS_PINID='A1';
NET_NAME
'USB2_P01_DP'
 '@BASEBOARD_FAB2_LIB.BASEBOARD_FAB2(SCH_1):USB2_P01_DP':
 C_SIGNAL='@baseboard_fab2_lib.baseboard_fab2(sch_1):usb2_p01_dp';
NODE_NAME     U7C1 BV60
 '@BASEBOARD_FAB2_LIB.BASEBOARD_FAB2(SCH_1):PAGE115_I74@MSTR_U_PROC.LBG_CORE_QAT_EXT_D(CHIPS)':
 'USB2P_1': CDS_PINID='USB2P_1';
NODE_NAME     R1M5 1
 '@BASEBOARD_FAB2_LIB.BASEBOARD_FAB2(SCH_1):PAGE176_I16@MSTR_DISCRETE.RES(CHIPS)':
 'A': CDS_PINID='A';
NODE_NAME     L1M2 2
 '@BASEBOARD_FAB2_LIB.BASEBOARD_FAB2(SCH_1):PAGE176_I181@MSTR_DISCRETE.CHOKE_4PIN(CHIPS)':
 'A2': CDS_PINID='A2';
NET_NAME
'USB2_P01_ESD_DN'
 '@BASEBOARD_FAB2_LIB.BASEBOARD_FAB2(SCH_1):USB2_P01_ESD_DN':
 C_SIGNAL='@baseboard_fab2_lib.baseboard_fab2(sch_1):usb2_p01_esd_dn';
NODE_NAME     R1M6 2
 '@BASEBOARD_FAB2_LIB.BASEBOARD_FAB2(SCH_1):PAGE176_I31@MSTR_DISCRETE.RES(CHIPS)':
 'B': CDS_PINID='B';
NODE_NAME     J9B1 2
 '@BASEBOARD_FAB2_LIB.BASEBOARD_FAB2(SCH_1):PAGE176_I69@MSTR_CONN.CONN9_H51826001(CHIPS)':
 'DN': CDS_PINID='DN';
NODE_NAME     CR1M2 2
 '@BASEBOARD_FAB2_LIB.BASEBOARD_FAB2(SCH_1):PAGE176_I98@MSTR_DISCRETE.DIODEAC_DUAL_ARRAY(CHIPS)':
 'AC1': CDS_PINID='AC1';
NODE_NAME     CR1M2 8
 '@BASEBOARD_FAB2_LIB.BASEBOARD_FAB2(SCH_1):PAGE176_I98@MSTR_DISCRETE.DIODEAC_DUAL_ARRAY(CHIPS)':
 'OUT1': CDS_PINID='OUT1';
NODE_NAME     L1M2 4
 '@BASEBOARD_FAB2_LIB.BASEBOARD_FAB2(SCH_1):PAGE176_I181@MSTR_DISCRETE.CHOKE_4PIN(CHIPS)':
 'B2': CDS_PINID='B2';
NET_NAME
'USB2_P01_ESD_DP'
 '@BASEBOARD_FAB2_LIB.BASEBOARD_FAB2(SCH_1):USB2_P01_ESD_DP':
 C_SIGNAL='@baseboard_fab2_lib.baseboard_fab2(sch_1):usb2_p01_esd_dp';
NODE_NAME     R1M5 2
 '@BASEBOARD_FAB2_LIB.BASEBOARD_FAB2(SCH_1):PAGE176_I16@MSTR_DISCRETE.RES(CHIPS)':
 'B': CDS_PINID='B';
NODE_NAME     J9B1 3
 '@BASEBOARD_FAB2_LIB.BASEBOARD_FAB2(SCH_1):PAGE176_I69@MSTR_CONN.CONN9_H51826001(CHIPS)':
 'DP': CDS_PINID='DP';
NODE_NAME     CR1M2 1
 '@BASEBOARD_FAB2_LIB.BASEBOARD_FAB2(SCH_1):PAGE176_I98@MSTR_DISCRETE.DIODEAC_DUAL_ARRAY(CHIPS)':
 'AC0': CDS_PINID='AC0';
NODE_NAME     CR1M2 9
 '@BASEBOARD_FAB2_LIB.BASEBOARD_FAB2(SCH_1):PAGE176_I98@MSTR_DISCRETE.DIODEAC_DUAL_ARRAY(CHIPS)':
 'OUT0': CDS_PINID='OUT0';
NODE_NAME     L1M2 3
 '@BASEBOARD_FAB2_LIB.BASEBOARD_FAB2(SCH_1):PAGE176_I181@MSTR_DISCRETE.CHOKE_4PIN(CHIPS)':
 'B1': CDS_PINID='B1';
NET_NAME
'USB2_P02_DN'
 '@BASEBOARD_FAB2_LIB.BASEBOARD_FAB2(SCH_1):USB2_P02_DN':
 C_SIGNAL='@baseboard_fab2_lib.baseboard_fab2(sch_1):usb2_p02_dn';
NODE_NAME     CONX8 57
 '@BASEBOARD_FAB2_LIB.BASEBOARD_FAB2(SCH_1):PAGE245_I48@W_HDL.SMC-CONN60A-22-GP(CHIPS)':
 '57': CDS_PINID='\57\';
NODE_NAME     R1W19 2
 '@BASEBOARD_FAB2_LIB.BASEBOARD_FAB2(SCH_1):PAGE115_I122@MSTR_DISCRETE.RES(CHIPS)':
 'B': CDS_PINID='B';
NET_NAME
'USB2_P02_DN_R'
 '@BASEBOARD_FAB2_LIB.BASEBOARD_FAB2(SCH_1):USB2_P02_DN_R':
 C_SIGNAL='@baseboard_fab2_lib.baseboard_fab2(sch_1):usb2_p02_dn_r';
NODE_NAME     U7C1 CA61
 '@BASEBOARD_FAB2_LIB.BASEBOARD_FAB2(SCH_1):PAGE115_I74@MSTR_U_PROC.LBG_CORE_QAT_EXT_D(CHIPS)':
 'USB2N_2': CDS_PINID='USB2N_2';
NODE_NAME     R1W19 1
 '@BASEBOARD_FAB2_LIB.BASEBOARD_FAB2(SCH_1):PAGE115_I122@MSTR_DISCRETE.RES(CHIPS)':
 'A': CDS_PINID='A';
NET_NAME
'USB2_P02_DP'
 '@BASEBOARD_FAB2_LIB.BASEBOARD_FAB2(SCH_1):USB2_P02_DP':
 C_SIGNAL='@baseboard_fab2_lib.baseboard_fab2(sch_1):usb2_p02_dp';
NODE_NAME     CONX8 59
 '@BASEBOARD_FAB2_LIB.BASEBOARD_FAB2(SCH_1):PAGE245_I48@W_HDL.SMC-CONN60A-22-GP(CHIPS)':
 '59': CDS_PINID='\59\';
NODE_NAME     R1W18 2
 '@BASEBOARD_FAB2_LIB.BASEBOARD_FAB2(SCH_1):PAGE115_I123@MSTR_DISCRETE.RES(CHIPS)':
 'B': CDS_PINID='B';
NET_NAME
'USB2_P02_DP_R'
 '@BASEBOARD_FAB2_LIB.BASEBOARD_FAB2(SCH_1):USB2_P02_DP_R':
 C_SIGNAL='@baseboard_fab2_lib.baseboard_fab2(sch_1):usb2_p02_dp_r';
NODE_NAME     U7C1 BW61
 '@BASEBOARD_FAB2_LIB.BASEBOARD_FAB2(SCH_1):PAGE115_I74@MSTR_U_PROC.LBG_CORE_QAT_EXT_D(CHIPS)':
 'USB2P_2': CDS_PINID='USB2P_2';
NODE_NAME     R1W18 1
 '@BASEBOARD_FAB2_LIB.BASEBOARD_FAB2(SCH_1):PAGE115_I123@MSTR_DISCRETE.RES(CHIPS)':
 'A': CDS_PINID='A';
NET_NAME
'USB2_PCH_BMC_P5_DN'
 '@BASEBOARD_FAB2_LIB.BASEBOARD_FAB2(SCH_1):USB2_PCH_BMC_P5_DN':
 C_SIGNAL='@baseboard_fab2_lib.baseboard_fab2(sch_1):usb2_pch_bmc_p5_dn';
NODE_NAME     U25W4 A6
 '@BASEBOARD_FAB2_LIB.BASEBOARD_FAB2(SCH_1):PAGE146_I104@W_HDL.AST2520A1-GP-GP(CHIPS)':
 'USB2B_DN': CDS_PINID='USB2B_DN';
NODE_NAME     R1W15 2
 '@BASEBOARD_FAB2_LIB.BASEBOARD_FAB2(SCH_1):PAGE115_I119@MSTR_DISCRETE.RES(CHIPS)':
 'B': CDS_PINID='B';
NET_NAME
'USB2_PCH_BMC_P5_DN_R'
 '@BASEBOARD_FAB2_LIB.BASEBOARD_FAB2(SCH_1):USB2_PCH_BMC_P5_DN_R':
 C_SIGNAL='@baseboard_fab2_lib.baseboard_fab2(sch_1):usb2_pch_bmc_p5_dn_r';
NODE_NAME     U7C1 BY58
 '@BASEBOARD_FAB2_LIB.BASEBOARD_FAB2(SCH_1):PAGE115_I74@MSTR_U_PROC.LBG_CORE_QAT_EXT_D(CHIPS)':
 'USB2N_5': CDS_PINID='USB2N_5';
NODE_NAME     R1W15 1
 '@BASEBOARD_FAB2_LIB.BASEBOARD_FAB2(SCH_1):PAGE115_I119@MSTR_DISCRETE.RES(CHIPS)':
 'A': CDS_PINID='A';
NET_NAME
'USB2_PCH_BMC_P5_DP'
 '@BASEBOARD_FAB2_LIB.BASEBOARD_FAB2(SCH_1):USB2_PCH_BMC_P5_DP':
 C_SIGNAL='@baseboard_fab2_lib.baseboard_fab2(sch_1):usb2_pch_bmc_p5_dp';
NODE_NAME     U25W4 B6
 '@BASEBOARD_FAB2_LIB.BASEBOARD_FAB2(SCH_1):PAGE146_I104@W_HDL.AST2520A1-GP-GP(CHIPS)':
 'USB2B_DP': CDS_PINID='USB2B_DP';
NODE_NAME     R1W14 2
 '@BASEBOARD_FAB2_LIB.BASEBOARD_FAB2(SCH_1):PAGE115_I118@MSTR_DISCRETE.RES(CHIPS)':
 'B': CDS_PINID='B';
NET_NAME
'USB2_PCH_BMC_P5_DP_R'
 '@BASEBOARD_FAB2_LIB.BASEBOARD_FAB2(SCH_1):USB2_PCH_BMC_P5_DP_R':
 C_SIGNAL='@baseboard_fab2_lib.baseboard_fab2(sch_1):usb2_pch_bmc_p5_dp_r';
NODE_NAME     U7C1 BV58
 '@BASEBOARD_FAB2_LIB.BASEBOARD_FAB2(SCH_1):PAGE115_I74@MSTR_U_PROC.LBG_CORE_QAT_EXT_D(CHIPS)':
 'USB2P_5': CDS_PINID='USB2P_5';
NODE_NAME     R1W14 1
 '@BASEBOARD_FAB2_LIB.BASEBOARD_FAB2(SCH_1):PAGE115_I118@MSTR_DISCRETE.RES(CHIPS)':
 'A': CDS_PINID='A';
NET_NAME
'USB3_P01_C_TXN'
 '@BASEBOARD_FAB2_LIB.BASEBOARD_FAB2(SCH_1):USB3_P01_C_TXN':
 C_SIGNAL='@baseboard_fab2_lib.baseboard_fab2(sch_1):usb3_p01_c_txn';
NODE_NAME     L30W2 4
 '@BASEBOARD_FAB2_LIB.BASEBOARD_FAB2(SCH_1):PAGE253_I11@MSTR_DISCRETE.CHOKE_4PIN(CHIPS)':
 '4': CDS_PINID='\4\';
NODE_NAME     R30W3 1
 '@BASEBOARD_FAB2_LIB.BASEBOARD_FAB2(SCH_1):PAGE253_I15@MSTR_DISCRETE.RES(CHIPS)':
 'A': CDS_PINID='A';
NODE_NAME     C30W1 2
 '@BASEBOARD_FAB2_LIB.BASEBOARD_FAB2(SCH_1):PAGE253_I20@DEV_DISCRETE.CAP_A(CHIPS)':
 'B': CDS_PINID='B';
NET_NAME
'USB3_P01_C_TXP'
 '@BASEBOARD_FAB2_LIB.BASEBOARD_FAB2(SCH_1):USB3_P01_C_TXP':
 C_SIGNAL='@baseboard_fab2_lib.baseboard_fab2(sch_1):usb3_p01_c_txp';
NODE_NAME     L30W2 1
 '@BASEBOARD_FAB2_LIB.BASEBOARD_FAB2(SCH_1):PAGE253_I11@MSTR_DISCRETE.CHOKE_4PIN(CHIPS)':
 '1': CDS_PINID='\1\';
NODE_NAME     R30W4 1
 '@BASEBOARD_FAB2_LIB.BASEBOARD_FAB2(SCH_1):PAGE253_I14@MSTR_DISCRETE.RES(CHIPS)':
 'A': CDS_PINID='A';
NODE_NAME     C30W2 2
 '@BASEBOARD_FAB2_LIB.BASEBOARD_FAB2(SCH_1):PAGE253_I19@DEV_DISCRETE.CAP_A(CHIPS)':
 'B': CDS_PINID='B';
NET_NAME
'USB3_P01_FB_RXN'
 '@BASEBOARD_FAB2_LIB.BASEBOARD_FAB2(SCH_1):USB3_P01_FB_RXN':
 C_SIGNAL='@baseboard_fab2_lib.baseboard_fab2(sch_1):usb3_p01_fb_rxn';
NODE_NAME     CR30W1 4
 '@BASEBOARD_FAB2_LIB.BASEBOARD_FAB2(SCH_1):PAGE253_I5@MSTR_DISCRETE.DIODEAC_DUAL_ARRAY(CHIPS)':
 'AC2': CDS_PINID='AC2';
NODE_NAME     CR30W1 7
 '@BASEBOARD_FAB2_LIB.BASEBOARD_FAB2(SCH_1):PAGE253_I5@MSTR_DISCRETE.DIODEAC_DUAL_ARRAY(CHIPS)':
 'OUT2': CDS_PINID='OUT2';
NODE_NAME     R30W1 2
 '@BASEBOARD_FAB2_LIB.BASEBOARD_FAB2(SCH_1):PAGE253_I13@MSTR_DISCRETE.RES(CHIPS)':
 'B': CDS_PINID='B';
NODE_NAME     L30W1 3
 '@BASEBOARD_FAB2_LIB.BASEBOARD_FAB2(SCH_1):PAGE253_I16@MSTR_DISCRETE.CHOKE_4PIN(CHIPS)':
 '3': CDS_PINID='\3\';
NODE_NAME     J30W1 B10
 '@BASEBOARD_FAB2_LIB.BASEBOARD_FAB2(SCH_1):PAGE253_I26@W_HDL.SKT-USB32-8-GP(CHIPS)':
 'SSRXN1': CDS_PINID='SSRXN1';
NET_NAME
'USB3_P01_FB_RXP'
 '@BASEBOARD_FAB2_LIB.BASEBOARD_FAB2(SCH_1):USB3_P01_FB_RXP':
 C_SIGNAL='@baseboard_fab2_lib.baseboard_fab2(sch_1):usb3_p01_fb_rxp';
NODE_NAME     CR30W1 5
 '@BASEBOARD_FAB2_LIB.BASEBOARD_FAB2(SCH_1):PAGE253_I5@MSTR_DISCRETE.DIODEAC_DUAL_ARRAY(CHIPS)':
 'AC3': CDS_PINID='AC3';
NODE_NAME     CR30W1 6
 '@BASEBOARD_FAB2_LIB.BASEBOARD_FAB2(SCH_1):PAGE253_I5@MSTR_DISCRETE.DIODEAC_DUAL_ARRAY(CHIPS)':
 'OUT3': CDS_PINID='OUT3';
NODE_NAME     R30W2 2
 '@BASEBOARD_FAB2_LIB.BASEBOARD_FAB2(SCH_1):PAGE253_I12@MSTR_DISCRETE.RES(CHIPS)':
 'B': CDS_PINID='B';
NODE_NAME     L30W1 2
 '@BASEBOARD_FAB2_LIB.BASEBOARD_FAB2(SCH_1):PAGE253_I16@MSTR_DISCRETE.CHOKE_4PIN(CHIPS)':
 '2': CDS_PINID='\2\';
NODE_NAME     J30W1 B11
 '@BASEBOARD_FAB2_LIB.BASEBOARD_FAB2(SCH_1):PAGE253_I26@W_HDL.SKT-USB32-8-GP(CHIPS)':
 'SSRXP1': CDS_PINID='SSRXP1';
NET_NAME
'USB3_P01_FB_TXN'
 '@BASEBOARD_FAB2_LIB.BASEBOARD_FAB2(SCH_1):USB3_P01_FB_TXN':
 C_SIGNAL='@baseboard_fab2_lib.baseboard_fab2(sch_1):usb3_p01_fb_txn';
NODE_NAME     CR30W1 1
 '@BASEBOARD_FAB2_LIB.BASEBOARD_FAB2(SCH_1):PAGE253_I5@MSTR_DISCRETE.DIODEAC_DUAL_ARRAY(CHIPS)':
 'AC0': CDS_PINID='AC0';
NODE_NAME     CR30W1 9
 '@BASEBOARD_FAB2_LIB.BASEBOARD_FAB2(SCH_1):PAGE253_I5@MSTR_DISCRETE.DIODEAC_DUAL_ARRAY(CHIPS)':
 'OUT0': CDS_PINID='OUT0';
NODE_NAME     L30W2 3
 '@BASEBOARD_FAB2_LIB.BASEBOARD_FAB2(SCH_1):PAGE253_I11@MSTR_DISCRETE.CHOKE_4PIN(CHIPS)':
 '3': CDS_PINID='\3\';
NODE_NAME     R30W3 2
 '@BASEBOARD_FAB2_LIB.BASEBOARD_FAB2(SCH_1):PAGE253_I15@MSTR_DISCRETE.RES(CHIPS)':
 'B': CDS_PINID='B';
NODE_NAME     J30W1 A3
 '@BASEBOARD_FAB2_LIB.BASEBOARD_FAB2(SCH_1):PAGE253_I26@W_HDL.SKT-USB32-8-GP(CHIPS)':
 'SSTXN1': CDS_PINID='SSTXN1';
NET_NAME
'USB3_P01_FB_TXP'
 '@BASEBOARD_FAB2_LIB.BASEBOARD_FAB2(SCH_1):USB3_P01_FB_TXP':
 C_SIGNAL='@baseboard_fab2_lib.baseboard_fab2(sch_1):usb3_p01_fb_txp';
NODE_NAME     CR30W1 2
 '@BASEBOARD_FAB2_LIB.BASEBOARD_FAB2(SCH_1):PAGE253_I5@MSTR_DISCRETE.DIODEAC_DUAL_ARRAY(CHIPS)':
 'AC1': CDS_PINID='AC1';
NODE_NAME     CR30W1 8
 '@BASEBOARD_FAB2_LIB.BASEBOARD_FAB2(SCH_1):PAGE253_I5@MSTR_DISCRETE.DIODEAC_DUAL_ARRAY(CHIPS)':
 'OUT1': CDS_PINID='OUT1';
NODE_NAME     L30W2 2
 '@BASEBOARD_FAB2_LIB.BASEBOARD_FAB2(SCH_1):PAGE253_I11@MSTR_DISCRETE.CHOKE_4PIN(CHIPS)':
 '2': CDS_PINID='\2\';
NODE_NAME     R30W4 2
 '@BASEBOARD_FAB2_LIB.BASEBOARD_FAB2(SCH_1):PAGE253_I14@MSTR_DISCRETE.RES(CHIPS)':
 'B': CDS_PINID='B';
NODE_NAME     J30W1 A2
 '@BASEBOARD_FAB2_LIB.BASEBOARD_FAB2(SCH_1):PAGE253_I26@W_HDL.SKT-USB32-8-GP(CHIPS)':
 'SSTXP1': CDS_PINID='SSTXP1';
NET_NAME
'USB3_P01_RXN'
 '@BASEBOARD_FAB2_LIB.BASEBOARD_FAB2(SCH_1):USB3_P01_RXN':
 C_SIGNAL='@baseboard_fab2_lib.baseboard_fab2(sch_1):usb3_p01_rxn';
NODE_NAME     U7C1 BK71
 '@BASEBOARD_FAB2_LIB.BASEBOARD_FAB2(SCH_1):PAGE115_I74@MSTR_U_PROC.LBG_CORE_QAT_EXT_D(CHIPS)':
 'USB3_1_RXN': CDS_PINID='USB3_1_RXN';
NODE_NAME     R30W1 1
 '@BASEBOARD_FAB2_LIB.BASEBOARD_FAB2(SCH_1):PAGE253_I13@MSTR_DISCRETE.RES(CHIPS)':
 'A': CDS_PINID='A';
NODE_NAME     L30W1 4
 '@BASEBOARD_FAB2_LIB.BASEBOARD_FAB2(SCH_1):PAGE253_I16@MSTR_DISCRETE.CHOKE_4PIN(CHIPS)':
 '4': CDS_PINID='\4\';
NET_NAME
'USB3_P01_RXP'
 '@BASEBOARD_FAB2_LIB.BASEBOARD_FAB2(SCH_1):USB3_P01_RXP':
 C_SIGNAL='@baseboard_fab2_lib.baseboard_fab2(sch_1):usb3_p01_rxp';
NODE_NAME     U7C1 BK69
 '@BASEBOARD_FAB2_LIB.BASEBOARD_FAB2(SCH_1):PAGE115_I74@MSTR_U_PROC.LBG_CORE_QAT_EXT_D(CHIPS)':
 'USB3_1_RXP': CDS_PINID='USB3_1_RXP';
NODE_NAME     R30W2 1
 '@BASEBOARD_FAB2_LIB.BASEBOARD_FAB2(SCH_1):PAGE253_I12@MSTR_DISCRETE.RES(CHIPS)':
 'A': CDS_PINID='A';
NODE_NAME     L30W1 1
 '@BASEBOARD_FAB2_LIB.BASEBOARD_FAB2(SCH_1):PAGE253_I16@MSTR_DISCRETE.CHOKE_4PIN(CHIPS)':
 '1': CDS_PINID='\1\';
NET_NAME
'USB3_P01_TXN'
 '@BASEBOARD_FAB2_LIB.BASEBOARD_FAB2(SCH_1):USB3_P01_TXN':
 C_SIGNAL='@baseboard_fab2_lib.baseboard_fab2(sch_1):usb3_p01_txn';
NODE_NAME     U7C1 BL52
 '@BASEBOARD_FAB2_LIB.BASEBOARD_FAB2(SCH_1):PAGE115_I74@MSTR_U_PROC.LBG_CORE_QAT_EXT_D(CHIPS)':
 'USB3_1_TXN': CDS_PINID='USB3_1_TXN';
NODE_NAME     C30W1 1
 '@BASEBOARD_FAB2_LIB.BASEBOARD_FAB2(SCH_1):PAGE253_I20@DEV_DISCRETE.CAP_A(CHIPS)':
 'A': CDS_PINID='A';
NET_NAME
'USB3_P01_TXP'
 '@BASEBOARD_FAB2_LIB.BASEBOARD_FAB2(SCH_1):USB3_P01_TXP':
 C_SIGNAL='@baseboard_fab2_lib.baseboard_fab2(sch_1):usb3_p01_txp';
NODE_NAME     U7C1 BK54
 '@BASEBOARD_FAB2_LIB.BASEBOARD_FAB2(SCH_1):PAGE115_I74@MSTR_U_PROC.LBG_CORE_QAT_EXT_D(CHIPS)':
 'USB3_1_TXP': CDS_PINID='USB3_1_TXP';
NODE_NAME     C30W2 1
 '@BASEBOARD_FAB2_LIB.BASEBOARD_FAB2(SCH_1):PAGE253_I19@DEV_DISCRETE.CAP_A(CHIPS)':
 'A': CDS_PINID='A';
NET_NAME
'USB_PCH_BMC_P4_DN'
 '@BASEBOARD_FAB2_LIB.BASEBOARD_FAB2(SCH_1):USB_PCH_BMC_P4_DN':
 C_SIGNAL='@baseboard_fab2_lib.baseboard_fab2(sch_1):usb_pch_bmc_p4_dn';
NODE_NAME     U25W4 A8
 '@BASEBOARD_FAB2_LIB.BASEBOARD_FAB2(SCH_1):PAGE146_I104@W_HDL.AST2520A1-GP-GP(CHIPS)':
 'USB2A_DN': CDS_PINID='USB2A_DN';
NODE_NAME     R1W17 2
 '@BASEBOARD_FAB2_LIB.BASEBOARD_FAB2(SCH_1):PAGE115_I120@MSTR_DISCRETE.RES(CHIPS)':
 'B': CDS_PINID='B';
NET_NAME
'USB_PCH_BMC_P4_DN_R'
 '@BASEBOARD_FAB2_LIB.BASEBOARD_FAB2(SCH_1):USB_PCH_BMC_P4_DN_R':
 C_SIGNAL='@baseboard_fab2_lib.baseboard_fab2(sch_1):usb_pch_bmc_p4_dn_r';
NODE_NAME     U7C1 BY62
 '@BASEBOARD_FAB2_LIB.BASEBOARD_FAB2(SCH_1):PAGE115_I74@MSTR_U_PROC.LBG_CORE_QAT_EXT_D(CHIPS)':
 'USB2N_4': CDS_PINID='USB2N_4';
NODE_NAME     R1W17 1
 '@BASEBOARD_FAB2_LIB.BASEBOARD_FAB2(SCH_1):PAGE115_I120@MSTR_DISCRETE.RES(CHIPS)':
 'A': CDS_PINID='A';
NET_NAME
'USB_PCH_BMC_P4_DP'
 '@BASEBOARD_FAB2_LIB.BASEBOARD_FAB2(SCH_1):USB_PCH_BMC_P4_DP':
 C_SIGNAL='@baseboard_fab2_lib.baseboard_fab2(sch_1):usb_pch_bmc_p4_dp';
NODE_NAME     U25W4 A7
 '@BASEBOARD_FAB2_LIB.BASEBOARD_FAB2(SCH_1):PAGE146_I104@W_HDL.AST2520A1-GP-GP(CHIPS)':
 'USB2A_DP': CDS_PINID='USB2A_DP';
NODE_NAME     R1W16 2
 '@BASEBOARD_FAB2_LIB.BASEBOARD_FAB2(SCH_1):PAGE115_I121@MSTR_DISCRETE.RES(CHIPS)':
 'B': CDS_PINID='B';
NET_NAME
'USB_PCH_BMC_P4_DP_R'
 '@BASEBOARD_FAB2_LIB.BASEBOARD_FAB2(SCH_1):USB_PCH_BMC_P4_DP_R':
 C_SIGNAL='@baseboard_fab2_lib.baseboard_fab2(sch_1):usb_pch_bmc_p4_dp_r';
NODE_NAME     U7C1 BV62
 '@BASEBOARD_FAB2_LIB.BASEBOARD_FAB2(SCH_1):PAGE115_I74@MSTR_U_PROC.LBG_CORE_QAT_EXT_D(CHIPS)':
 'USB2P_4': CDS_PINID='USB2P_4';
NODE_NAME     R1W16 1
 '@BASEBOARD_FAB2_LIB.BASEBOARD_FAB2(SCH_1):PAGE115_I121@MSTR_DISCRETE.RES(CHIPS)':
 'A': CDS_PINID='A';
NET_NAME
'UV_HIGH_SET'
 '@BASEBOARD_FAB2_LIB.BASEBOARD_FAB2(SCH_1):UV_HIGH_SET':
 C_SIGNAL='@baseboard_fab2_lib.baseboard_fab2(sch_1):uv_high_set';
NODE_NAME     J9G1 3
 '@BASEBOARD_FAB2_LIB.BASEBOARD_FAB2(SCH_1):PAGE137_I128@MSTR_CONN.CONN12_C73564003(CHIPS)':
 'IO3': CDS_PINID='IO3';
NODE_NAME     Q6W1 1
 '@BASEBOARD_FAB2_LIB.BASEBOARD_FAB2(SCH_1):PAGE200_I225@MSTR_DISCRETE.FET_N(CHIPS)':
 'GATE': CDS_PINID='GATE';
NODE_NAME     U25W4 T20
 '@BASEBOARD_FAB2_LIB.BASEBOARD_FAB2(SCH_1):PAGE146_I104@W_HDL.AST2520A1-GP-GP(CHIPS)':
 'GPIOAA5_VPOR7_NORD5_SALT12': CDS_PINID='GPIOAA5_VPOR7_NORD5_SALT12';
NET_NAME
'UV_HIGH_SET_N'
 '@BASEBOARD_FAB2_LIB.BASEBOARD_FAB2(SCH_1):UV_HIGH_SET_N':
 C_SIGNAL='@baseboard_fab2_lib.baseboard_fab2(sch_1):uv_high_set_n';
NODE_NAME     Q6W1 3
 '@BASEBOARD_FAB2_LIB.BASEBOARD_FAB2(SCH_1):PAGE200_I225@MSTR_DISCRETE.FET_N(CHIPS)':
 'DRN': CDS_PINID='DRN';
NODE_NAME     R6W3 1
 '@BASEBOARD_FAB2_LIB.BASEBOARD_FAB2(SCH_1):PAGE200_I250@W_HDL.232KR2F-2-GP(CHIPS)':
 '1': CDS_PINID='\1\';
NET_NAME
'VCCBAT_TW12'
 '@BASEBOARD_FAB2_LIB.BASEBOARD_FAB2(SCH_1):VCCBAT_TW12':
 C_SIGNAL='@baseboard_fab2_lib.baseboard_fab2(sch_1):vccbat_tw12';
NODE_NAME     R25W59 2
 '@BASEBOARD_FAB2_LIB.BASEBOARD_FAB2(SCH_1):PAGE148_I16@MSTR_DISCRETE.RES(CHIPS)':
 'B': CDS_PINID='B';
NODE_NAME     U25W4 E4
 '@BASEBOARD_FAB2_LIB.BASEBOARD_FAB2(SCH_1):PAGE148_I28@W_HDL.AST2520A1-GP-GP(CHIPS)':
 'BATVDD': CDS_PINID='BATVDD';
NET_NAME
'VCC_ADCAV3V3'
 '@BASEBOARD_FAB2_LIB.BASEBOARD_FAB2(SCH_1):VCC_ADCAV3V3':
 C_SIGNAL='@baseboard_fab2_lib.baseboard_fab2(sch_1):vcc_adcav3v3';
NODE_NAME     U25W4 J6
 '@BASEBOARD_FAB2_LIB.BASEBOARD_FAB2(SCH_1):PAGE148_I28@W_HDL.AST2520A1-GP-GP(CHIPS)':
 'ADCAV33': CDS_PINID='ADCAV33';
NODE_NAME     FB2T3 2
 '@BASEBOARD_FAB2_LIB.BASEBOARD_FAB2(SCH_1):PAGE149_I85@W_HDL.HCB1608KF-800T30-GP(CHIPS)':
 '2': CDS_PINID='\2\';
NODE_NAME     C25W32 1
 '@BASEBOARD_FAB2_LIB.BASEBOARD_FAB2(SCH_1):PAGE149_I99@MSTR_DISCRETE.CAP(CHIPS)':
 'A': CDS_PINID='A';
NODE_NAME     C25W33 1
 '@BASEBOARD_FAB2_LIB.BASEBOARD_FAB2(SCH_1):PAGE149_I102@MSTR_DISCRETE.CAP(CHIPS)':
 'A': CDS_PINID='A';
NODE_NAME     C25W31 1
 '@BASEBOARD_FAB2_LIB.BASEBOARD_FAB2(SCH_1):PAGE149_I119@DEV_DISCRETE.CAP_A(CHIPS)':
 'A': CDS_PINID='A';
NODE_NAME     C25W7 2
 '@BASEBOARD_FAB2_LIB.BASEBOARD_FAB2(SCH_1):PAGE147_I161@DEV_DISCRETE.CAP_A(CHIPS)':
 'B': CDS_PINID='B';
NET_NAME
'VCC_A_1V1'
 '@BASEBOARD_FAB2_LIB.BASEBOARD_FAB2(SCH_1):VCC_A_1V1':
 C_SIGNAL='@baseboard_fab2_lib.baseboard_fab2(sch_1):vcc_a_1v1';
NODE_NAME     U25W4 L5
 '@BASEBOARD_FAB2_LIB.BASEBOARD_FAB2(SCH_1):PAGE148_I28@W_HDL.AST2520A1-GP-GP(CHIPS)':
 'VPLLAV110': CDS_PINID='VPLLAV110';
NODE_NAME     U25W4 L6
 '@BASEBOARD_FAB2_LIB.BASEBOARD_FAB2(SCH_1):PAGE148_I28@W_HDL.AST2520A1-GP-GP(CHIPS)':
 'VPLLAV111': CDS_PINID='VPLLAV111';
NODE_NAME     C25W39 1
 '@BASEBOARD_FAB2_LIB.BASEBOARD_FAB2(SCH_1):PAGE149_I25@MSTR_DISCRETE.CAP(CHIPS)':
 'A': CDS_PINID='A';
NODE_NAME     FB2T7 2
 '@BASEBOARD_FAB2_LIB.BASEBOARD_FAB2(SCH_1):PAGE149_I42@W_HDL.HCB1608KF-800T30-GP(CHIPS)':
 '2': CDS_PINID='\2\';
NODE_NAME     C25W37 1
 '@BASEBOARD_FAB2_LIB.BASEBOARD_FAB2(SCH_1):PAGE149_I113@MSTR_DISCRETE.CAP(CHIPS)':
 'A': CDS_PINID='A';
NODE_NAME     C25W38 1
 '@BASEBOARD_FAB2_LIB.BASEBOARD_FAB2(SCH_1):PAGE149_I121@DEV_DISCRETE.CAP_A(CHIPS)':
 'A': CDS_PINID='A';
NET_NAME
'VCC_DACAV3V3'
 '@BASEBOARD_FAB2_LIB.BASEBOARD_FAB2(SCH_1):VCC_DACAV3V3':
 C_SIGNAL='@baseboard_fab2_lib.baseboard_fab2(sch_1):vcc_dacav3v3';
NODE_NAME     U25W4 K6
 '@BASEBOARD_FAB2_LIB.BASEBOARD_FAB2(SCH_1):PAGE148_I28@W_HDL.AST2520A1-GP-GP(CHIPS)':
 'DACAV33': CDS_PINID='DACAV33';
NODE_NAME     U25W4 K5
 '@BASEBOARD_FAB2_LIB.BASEBOARD_FAB2(SCH_1):PAGE148_I28@W_HDL.AST2520A1-GP-GP(CHIPS)':
 'DACDV33': CDS_PINID='DACDV33';
NODE_NAME     C25W36 1
 '@BASEBOARD_FAB2_LIB.BASEBOARD_FAB2(SCH_1):PAGE149_I46@MSTR_DISCRETE.CAP(CHIPS)':
 'A': CDS_PINID='A';
NODE_NAME     R25W93 2
 '@BASEBOARD_FAB2_LIB.BASEBOARD_FAB2(SCH_1):PAGE149_I90@MSTR_DISCRETE.RES(CHIPS)':
 'B': CDS_PINID='B';
NODE_NAME     C25W35 1
 '@BASEBOARD_FAB2_LIB.BASEBOARD_FAB2(SCH_1):PAGE149_I110@MSTR_DISCRETE.CAP(CHIPS)':
 'A': CDS_PINID='A';
NODE_NAME     C25W34 1
 '@BASEBOARD_FAB2_LIB.BASEBOARD_FAB2(SCH_1):PAGE149_I120@DEV_DISCRETE.CAP_A(CHIPS)':
 'A': CDS_PINID='A';
NET_NAME
'VCC_D_3V3'
 '@BASEBOARD_FAB2_LIB.BASEBOARD_FAB2(SCH_1):VCC_D_3V3':
 C_SIGNAL='@baseboard_fab2_lib.baseboard_fab2(sch_1):vcc_d_3v3';
NODE_NAME     U25W4 L16
 '@BASEBOARD_FAB2_LIB.BASEBOARD_FAB2(SCH_1):PAGE148_I28@W_HDL.AST2520A1-GP-GP(CHIPS)':
 'PEAV33': CDS_PINID='PEAV33';
NODE_NAME     U25W4 F12
 '@BASEBOARD_FAB2_LIB.BASEBOARD_FAB2(SCH_1):PAGE148_I28@W_HDL.AST2520A1-GP-GP(CHIPS)':
 'PV33D0': CDS_PINID='PV33D0';
NODE_NAME     U25W4 F13
 '@BASEBOARD_FAB2_LIB.BASEBOARD_FAB2(SCH_1):PAGE148_I28@W_HDL.AST2520A1-GP-GP(CHIPS)':
 'PV33D1': CDS_PINID='PV33D1';
NODE_NAME     U25W4 F14
 '@BASEBOARD_FAB2_LIB.BASEBOARD_FAB2(SCH_1):PAGE148_I28@W_HDL.AST2520A1-GP-GP(CHIPS)':
 'PV33D2': CDS_PINID='PV33D2';
NODE_NAME     U25W4 F15
 '@BASEBOARD_FAB2_LIB.BASEBOARD_FAB2(SCH_1):PAGE148_I28@W_HDL.AST2520A1-GP-GP(CHIPS)':
 'PV33D3': CDS_PINID='PV33D3';
NODE_NAME     U25W4 G16
 '@BASEBOARD_FAB2_LIB.BASEBOARD_FAB2(SCH_1):PAGE148_I28@W_HDL.AST2520A1-GP-GP(CHIPS)':
 'PV33D4': CDS_PINID='PV33D4';
NODE_NAME     U25W4 H17
 '@BASEBOARD_FAB2_LIB.BASEBOARD_FAB2(SCH_1):PAGE148_I28@W_HDL.AST2520A1-GP-GP(CHIPS)':
 'PV33D5': CDS_PINID='PV33D5';
NODE_NAME     U25W4 K7
 '@BASEBOARD_FAB2_LIB.BASEBOARD_FAB2(SCH_1):PAGE148_I28@W_HDL.AST2520A1-GP-GP(CHIPS)':
 'PV33D6': CDS_PINID='PV33D6';
NODE_NAME     U25W4 N17
 '@BASEBOARD_FAB2_LIB.BASEBOARD_FAB2(SCH_1):PAGE148_I28@W_HDL.AST2520A1-GP-GP(CHIPS)':
 'PV33D7': CDS_PINID='PV33D7';
NODE_NAME     U25W4 N6
 '@BASEBOARD_FAB2_LIB.BASEBOARD_FAB2(SCH_1):PAGE148_I28@W_HDL.AST2520A1-GP-GP(CHIPS)':
 'PV33D8': CDS_PINID='PV33D8';
NODE_NAME     U25W4 P17
 '@BASEBOARD_FAB2_LIB.BASEBOARD_FAB2(SCH_1):PAGE148_I28@W_HDL.AST2520A1-GP-GP(CHIPS)':
 'PV33D9': CDS_PINID='PV33D9';
NODE_NAME     U25W4 P6
 '@BASEBOARD_FAB2_LIB.BASEBOARD_FAB2(SCH_1):PAGE148_I28@W_HDL.AST2520A1-GP-GP(CHIPS)':
 'PV33D10': CDS_PINID='PV33D10';
NODE_NAME     U25W4 R17
 '@BASEBOARD_FAB2_LIB.BASEBOARD_FAB2(SCH_1):PAGE148_I28@W_HDL.AST2520A1-GP-GP(CHIPS)':
 'PV33D11': CDS_PINID='PV33D11';
NODE_NAME     U25W4 R6
 '@BASEBOARD_FAB2_LIB.BASEBOARD_FAB2(SCH_1):PAGE148_I28@W_HDL.AST2520A1-GP-GP(CHIPS)':
 'PV33D12': CDS_PINID='PV33D12';
NODE_NAME     U25W4 T15
 '@BASEBOARD_FAB2_LIB.BASEBOARD_FAB2(SCH_1):PAGE148_I28@W_HDL.AST2520A1-GP-GP(CHIPS)':
 'PV33D14': CDS_PINID='PV33D14';
NODE_NAME     C25W47 1
 '@BASEBOARD_FAB2_LIB.BASEBOARD_FAB2(SCH_1):PAGE149_I50@MSTR_DISCRETE.CAP(CHIPS)':
 'A': CDS_PINID='A';
NODE_NAME     C25W46 1
 '@BASEBOARD_FAB2_LIB.BASEBOARD_FAB2(SCH_1):PAGE149_I51@MSTR_DISCRETE.CAP(CHIPS)':
 'A': CDS_PINID='A';
NODE_NAME     FB2T4 2
 '@BASEBOARD_FAB2_LIB.BASEBOARD_FAB2(SCH_1):PAGE149_I86@W_HDL.HCB1608KF-800T30-GP(CHIPS)':
 '2': CDS_PINID='\2\';
NODE_NAME     C25W40 1
 '@BASEBOARD_FAB2_LIB.BASEBOARD_FAB2(SCH_1):PAGE149_I96@MSTR_DISCRETE.CAP(CHIPS)':
 'A': CDS_PINID='A';
NODE_NAME     C25W41 1
 '@BASEBOARD_FAB2_LIB.BASEBOARD_FAB2(SCH_1):PAGE149_I97@MSTR_DISCRETE.CAP(CHIPS)':
 'A': CDS_PINID='A';
NODE_NAME     C25W42 1
 '@BASEBOARD_FAB2_LIB.BASEBOARD_FAB2(SCH_1):PAGE149_I98@MSTR_DISCRETE.CAP(CHIPS)':
 'A': CDS_PINID='A';
NODE_NAME     C25W43 1
 '@BASEBOARD_FAB2_LIB.BASEBOARD_FAB2(SCH_1):PAGE149_I100@MSTR_DISCRETE.CAP(CHIPS)':
 'A': CDS_PINID='A';
NODE_NAME     C25W44 1
 '@BASEBOARD_FAB2_LIB.BASEBOARD_FAB2(SCH_1):PAGE149_I101@MSTR_DISCRETE.CAP(CHIPS)':
 'A': CDS_PINID='A';
NODE_NAME     C25W45 1
 '@BASEBOARD_FAB2_LIB.BASEBOARD_FAB2(SCH_1):PAGE149_I122@DEV_DISCRETE.CAP_A(CHIPS)':
 'A': CDS_PINID='A';
NET_NAME
'VCC_PA_3V3'
 '@BASEBOARD_FAB2_LIB.BASEBOARD_FAB2(SCH_1):VCC_PA_3V3':
 C_SIGNAL='@baseboard_fab2_lib.baseboard_fab2(sch_1):vcc_pa_3v3';
NODE_NAME     U25W4 Y17
 '@BASEBOARD_FAB2_LIB.BASEBOARD_FAB2(SCH_1):PAGE148_I28@W_HDL.AST2520A1-GP-GP(CHIPS)':
 'PLLAV330': CDS_PINID='PLLAV330';
NODE_NAME     U25W4 W17
 '@BASEBOARD_FAB2_LIB.BASEBOARD_FAB2(SCH_1):PAGE148_I28@W_HDL.AST2520A1-GP-GP(CHIPS)':
 'PLLAV331': CDS_PINID='PLLAV331';
NODE_NAME     U25W4 T11
 '@BASEBOARD_FAB2_LIB.BASEBOARD_FAB2(SCH_1):PAGE148_I28@W_HDL.AST2520A1-GP-GP(CHIPS)':
 'PV33D13': CDS_PINID='PV33D13';
NODE_NAME     C25W59 1
 '@BASEBOARD_FAB2_LIB.BASEBOARD_FAB2(SCH_1):PAGE149_I79@MSTR_DISCRETE.CAP(CHIPS)':
 'A': CDS_PINID='A';
NODE_NAME     FB2T5 2
 '@BASEBOARD_FAB2_LIB.BASEBOARD_FAB2(SCH_1):PAGE149_I88@W_HDL.HCB1608KF-800T30-GP(CHIPS)':
 '2': CDS_PINID='\2\';
NODE_NAME     C25W56 1
 '@BASEBOARD_FAB2_LIB.BASEBOARD_FAB2(SCH_1):PAGE149_I93@MSTR_DISCRETE.CAP(CHIPS)':
 'A': CDS_PINID='A';
NODE_NAME     C25W58 1
 '@BASEBOARD_FAB2_LIB.BASEBOARD_FAB2(SCH_1):PAGE149_I125@DEV_DISCRETE.CAP_A(CHIPS)':
 'A': CDS_PINID='A';
NODE_NAME     C25W57 1
 '@BASEBOARD_FAB2_LIB.BASEBOARD_FAB2(SCH_1):PAGE149_I130@MSTR_DISCRETE.CAP(CHIPS)':
 'A': CDS_PINID='A';
NET_NAME
'VCC_VA_3V3'
 '@BASEBOARD_FAB2_LIB.BASEBOARD_FAB2(SCH_1):VCC_VA_3V3':
 C_SIGNAL='@baseboard_fab2_lib.baseboard_fab2(sch_1):vcc_va_3v3';
NODE_NAME     U25W4 J7
 '@BASEBOARD_FAB2_LIB.BASEBOARD_FAB2(SCH_1):PAGE148_I28@W_HDL.AST2520A1-GP-GP(CHIPS)':
 'VPLLAV330': CDS_PINID='VPLLAV330';
NODE_NAME     U25W4 H7
 '@BASEBOARD_FAB2_LIB.BASEBOARD_FAB2(SCH_1):PAGE148_I28@W_HDL.AST2520A1-GP-GP(CHIPS)':
 'VPLLAV331': CDS_PINID='VPLLAV331';
NODE_NAME     C25W69 1
 '@BASEBOARD_FAB2_LIB.BASEBOARD_FAB2(SCH_1):PAGE149_I17@MSTR_DISCRETE.CAP(CHIPS)':
 'A': CDS_PINID='A';
NODE_NAME     FB2T1 2
 '@BASEBOARD_FAB2_LIB.BASEBOARD_FAB2(SCH_1):PAGE149_I22@W_HDL.HCB1608KF-800T30-GP(CHIPS)':
 '2': CDS_PINID='\2\';
NODE_NAME     C25W66 1
 '@BASEBOARD_FAB2_LIB.BASEBOARD_FAB2(SCH_1):PAGE149_I116@MSTR_DISCRETE.CAP(CHIPS)':
 'A': CDS_PINID='A';
NODE_NAME     C25W67 1
 '@BASEBOARD_FAB2_LIB.BASEBOARD_FAB2(SCH_1):PAGE149_I117@MSTR_DISCRETE.CAP(CHIPS)':
 'A': CDS_PINID='A';
NODE_NAME     C25W68 1
 '@BASEBOARD_FAB2_LIB.BASEBOARD_FAB2(SCH_1):PAGE149_I128@DEV_DISCRETE.CAP_A(CHIPS)':
 'A': CDS_PINID='A';
NET_NAME
'VGA_REAR_HSYNC_S'
 '@BASEBOARD_FAB2_LIB.BASEBOARD_FAB2(SCH_1):VGA_REAR_HSYNC_S':
 C_SIGNAL='@baseboard_fab2_lib.baseboard_fab2(sch_1):vga_rear_hsync_s';
NODE_NAME     R25W138 1
 '@BASEBOARD_FAB2_LIB.BASEBOARD_FAB2(SCH_1):PAGE255_I49@MSTR_DISCRETE.RES(CHIPS)':
 'A': CDS_PINID='A';
NODE_NAME     U25W7 4
 '@BASEBOARD_FAB2_LIB.BASEBOARD_FAB2(SCH_1):PAGE255_I111@W_HDL.U74AHCT1G125G-AL5-R-GP-U(CHIPS)':
 'Y': CDS_PINID='Y';
NET_NAME
'VGA_REAR_VSYNC_S'
 '@BASEBOARD_FAB2_LIB.BASEBOARD_FAB2(SCH_1):VGA_REAR_VSYNC_S':
 C_SIGNAL='@baseboard_fab2_lib.baseboard_fab2(sch_1):vga_rear_vsync_s';
NODE_NAME     R25W139 1
 '@BASEBOARD_FAB2_LIB.BASEBOARD_FAB2(SCH_1):PAGE255_I59@MSTR_DISCRETE.RES(CHIPS)':
 'A': CDS_PINID='A';
NODE_NAME     U25W8 4
 '@BASEBOARD_FAB2_LIB.BASEBOARD_FAB2(SCH_1):PAGE255_I112@W_HDL.U74AHCT1G125G-AL5-R-GP-U(CHIPS)':
 'Y': CDS_PINID='Y';
NET_NAME
'VID_PCH_CORE_PVNN_AUX_VID_0'
 '@BASEBOARD_FAB2_LIB.BASEBOARD_FAB2(SCH_1):VID_PCH_CORE_PVNN_AUX_VID_0':
 C_SIGNAL='@baseboard_fab2_lib.baseboard_fab2(sch_1):vid_pch_core_pvnn_aux_vid_0~
';
NODE_NAME     U7C1 BL7
 '@BASEBOARD_FAB2_LIB.BASEBOARD_FAB2(SCH_1):PAGE119_I115@MSTR_U_PROC.LBG_CORE_QAT_EXT_D(CHIPS)':
 'GPP_B0_CORE_VID0': CDS_PINID='GPP_B0_CORE_VID0';
NODE_NAME     EU8A1 13
 '@BASEBOARD_FAB2_LIB.BASEBOARD_FAB2(SCH_1):PAGE235_I229@MSTR_CONTROLLER.PXE1110B(CHIPS)':
 'MP0': CDS_PINID='MP0';
NODE_NAME     R2L26 2
 '@BASEBOARD_FAB2_LIB.BASEBOARD_FAB2(SCH_1):PAGE235_I253@MSTR_DISCRETE.RES(CHIPS)':
 'B': CDS_PINID='B';
NET_NAME
'VID_PCH_CORE_PVNN_AUX_VID_1'
 '@BASEBOARD_FAB2_LIB.BASEBOARD_FAB2(SCH_1):VID_PCH_CORE_PVNN_AUX_VID_1':
 C_SIGNAL='@baseboard_fab2_lib.baseboard_fab2(sch_1):vid_pch_core_pvnn_aux_vid_1~
';
NODE_NAME     U7C1 BH9
 '@BASEBOARD_FAB2_LIB.BASEBOARD_FAB2(SCH_1):PAGE119_I115@MSTR_U_PROC.LBG_CORE_QAT_EXT_D(CHIPS)':
 'GPP_B1_CORE_VID1': CDS_PINID='GPP_B1_CORE_VID1';
NODE_NAME     EU8A1 14
 '@BASEBOARD_FAB2_LIB.BASEBOARD_FAB2(SCH_1):PAGE235_I229@MSTR_CONTROLLER.PXE1110B(CHIPS)':
 'MP1': CDS_PINID='MP1';
NODE_NAME     R2L25 2
 '@BASEBOARD_FAB2_LIB.BASEBOARD_FAB2(SCH_1):PAGE235_I252@MSTR_DISCRETE.RES(CHIPS)':
 'B': CDS_PINID='B';
NET_NAME
'VREF_2V2'
 '@BASEBOARD_FAB2_LIB.BASEBOARD_FAB2(SCH_1):VREF_2V2':
 C_SIGNAL='@baseboard_fab2_lib.baseboard_fab2(sch_1):vref_2v2';
NODE_NAME     R3W9 1
 '@BASEBOARD_FAB2_LIB.BASEBOARD_FAB2(SCH_1):PAGE249_I7@MSTR_DISCRETE.RES(CHIPS)':
 'A': CDS_PINID='A';
NODE_NAME     R3W7 2
 '@BASEBOARD_FAB2_LIB.BASEBOARD_FAB2(SCH_1):PAGE249_I8@MSTR_DISCRETE.RES(CHIPS)':
 'B': CDS_PINID='B';
NODE_NAME     Q9W4 3
 '@BASEBOARD_FAB2_LIB.BASEBOARD_FAB2(SCH_1):PAGE249_I15@W_HDL.LMV331IDCKRG4-GP(CHIPS)':
 '-IN': CDS_PINID='\-in\';
NET_NAME
'VREF_LMV431_1V42'
 '@BASEBOARD_FAB2_LIB.BASEBOARD_FAB2(SCH_1):VREF_LMV431_1V42':
 C_SIGNAL='@baseboard_fab2_lib.baseboard_fab2(sch_1):vref_lmv431_1v42';
NODE_NAME     R32W3 1
 '@BASEBOARD_FAB2_LIB.BASEBOARD_FAB2(SCH_1):PAGE185_I206@MSTR_DISCRETE.RES(CHIPS)':
 'A': CDS_PINID='A';
NODE_NAME     R32W2 2
 '@BASEBOARD_FAB2_LIB.BASEBOARD_FAB2(SCH_1):PAGE185_I207@MSTR_DISCRETE.RES(CHIPS)':
 'B': CDS_PINID='B';
NODE_NAME     VR32W1 1
 '@BASEBOARD_FAB2_LIB.BASEBOARD_FAB2(SCH_1):PAGE185_I213@W_HDL.LMV431AIMFX-GP(CHIPS)':
 'REF': CDS_PINID='REF';
NET_NAME
'VR_COMP_PVPP_ABC'
 '@BASEBOARD_FAB2_LIB.BASEBOARD_FAB2(SCH_1):VR_COMP_PVPP_ABC':
 C_SIGNAL='@baseboard_fab2_lib.baseboard_fab2(sch_1):vr_comp_pvpp_abc';
NODE_NAME     R7F17 2
 '@BASEBOARD_FAB2_LIB.BASEBOARD_FAB2(SCH_1):PAGE231_I218@MSTR_DISCRETE.RES(CHIPS)':
 'B': CDS_PINID='B';
NODE_NAME     C7F13 1
 '@BASEBOARD_FAB2_LIB.BASEBOARD_FAB2(SCH_1):PAGE231_I219@MSTR_DISCRETE.CAP(CHIPS)':
 'A': CDS_PINID='A';
NET_NAME
'VR_COMP_PVPP_ABC_3'
 '@BASEBOARD_FAB2_LIB.BASEBOARD_FAB2(SCH_1):VR_COMP_PVPP_ABC_3':
 C_SIGNAL='@baseboard_fab2_lib.baseboard_fab2(sch_1):vr_comp_pvpp_abc_3';
NODE_NAME     EU7F1 3
 '@BASEBOARD_FAB2_LIB.BASEBOARD_FAB2(SCH_1):PAGE231_I193@MSTR_VREG.NCP3232L(CHIPS)':
 'COMP': CDS_PINID='COMP';
NODE_NAME     C7F9 2
 '@BASEBOARD_FAB2_LIB.BASEBOARD_FAB2(SCH_1):PAGE231_I199@MSTR_DISCRETE.CAP(CHIPS)':
 'B': CDS_PINID='B';
NODE_NAME     C7F12 2
 '@BASEBOARD_FAB2_LIB.BASEBOARD_FAB2(SCH_1):PAGE231_I200@MSTR_DISCRETE.CAP(CHIPS)':
 'B': CDS_PINID='B';
NET_NAME
'VR_COMP_PVPP_DEF'
 '@BASEBOARD_FAB2_LIB.BASEBOARD_FAB2(SCH_1):VR_COMP_PVPP_DEF':
 C_SIGNAL='@baseboard_fab2_lib.baseboard_fab2(sch_1):vr_comp_pvpp_def';
NODE_NAME     R7B18 2
 '@BASEBOARD_FAB2_LIB.BASEBOARD_FAB2(SCH_1):PAGE232_I298@MSTR_DISCRETE.RES(CHIPS)':
 'B': CDS_PINID='B';
NODE_NAME     C7B13 1
 '@BASEBOARD_FAB2_LIB.BASEBOARD_FAB2(SCH_1):PAGE232_I302@MSTR_DISCRETE.CAP(CHIPS)':
 'A': CDS_PINID='A';
NET_NAME
'VR_COMP_PVPP_DEF_3'
 '@BASEBOARD_FAB2_LIB.BASEBOARD_FAB2(SCH_1):VR_COMP_PVPP_DEF_3':
 C_SIGNAL='@baseboard_fab2_lib.baseboard_fab2(sch_1):vr_comp_pvpp_def_3';
NODE_NAME     EU7B1 3
 '@BASEBOARD_FAB2_LIB.BASEBOARD_FAB2(SCH_1):PAGE232_I214@MSTR_VREG.NCP3232L(CHIPS)':
 'COMP': CDS_PINID='COMP';
NODE_NAME     C7B10 2
 '@BASEBOARD_FAB2_LIB.BASEBOARD_FAB2(SCH_1):PAGE232_I301@MSTR_DISCRETE.CAP(CHIPS)':
 'B': CDS_PINID='B';
NODE_NAME     C7B14 2
 '@BASEBOARD_FAB2_LIB.BASEBOARD_FAB2(SCH_1):PAGE232_I306@MSTR_DISCRETE.CAP(CHIPS)':
 'B': CDS_PINID='B';
NET_NAME
'VR_COMP_PVPP_GHJ'
 '@BASEBOARD_FAB2_LIB.BASEBOARD_FAB2(SCH_1):VR_COMP_PVPP_GHJ':
 C_SIGNAL='@baseboard_fab2_lib.baseboard_fab2(sch_1):vr_comp_pvpp_ghj';
NODE_NAME     R4G10 2
 '@BASEBOARD_FAB2_LIB.BASEBOARD_FAB2(SCH_1):PAGE233_I266@MSTR_DISCRETE.RES(CHIPS)':
 'B': CDS_PINID='B';
NODE_NAME     C4G11 1
 '@BASEBOARD_FAB2_LIB.BASEBOARD_FAB2(SCH_1):PAGE233_I267@MSTR_DISCRETE.CAP(CHIPS)':
 'A': CDS_PINID='A';
NET_NAME
'VR_COMP_PVPP_GHJ_3'
 '@BASEBOARD_FAB2_LIB.BASEBOARD_FAB2(SCH_1):VR_COMP_PVPP_GHJ_3':
 C_SIGNAL='@baseboard_fab2_lib.baseboard_fab2(sch_1):vr_comp_pvpp_ghj_3';
NODE_NAME     EU4G1 3
 '@BASEBOARD_FAB2_LIB.BASEBOARD_FAB2(SCH_1):PAGE233_I225@MSTR_VREG.NCP3232L(CHIPS)':
 'COMP': CDS_PINID='COMP';
NODE_NAME     C4G6 2
 '@BASEBOARD_FAB2_LIB.BASEBOARD_FAB2(SCH_1):PAGE233_I273@MSTR_DISCRETE.CAP(CHIPS)':
 'B': CDS_PINID='B';
NODE_NAME     C4G10 2
 '@BASEBOARD_FAB2_LIB.BASEBOARD_FAB2(SCH_1):PAGE233_I274@MSTR_DISCRETE.CAP(CHIPS)':
 'B': CDS_PINID='B';
NET_NAME
'VR_COMP_PVPP_KLM'
 '@BASEBOARD_FAB2_LIB.BASEBOARD_FAB2(SCH_1):VR_COMP_PVPP_KLM':
 C_SIGNAL='@baseboard_fab2_lib.baseboard_fab2(sch_1):vr_comp_pvpp_klm';
NODE_NAME     C4B7 1
 '@BASEBOARD_FAB2_LIB.BASEBOARD_FAB2(SCH_1):PAGE234_I218@MSTR_DISCRETE.CAP(CHIPS)':
 'A': CDS_PINID='A';
NODE_NAME     R4B9 2
 '@BASEBOARD_FAB2_LIB.BASEBOARD_FAB2(SCH_1):PAGE234_I219@MSTR_DISCRETE.RES(CHIPS)':
 'B': CDS_PINID='B';
NET_NAME
'VR_COMP_PVPP_KLM_3'
 '@BASEBOARD_FAB2_LIB.BASEBOARD_FAB2(SCH_1):VR_COMP_PVPP_KLM_3':
 C_SIGNAL='@baseboard_fab2_lib.baseboard_fab2(sch_1):vr_comp_pvpp_klm_3';
NODE_NAME     EU4A3 3
 '@BASEBOARD_FAB2_LIB.BASEBOARD_FAB2(SCH_1):PAGE234_I184@MSTR_VREG.NCP3232L(CHIPS)':
 'COMP': CDS_PINID='COMP';
NODE_NAME     C4B9 2
 '@BASEBOARD_FAB2_LIB.BASEBOARD_FAB2(SCH_1):PAGE234_I211@MSTR_DISCRETE.CAP(CHIPS)':
 'B': CDS_PINID='B';
NODE_NAME     C4B4 2
 '@BASEBOARD_FAB2_LIB.BASEBOARD_FAB2(SCH_1):PAGE234_I212@MSTR_DISCRETE.CAP(CHIPS)':
 'B': CDS_PINID='B';
NET_NAME
'VR_COMP_RC_PVPP_ABC'
 '@BASEBOARD_FAB2_LIB.BASEBOARD_FAB2(SCH_1):VR_COMP_RC_PVPP_ABC':
 C_SIGNAL='@baseboard_fab2_lib.baseboard_fab2(sch_1):vr_comp_rc_pvpp_abc';
NODE_NAME     C7F12 1
 '@BASEBOARD_FAB2_LIB.BASEBOARD_FAB2(SCH_1):PAGE231_I200@MSTR_DISCRETE.CAP(CHIPS)':
 'A': CDS_PINID='A';
NODE_NAME     R7F18 1
 '@BASEBOARD_FAB2_LIB.BASEBOARD_FAB2(SCH_1):PAGE231_I201@MSTR_DISCRETE.RES(CHIPS)':
 'A': CDS_PINID='A';
NET_NAME
'VR_COMP_RC_PVPP_DEF'
 '@BASEBOARD_FAB2_LIB.BASEBOARD_FAB2(SCH_1):VR_COMP_RC_PVPP_DEF':
 C_SIGNAL='@baseboard_fab2_lib.baseboard_fab2(sch_1):vr_comp_rc_pvpp_def';
NODE_NAME     R7B16 1
 '@BASEBOARD_FAB2_LIB.BASEBOARD_FAB2(SCH_1):PAGE232_I300@MSTR_DISCRETE.RES(CHIPS)':
 'A': CDS_PINID='A';
NODE_NAME     C7B14 1
 '@BASEBOARD_FAB2_LIB.BASEBOARD_FAB2(SCH_1):PAGE232_I306@MSTR_DISCRETE.CAP(CHIPS)':
 'A': CDS_PINID='A';
NET_NAME
'VR_COMP_RC_PVPP_GHJ'
 '@BASEBOARD_FAB2_LIB.BASEBOARD_FAB2(SCH_1):VR_COMP_RC_PVPP_GHJ':
 C_SIGNAL='@baseboard_fab2_lib.baseboard_fab2(sch_1):vr_comp_rc_pvpp_ghj';
NODE_NAME     R4G13 1
 '@BASEBOARD_FAB2_LIB.BASEBOARD_FAB2(SCH_1):PAGE233_I272@MSTR_DISCRETE.RES(CHIPS)':
 'A': CDS_PINID='A';
NODE_NAME     C4G10 1
 '@BASEBOARD_FAB2_LIB.BASEBOARD_FAB2(SCH_1):PAGE233_I274@MSTR_DISCRETE.CAP(CHIPS)':
 'A': CDS_PINID='A';
NET_NAME
'VR_COMP_RC_PVPP_KLM'
 '@BASEBOARD_FAB2_LIB.BASEBOARD_FAB2(SCH_1):VR_COMP_RC_PVPP_KLM':
 C_SIGNAL='@baseboard_fab2_lib.baseboard_fab2(sch_1):vr_comp_rc_pvpp_klm';
NODE_NAME     C4B9 1
 '@BASEBOARD_FAB2_LIB.BASEBOARD_FAB2(SCH_1):PAGE234_I211@MSTR_DISCRETE.CAP(CHIPS)':
 'A': CDS_PINID='A';
NODE_NAME     R4B8 1
 '@BASEBOARD_FAB2_LIB.BASEBOARD_FAB2(SCH_1):PAGE234_I213@MSTR_DISCRETE.RES(CHIPS)':
 'A': CDS_PINID='A';
NET_NAME
'VR_FB_PVPP_ABC'
 '@BASEBOARD_FAB2_LIB.BASEBOARD_FAB2(SCH_1):VR_FB_PVPP_ABC':
 C_SIGNAL='@baseboard_fab2_lib.baseboard_fab2(sch_1):vr_fb_pvpp_abc';
NODE_NAME     R7F13 2
 '@BASEBOARD_FAB2_LIB.BASEBOARD_FAB2(SCH_1):PAGE231_I167@MSTR_DISCRETE.RES(CHIPS)':
 'B': CDS_PINID='B';
NODE_NAME     EU7F1 2
 '@BASEBOARD_FAB2_LIB.BASEBOARD_FAB2(SCH_1):PAGE231_I193@MSTR_VREG.NCP3232L(CHIPS)':
 'FB': CDS_PINID='FB';
NODE_NAME     C7F9 1
 '@BASEBOARD_FAB2_LIB.BASEBOARD_FAB2(SCH_1):PAGE231_I199@MSTR_DISCRETE.CAP(CHIPS)':
 'A': CDS_PINID='A';
NODE_NAME     R7F18 2
 '@BASEBOARD_FAB2_LIB.BASEBOARD_FAB2(SCH_1):PAGE231_I201@MSTR_DISCRETE.RES(CHIPS)':
 'B': CDS_PINID='B';
NODE_NAME     C7F13 2
 '@BASEBOARD_FAB2_LIB.BASEBOARD_FAB2(SCH_1):PAGE231_I219@MSTR_DISCRETE.CAP(CHIPS)':
 'B': CDS_PINID='B';
NODE_NAME     R7F11 1
 '@BASEBOARD_FAB2_LIB.BASEBOARD_FAB2(SCH_1):PAGE231_I230@MSTR_DISCRETE.RES(CHIPS)':
 'A': CDS_PINID='A';
NET_NAME
'VR_FB_PVPP_DEF'
 '@BASEBOARD_FAB2_LIB.BASEBOARD_FAB2(SCH_1):VR_FB_PVPP_DEF':
 C_SIGNAL='@baseboard_fab2_lib.baseboard_fab2(sch_1):vr_fb_pvpp_def';
NODE_NAME     EU7B1 2
 '@BASEBOARD_FAB2_LIB.BASEBOARD_FAB2(SCH_1):PAGE232_I214@MSTR_VREG.NCP3232L(CHIPS)':
 'FB': CDS_PINID='FB';
NODE_NAME     R7B16 2
 '@BASEBOARD_FAB2_LIB.BASEBOARD_FAB2(SCH_1):PAGE232_I300@MSTR_DISCRETE.RES(CHIPS)':
 'B': CDS_PINID='B';
NODE_NAME     C7B10 1
 '@BASEBOARD_FAB2_LIB.BASEBOARD_FAB2(SCH_1):PAGE232_I301@MSTR_DISCRETE.CAP(CHIPS)':
 'A': CDS_PINID='A';
NODE_NAME     C7B13 2
 '@BASEBOARD_FAB2_LIB.BASEBOARD_FAB2(SCH_1):PAGE232_I302@MSTR_DISCRETE.CAP(CHIPS)':
 'B': CDS_PINID='B';
NODE_NAME     R7B15 2
 '@BASEBOARD_FAB2_LIB.BASEBOARD_FAB2(SCH_1):PAGE232_I303@MSTR_DISCRETE.RES(CHIPS)':
 'B': CDS_PINID='B';
NODE_NAME     R7B13 1
 '@BASEBOARD_FAB2_LIB.BASEBOARD_FAB2(SCH_1):PAGE232_I314@MSTR_DISCRETE.RES(CHIPS)':
 'A': CDS_PINID='A';
NET_NAME
'VR_FB_PVPP_GHJ'
 '@BASEBOARD_FAB2_LIB.BASEBOARD_FAB2(SCH_1):VR_FB_PVPP_GHJ':
 C_SIGNAL='@baseboard_fab2_lib.baseboard_fab2(sch_1):vr_fb_pvpp_ghj';
NODE_NAME     EU4G1 2
 '@BASEBOARD_FAB2_LIB.BASEBOARD_FAB2(SCH_1):PAGE233_I225@MSTR_VREG.NCP3232L(CHIPS)':
 'FB': CDS_PINID='FB';
NODE_NAME     C4G11 2
 '@BASEBOARD_FAB2_LIB.BASEBOARD_FAB2(SCH_1):PAGE233_I267@MSTR_DISCRETE.CAP(CHIPS)':
 'B': CDS_PINID='B';
NODE_NAME     R4G7 2
 '@BASEBOARD_FAB2_LIB.BASEBOARD_FAB2(SCH_1):PAGE233_I270@MSTR_DISCRETE.RES(CHIPS)':
 'B': CDS_PINID='B';
NODE_NAME     R4G13 2
 '@BASEBOARD_FAB2_LIB.BASEBOARD_FAB2(SCH_1):PAGE233_I272@MSTR_DISCRETE.RES(CHIPS)':
 'B': CDS_PINID='B';
NODE_NAME     C4G6 1
 '@BASEBOARD_FAB2_LIB.BASEBOARD_FAB2(SCH_1):PAGE233_I273@MSTR_DISCRETE.CAP(CHIPS)':
 'A': CDS_PINID='A';
NODE_NAME     R4G9 1
 '@BASEBOARD_FAB2_LIB.BASEBOARD_FAB2(SCH_1):PAGE233_I283@MSTR_DISCRETE.RES(CHIPS)':
 'A': CDS_PINID='A';
NET_NAME
'VR_FB_PVPP_KLM'
 '@BASEBOARD_FAB2_LIB.BASEBOARD_FAB2(SCH_1):VR_FB_PVPP_KLM':
 C_SIGNAL='@baseboard_fab2_lib.baseboard_fab2(sch_1):vr_fb_pvpp_klm';
NODE_NAME     EU4A3 2
 '@BASEBOARD_FAB2_LIB.BASEBOARD_FAB2(SCH_1):PAGE234_I184@MSTR_VREG.NCP3232L(CHIPS)':
 'FB': CDS_PINID='FB';
NODE_NAME     C4B4 1
 '@BASEBOARD_FAB2_LIB.BASEBOARD_FAB2(SCH_1):PAGE234_I212@MSTR_DISCRETE.CAP(CHIPS)':
 'A': CDS_PINID='A';
NODE_NAME     R4B8 2
 '@BASEBOARD_FAB2_LIB.BASEBOARD_FAB2(SCH_1):PAGE234_I213@MSTR_DISCRETE.RES(CHIPS)':
 'B': CDS_PINID='B';
NODE_NAME     R4B5 2
 '@BASEBOARD_FAB2_LIB.BASEBOARD_FAB2(SCH_1):PAGE234_I215@MSTR_DISCRETE.RES(CHIPS)':
 'B': CDS_PINID='B';
NODE_NAME     C4B7 2
 '@BASEBOARD_FAB2_LIB.BASEBOARD_FAB2(SCH_1):PAGE234_I218@MSTR_DISCRETE.CAP(CHIPS)':
 'B': CDS_PINID='B';
NODE_NAME     R4B4 1
 '@BASEBOARD_FAB2_LIB.BASEBOARD_FAB2(SCH_1):PAGE234_I227@MSTR_DISCRETE.RES(CHIPS)':
 'A': CDS_PINID='A';
NET_NAME
'VR_FET_SW_P12V_STBY_P3V3_STBY'
 '@BASEBOARD_FAB2_LIB.BASEBOARD_FAB2(SCH_1):VR_FET_SW_P12V_STBY_P3V3_STBY':
 C_SIGNAL='@baseboard_fab2_lib.baseboard_fab2(sch_1):vr_fet_sw_p12v_stby_p3v3_st~
by';
NODE_NAME     C8E10 1
 '@BASEBOARD_FAB2_LIB.BASEBOARD_FAB2(SCH_1):PAGE240_I137@MSTR_DISCRETE.CAP(CHIPS)':
 'A': CDS_PINID='A';
NODE_NAME     C8E14 1
 '@BASEBOARD_FAB2_LIB.BASEBOARD_FAB2(SCH_1):PAGE240_I139@MSTR_DISCRETE.CAP(CHIPS)':
 'A': CDS_PINID='A';
NODE_NAME     EU8E1 2
 '@BASEBOARD_FAB2_LIB.BASEBOARD_FAB2(SCH_1):PAGE240_I170@MSTR_DISCRETE.CSD87384M(CHIPS)':
 'VIN': CDS_PINID='VIN';
NODE_NAME     C9F1 1
 '@BASEBOARD_FAB2_LIB.BASEBOARD_FAB2(SCH_1):PAGE240_I181@W_HDL.SC22U16V5MX-4-GP(CHIPS)':
 '1': CDS_PINID='\1\';
NODE_NAME     C22W11 1
 '@BASEBOARD_FAB2_LIB.BASEBOARD_FAB2(SCH_1):PAGE240_I182@W_HDL.SC22U16V5MX-4-GP(CHIPS)':
 '1': CDS_PINID='\1\';
NODE_NAME     C8E11 1
 '@BASEBOARD_FAB2_LIB.BASEBOARD_FAB2(SCH_1):PAGE240_I183@W_HDL.SC22U16V5MX-4-GP(CHIPS)':
 '1': CDS_PINID='\1\';
NODE_NAME     C22W12 1
 '@BASEBOARD_FAB2_LIB.BASEBOARD_FAB2(SCH_1):PAGE240_I186@W_HDL.SC22U16V5MX-4-GP(CHIPS)':
 '1': CDS_PINID='\1\';
NODE_NAME     FB9E1 2
 '@BASEBOARD_FAB2_LIB.BASEBOARD_FAB2(SCH_1):PAGE240_I193@W_HDL.BLM31SN500SN1L-GP(CHIPS)':
 '2': CDS_PINID='\2\';
NET_NAME
'VR_FET_SW_P12V_STBY_PVCCIN_CPU0'
 '@BASEBOARD_FAB2_LIB.BASEBOARD_FAB2(SCH_1):VR_FET_SW_P12V_STBY_PVCCIN_CPU0':
 C_SIGNAL='@baseboard_fab2_lib.baseboard_fab2(sch_1):vr_fet_sw_p12v_stby_pvccin_~
cpu0';
NODE_NAME     R4D27 1
 '@BASEBOARD_FAB2_LIB.BASEBOARD_FAB2(SCH_1):PAGE201_I54@MSTR_DISCRETE.RES(CHIPS)':
 'A': CDS_PINID='A';
NODE_NAME     C4E20 1
 '@BASEBOARD_FAB2_LIB.BASEBOARD_FAB2(SCH_1):PAGE202_I35@DEV_DISCRETE.CAP_A(CHIPS)':
 'A': CDS_PINID='A';
NODE_NAME     C4E19 1
 '@BASEBOARD_FAB2_LIB.BASEBOARD_FAB2(SCH_1):PAGE202_I36@MSTR_DISCRETE.CAP(CHIPS)':
 'A': CDS_PINID='A';
NODE_NAME     C6R11 1
 '@BASEBOARD_FAB2_LIB.BASEBOARD_FAB2(SCH_1):PAGE202_I37@MSTR_DISCRETE.CAP(CHIPS)':
 'A': CDS_PINID='A';
NODE_NAME     C6P13 1
 '@BASEBOARD_FAB2_LIB.BASEBOARD_FAB2(SCH_1):PAGE202_I38@MSTR_DISCRETE.CAP(CHIPS)':
 'A': CDS_PINID='A';
NODE_NAME     C6R13 1
 '@BASEBOARD_FAB2_LIB.BASEBOARD_FAB2(SCH_1):PAGE202_I42@MSTR_DISCRETE.CAP(CHIPS)':
 'A': CDS_PINID='A';
NODE_NAME     C4D49 1
 '@BASEBOARD_FAB2_LIB.BASEBOARD_FAB2(SCH_1):PAGE202_I46@DEV_DISCRETE.CAP_A(CHIPS)':
 'A': CDS_PINID='A';
NODE_NAME     C4D48 1
 '@BASEBOARD_FAB2_LIB.BASEBOARD_FAB2(SCH_1):PAGE202_I47@MSTR_DISCRETE.CAP(CHIPS)':
 'A': CDS_PINID='A';
NODE_NAME     C6R4 1
 '@BASEBOARD_FAB2_LIB.BASEBOARD_FAB2(SCH_1):PAGE202_I48@MSTR_DISCRETE.CAP(CHIPS)':
 'A': CDS_PINID='A';
NODE_NAME     C6P22 1
 '@BASEBOARD_FAB2_LIB.BASEBOARD_FAB2(SCH_1):PAGE202_I49@MSTR_DISCRETE.CAP(CHIPS)':
 'A': CDS_PINID='A';
NODE_NAME     C6N8 1
 '@BASEBOARD_FAB2_LIB.BASEBOARD_FAB2(SCH_1):PAGE202_I51@MSTR_DISCRETE.CAP(CHIPS)':
 'A': CDS_PINID='A';
NODE_NAME     EU4E1 25
 '@BASEBOARD_FAB2_LIB.BASEBOARD_FAB2(SCH_1):PAGE202_I63@MSTR_DISCRETE.IR354XX(CHIPS)':
 'VIN'<0>: CDS_PINID='VIN(0)';
NODE_NAME     EU4E1 30
 '@BASEBOARD_FAB2_LIB.BASEBOARD_FAB2(SCH_1):PAGE202_I63@MSTR_DISCRETE.IR354XX(CHIPS)':
 'VIN'<1>: CDS_PINID='VIN(1)';
NODE_NAME     EU4D6 25
 '@BASEBOARD_FAB2_LIB.BASEBOARD_FAB2(SCH_1):PAGE202_I64@MSTR_DISCRETE.IR354XX(CHIPS)':
 'VIN'<0>: CDS_PINID='VIN(0)';
NODE_NAME     EU4D6 30
 '@BASEBOARD_FAB2_LIB.BASEBOARD_FAB2(SCH_1):PAGE202_I64@MSTR_DISCRETE.IR354XX(CHIPS)':
 'VIN'<1>: CDS_PINID='VIN(1)';
NODE_NAME     C6P24 1
 '@BASEBOARD_FAB2_LIB.BASEBOARD_FAB2(SCH_1):PAGE203_I1@MSTR_DISCRETE.CAP(CHIPS)':
 'A': CDS_PINID='A';
NODE_NAME     C6R6 1
 '@BASEBOARD_FAB2_LIB.BASEBOARD_FAB2(SCH_1):PAGE203_I2@MSTR_DISCRETE.CAP(CHIPS)':
 'A': CDS_PINID='A';
NODE_NAME     C4D35 1
 '@BASEBOARD_FAB2_LIB.BASEBOARD_FAB2(SCH_1):PAGE203_I46@DEV_DISCRETE.CAP_A(CHIPS)':
 'A': CDS_PINID='A';
NODE_NAME     C4D30 1
 '@BASEBOARD_FAB2_LIB.BASEBOARD_FAB2(SCH_1):PAGE203_I47@MSTR_DISCRETE.CAP(CHIPS)':
 'A': CDS_PINID='A';
NODE_NAME     C4D11 1
 '@BASEBOARD_FAB2_LIB.BASEBOARD_FAB2(SCH_1):PAGE203_I52@DEV_DISCRETE.CAP_A(CHIPS)':
 'A': CDS_PINID='A';
NODE_NAME     C4D10 1
 '@BASEBOARD_FAB2_LIB.BASEBOARD_FAB2(SCH_1):PAGE203_I53@MSTR_DISCRETE.CAP(CHIPS)':
 'A': CDS_PINID='A';
NODE_NAME     C6P19 1
 '@BASEBOARD_FAB2_LIB.BASEBOARD_FAB2(SCH_1):PAGE203_I54@MSTR_DISCRETE.CAP(CHIPS)':
 'A': CDS_PINID='A';
NODE_NAME     C6P20 1
 '@BASEBOARD_FAB2_LIB.BASEBOARD_FAB2(SCH_1):PAGE203_I57@MSTR_DISCRETE.CAP(CHIPS)':
 'A': CDS_PINID='A';
NODE_NAME     C6P15 1
 '@BASEBOARD_FAB2_LIB.BASEBOARD_FAB2(SCH_1):PAGE203_I58@MSTR_DISCRETE.CAP(CHIPS)':
 'A': CDS_PINID='A';
NODE_NAME     C6P7 1
 '@BASEBOARD_FAB2_LIB.BASEBOARD_FAB2(SCH_1):PAGE203_I59@MSTR_DISCRETE.CAP(CHIPS)':
 'A': CDS_PINID='A';
NODE_NAME     EU4D3 25
 '@BASEBOARD_FAB2_LIB.BASEBOARD_FAB2(SCH_1):PAGE203_I70@MSTR_DISCRETE.IR354XX(CHIPS)':
 'VIN'<0>: CDS_PINID='VIN(0)';
NODE_NAME     EU4D3 30
 '@BASEBOARD_FAB2_LIB.BASEBOARD_FAB2(SCH_1):PAGE203_I70@MSTR_DISCRETE.IR354XX(CHIPS)':
 'VIN'<1>: CDS_PINID='VIN(1)';
NODE_NAME     EU4D1 25
 '@BASEBOARD_FAB2_LIB.BASEBOARD_FAB2(SCH_1):PAGE203_I71@MSTR_DISCRETE.IR354XX(CHIPS)':
 'VIN'<0>: CDS_PINID='VIN(0)';
NODE_NAME     EU4D1 30
 '@BASEBOARD_FAB2_LIB.BASEBOARD_FAB2(SCH_1):PAGE203_I71@MSTR_DISCRETE.IR354XX(CHIPS)':
 'VIN'<1>: CDS_PINID='VIN(1)';
NODE_NAME     C4C19 1
 '@BASEBOARD_FAB2_LIB.BASEBOARD_FAB2(SCH_1):PAGE204_I35@DEV_DISCRETE.CAP_A(CHIPS)':
 'A': CDS_PINID='A';
NODE_NAME     C4C18 1
 '@BASEBOARD_FAB2_LIB.BASEBOARD_FAB2(SCH_1):PAGE204_I36@MSTR_DISCRETE.CAP(CHIPS)':
 'A': CDS_PINID='A';
NODE_NAME     C6N10 1
 '@BASEBOARD_FAB2_LIB.BASEBOARD_FAB2(SCH_1):PAGE204_I37@MSTR_DISCRETE.CAP(CHIPS)':
 'A': CDS_PINID='A';
NODE_NAME     C6P17 1
 '@BASEBOARD_FAB2_LIB.BASEBOARD_FAB2(SCH_1):PAGE204_I38@MSTR_DISCRETE.CAP(CHIPS)':
 'A': CDS_PINID='A';
NODE_NAME     C6N11 1
 '@BASEBOARD_FAB2_LIB.BASEBOARD_FAB2(SCH_1):PAGE204_I42@MSTR_DISCRETE.CAP(CHIPS)':
 'A': CDS_PINID='A';
NODE_NAME     C4D2 1
 '@BASEBOARD_FAB2_LIB.BASEBOARD_FAB2(SCH_1):PAGE204_I48@MSTR_DISCRETE.CAPP(CHIPS)':
 'A': CDS_PINID='A';
NODE_NAME     C4E16 1
 '@BASEBOARD_FAB2_LIB.BASEBOARD_FAB2(SCH_1):PAGE204_I50@MSTR_DISCRETE.CAPP(CHIPS)':
 'A': CDS_PINID='A';
NODE_NAME     C4C12 1
 '@BASEBOARD_FAB2_LIB.BASEBOARD_FAB2(SCH_1):PAGE204_I67@MSTR_DISCRETE.CAPP(CHIPS)':
 'A': CDS_PINID='A';
NODE_NAME     EU4C2 25
 '@BASEBOARD_FAB2_LIB.BASEBOARD_FAB2(SCH_1):PAGE204_I71@MSTR_DISCRETE.IR354XX(CHIPS)':
 'VIN'<0>: CDS_PINID='VIN(0)';
NODE_NAME     EU4C2 30
 '@BASEBOARD_FAB2_LIB.BASEBOARD_FAB2(SCH_1):PAGE204_I71@MSTR_DISCRETE.IR354XX(CHIPS)':
 'VIN'<1>: CDS_PINID='VIN(1)';
NODE_NAME     C4C10 1
 '@BASEBOARD_FAB2_LIB.BASEBOARD_FAB2(SCH_1):PAGE205_I31@DEV_DISCRETE.CAP_A(CHIPS)':
 'A': CDS_PINID='A';
NODE_NAME     C4C9 1
 '@BASEBOARD_FAB2_LIB.BASEBOARD_FAB2(SCH_1):PAGE205_I32@MSTR_DISCRETE.CAP(CHIPS)':
 'A': CDS_PINID='A';
NODE_NAME     C6N2 1
 '@BASEBOARD_FAB2_LIB.BASEBOARD_FAB2(SCH_1):PAGE205_I33@MSTR_DISCRETE.CAP(CHIPS)':
 'A': CDS_PINID='A';
NODE_NAME     C6N3 1
 '@BASEBOARD_FAB2_LIB.BASEBOARD_FAB2(SCH_1):PAGE205_I34@MSTR_DISCRETE.CAP(CHIPS)':
 'A': CDS_PINID='A';
NODE_NAME     C6N6 1
 '@BASEBOARD_FAB2_LIB.BASEBOARD_FAB2(SCH_1):PAGE205_I35@MSTR_DISCRETE.CAP(CHIPS)':
 'A': CDS_PINID='A';
NODE_NAME     EU4C1 25
 '@BASEBOARD_FAB2_LIB.BASEBOARD_FAB2(SCH_1):PAGE205_I46@MSTR_DISCRETE.IR354XX(CHIPS)':
 'VIN'<0>: CDS_PINID='VIN(0)';
NODE_NAME     EU4C1 30
 '@BASEBOARD_FAB2_LIB.BASEBOARD_FAB2(SCH_1):PAGE205_I46@MSTR_DISCRETE.IR354XX(CHIPS)':
 'VIN'<1>: CDS_PINID='VIN(1)';
NODE_NAME     R4D60 1
 '@BASEBOARD_FAB2_LIB.BASEBOARD_FAB2(SCH_1):PAGE213_I31@MSTR_DISCRETE.RES(CHIPS)':
 'A': CDS_PINID='A';
NODE_NAME     C4E13 1
 '@BASEBOARD_FAB2_LIB.BASEBOARD_FAB2(SCH_1):PAGE214_I77@DEV_DISCRETE.CAP_A(CHIPS)':
 'A': CDS_PINID='A';
NODE_NAME     C4E15 1
 '@BASEBOARD_FAB2_LIB.BASEBOARD_FAB2(SCH_1):PAGE214_I79@MSTR_DISCRETE.CAP(CHIPS)':
 'A': CDS_PINID='A';
NODE_NAME     C6R14 1
 '@BASEBOARD_FAB2_LIB.BASEBOARD_FAB2(SCH_1):PAGE214_I80@MSTR_DISCRETE.CAP(CHIPS)':
 'A': CDS_PINID='A';
NODE_NAME     C6R10 1
 '@BASEBOARD_FAB2_LIB.BASEBOARD_FAB2(SCH_1):PAGE214_I81@MSTR_DISCRETE.CAP(CHIPS)':
 'A': CDS_PINID='A';
NODE_NAME     C6R8 1
 '@BASEBOARD_FAB2_LIB.BASEBOARD_FAB2(SCH_1):PAGE214_I83@MSTR_DISCRETE.CAP(CHIPS)':
 'A': CDS_PINID='A';
NODE_NAME     EU4E2 25
 '@BASEBOARD_FAB2_LIB.BASEBOARD_FAB2(SCH_1):PAGE214_I126@MSTR_DISCRETE.IR354XX(CHIPS)':
 'VIN'<0>: CDS_PINID='VIN(0)';
NODE_NAME     EU4E2 30
 '@BASEBOARD_FAB2_LIB.BASEBOARD_FAB2(SCH_1):PAGE214_I126@MSTR_DISCRETE.IR354XX(CHIPS)':
 'VIN'<1>: CDS_PINID='VIN(1)';
NODE_NAME     C4E14 1
 '@BASEBOARD_FAB2_LIB.BASEBOARD_FAB2(SCH_1):PAGE214_I148@W_HDL.SC22U16V5MX-4-GP(CHIPS)':
 '1': CDS_PINID='\1\';
NODE_NAME     C22W13 1
 '@BASEBOARD_FAB2_LIB.BASEBOARD_FAB2(SCH_1):PAGE214_I149@W_HDL.SC22U16V5MX-4-GP(CHIPS)':
 '1': CDS_PINID='\1\';
NODE_NAME     C22W14 1
 '@BASEBOARD_FAB2_LIB.BASEBOARD_FAB2(SCH_1):PAGE214_I152@W_HDL.SC22U16V5MX-4-GP(CHIPS)':
 '1': CDS_PINID='\1\';
NODE_NAME     C22W15 1
 '@BASEBOARD_FAB2_LIB.BASEBOARD_FAB2(SCH_1):PAGE214_I154@W_HDL.SC22U16V5MX-4-GP(CHIPS)':
 '1': CDS_PINID='\1\';
NODE_NAME     C22W18 1
 '@BASEBOARD_FAB2_LIB.BASEBOARD_FAB2(SCH_1):PAGE214_I156@W_HDL.SC22U16V5MX-4-GP(CHIPS)':
 '1': CDS_PINID='\1\';
NODE_NAME     C22W17 1
 '@BASEBOARD_FAB2_LIB.BASEBOARD_FAB2(SCH_1):PAGE214_I158@W_HDL.SC22U16V5MX-4-GP(CHIPS)':
 '1': CDS_PINID='\1\';
NODE_NAME     C22W16 1
 '@BASEBOARD_FAB2_LIB.BASEBOARD_FAB2(SCH_1):PAGE214_I160@W_HDL.SC22U16V5MX-4-GP(CHIPS)':
 '1': CDS_PINID='\1\';
NODE_NAME     C4E8 1
 '@BASEBOARD_FAB2_LIB.BASEBOARD_FAB2(SCH_1):PAGE214_I161@W_HDL.SC22U16V5MX-4-GP(CHIPS)':
 '1': CDS_PINID='\1\';
NODE_NAME     C4E9 1
 '@BASEBOARD_FAB2_LIB.BASEBOARD_FAB2(SCH_1):PAGE214_I164@W_HDL.SC22U16V5MX-4-GP(CHIPS)':
 '1': CDS_PINID='\1\';
NODE_NAME     C22W21 1
 '@BASEBOARD_FAB2_LIB.BASEBOARD_FAB2(SCH_1):PAGE214_I166@W_HDL.SC22U16V5MX-4-GP(CHIPS)':
 '1': CDS_PINID='\1\';
NODE_NAME     C22W20 1
 '@BASEBOARD_FAB2_LIB.BASEBOARD_FAB2(SCH_1):PAGE214_I168@W_HDL.SC22U16V5MX-4-GP(CHIPS)':
 '1': CDS_PINID='\1\';
NODE_NAME     C22W19 1
 '@BASEBOARD_FAB2_LIB.BASEBOARD_FAB2(SCH_1):PAGE214_I169@W_HDL.SC22U16V5MX-4-GP(CHIPS)':
 '1': CDS_PINID='\1\';
NODE_NAME     L4C1 2
 '@BASEBOARD_FAB2_LIB.BASEBOARD_FAB2(SCH_1):PAGE204_I105@W_HDL.IND-80NH-1-GP(CHIPS)':
 'F': CDS_PINID='F';
NET_NAME
'VR_FET_SW_P12V_STBY_PVCCIN_CPU1'
 '@BASEBOARD_FAB2_LIB.BASEBOARD_FAB2(SCH_1):VR_FET_SW_P12V_STBY_PVCCIN_CPU1':
 C_SIGNAL='@baseboard_fab2_lib.baseboard_fab2(sch_1):vr_fet_sw_p12v_stby_pvccin_~
cpu1';
NODE_NAME     R1C13 1
 '@BASEBOARD_FAB2_LIB.BASEBOARD_FAB2(SCH_1):PAGE206_I49@MSTR_DISCRETE.RES(CHIPS)':
 'A': CDS_PINID='A';
NODE_NAME     EU1E2 25
 '@BASEBOARD_FAB2_LIB.BASEBOARD_FAB2(SCH_1):PAGE207_I20@MSTR_DISCRETE.IR354XX(CHIPS)':
 'VIN'<0>: CDS_PINID='VIN(0)';
NODE_NAME     EU1E2 30
 '@BASEBOARD_FAB2_LIB.BASEBOARD_FAB2(SCH_1):PAGE207_I20@MSTR_DISCRETE.IR354XX(CHIPS)':
 'VIN'<1>: CDS_PINID='VIN(1)';
NODE_NAME     C1E14 1
 '@BASEBOARD_FAB2_LIB.BASEBOARD_FAB2(SCH_1):PAGE207_I33@DEV_DISCRETE.CAP_A(CHIPS)':
 'A': CDS_PINID='A';
NODE_NAME     C1E13 1
 '@BASEBOARD_FAB2_LIB.BASEBOARD_FAB2(SCH_1):PAGE207_I34@MSTR_DISCRETE.CAP(CHIPS)':
 'A': CDS_PINID='A';
NODE_NAME     C1D34 1
 '@BASEBOARD_FAB2_LIB.BASEBOARD_FAB2(SCH_1):PAGE207_I41@DEV_DISCRETE.CAP_A(CHIPS)':
 'A': CDS_PINID='A';
NODE_NAME     C1D35 1
 '@BASEBOARD_FAB2_LIB.BASEBOARD_FAB2(SCH_1):PAGE207_I42@MSTR_DISCRETE.CAP(CHIPS)':
 'A': CDS_PINID='A';
NODE_NAME     C9R7 1
 '@BASEBOARD_FAB2_LIB.BASEBOARD_FAB2(SCH_1):PAGE207_I43@MSTR_DISCRETE.CAP(CHIPS)':
 'A': CDS_PINID='A';
NODE_NAME     C9R10 1
 '@BASEBOARD_FAB2_LIB.BASEBOARD_FAB2(SCH_1):PAGE207_I44@MSTR_DISCRETE.CAP(CHIPS)':
 'A': CDS_PINID='A';
NODE_NAME     C9R11 1
 '@BASEBOARD_FAB2_LIB.BASEBOARD_FAB2(SCH_1):PAGE207_I48@MSTR_DISCRETE.CAP(CHIPS)':
 'A': CDS_PINID='A';
NODE_NAME     C9P22 1
 '@BASEBOARD_FAB2_LIB.BASEBOARD_FAB2(SCH_1):PAGE207_I50@MSTR_DISCRETE.CAP(CHIPS)':
 'A': CDS_PINID='A';
NODE_NAME     C9P25 1
 '@BASEBOARD_FAB2_LIB.BASEBOARD_FAB2(SCH_1):PAGE207_I51@MSTR_DISCRETE.CAP(CHIPS)':
 'A': CDS_PINID='A';
NODE_NAME     C9P26 1
 '@BASEBOARD_FAB2_LIB.BASEBOARD_FAB2(SCH_1):PAGE207_I54@MSTR_DISCRETE.CAP(CHIPS)':
 'A': CDS_PINID='A';
NODE_NAME     EU1D3 25
 '@BASEBOARD_FAB2_LIB.BASEBOARD_FAB2(SCH_1):PAGE208_I27@MSTR_DISCRETE.IR354XX(CHIPS)':
 'VIN'<0>: CDS_PINID='VIN(0)';
NODE_NAME     EU1D3 30
 '@BASEBOARD_FAB2_LIB.BASEBOARD_FAB2(SCH_1):PAGE208_I27@MSTR_DISCRETE.IR354XX(CHIPS)':
 'VIN'<1>: CDS_PINID='VIN(1)';
NODE_NAME     C1D28 1
 '@BASEBOARD_FAB2_LIB.BASEBOARD_FAB2(SCH_1):PAGE208_I44@DEV_DISCRETE.CAP_A(CHIPS)':
 'A': CDS_PINID='A';
NODE_NAME     C1D23 1
 '@BASEBOARD_FAB2_LIB.BASEBOARD_FAB2(SCH_1):PAGE208_I45@MSTR_DISCRETE.CAP(CHIPS)':
 'A': CDS_PINID='A';
NODE_NAME     C1D13 1
 '@BASEBOARD_FAB2_LIB.BASEBOARD_FAB2(SCH_1):PAGE208_I51@DEV_DISCRETE.CAP_A(CHIPS)':
 'A': CDS_PINID='A';
NODE_NAME     C1D12 1
 '@BASEBOARD_FAB2_LIB.BASEBOARD_FAB2(SCH_1):PAGE208_I52@MSTR_DISCRETE.CAP(CHIPS)':
 'A': CDS_PINID='A';
NODE_NAME     C9P4 1
 '@BASEBOARD_FAB2_LIB.BASEBOARD_FAB2(SCH_1):PAGE208_I53@MSTR_DISCRETE.CAP(CHIPS)':
 'A': CDS_PINID='A';
NODE_NAME     C9P7 1
 '@BASEBOARD_FAB2_LIB.BASEBOARD_FAB2(SCH_1):PAGE208_I54@MSTR_DISCRETE.CAP(CHIPS)':
 'A': CDS_PINID='A';
NODE_NAME     C9P9 1
 '@BASEBOARD_FAB2_LIB.BASEBOARD_FAB2(SCH_1):PAGE208_I55@MSTR_DISCRETE.CAP(CHIPS)':
 'A': CDS_PINID='A';
NODE_NAME     C9P24 1
 '@BASEBOARD_FAB2_LIB.BASEBOARD_FAB2(SCH_1):PAGE208_I58@MSTR_DISCRETE.CAP(CHIPS)':
 'A': CDS_PINID='A';
NODE_NAME     C9P1 1
 '@BASEBOARD_FAB2_LIB.BASEBOARD_FAB2(SCH_1):PAGE208_I59@MSTR_DISCRETE.CAP(CHIPS)':
 'A': CDS_PINID='A';
NODE_NAME     C9P2 1
 '@BASEBOARD_FAB2_LIB.BASEBOARD_FAB2(SCH_1):PAGE208_I60@MSTR_DISCRETE.CAP(CHIPS)':
 'A': CDS_PINID='A';
NODE_NAME     EU1D1 25
 '@BASEBOARD_FAB2_LIB.BASEBOARD_FAB2(SCH_1):PAGE208_I71@MSTR_DISCRETE.IR354XX(CHIPS)':
 'VIN'<0>: CDS_PINID='VIN(0)';
NODE_NAME     EU1D1 30
 '@BASEBOARD_FAB2_LIB.BASEBOARD_FAB2(SCH_1):PAGE208_I71@MSTR_DISCRETE.IR354XX(CHIPS)':
 'VIN'<1>: CDS_PINID='VIN(1)';
NODE_NAME     C9N27 1
 '@BASEBOARD_FAB2_LIB.BASEBOARD_FAB2(SCH_1):PAGE209_I5@MSTR_DISCRETE.CAP(CHIPS)':
 'A': CDS_PINID='A';
NODE_NAME     C9N26 1
 '@BASEBOARD_FAB2_LIB.BASEBOARD_FAB2(SCH_1):PAGE209_I7@MSTR_DISCRETE.CAP(CHIPS)':
 'A': CDS_PINID='A';
NODE_NAME     C9N25 1
 '@BASEBOARD_FAB2_LIB.BASEBOARD_FAB2(SCH_1):PAGE209_I8@MSTR_DISCRETE.CAP(CHIPS)':
 'A': CDS_PINID='A';
NODE_NAME     C1C26 1
 '@BASEBOARD_FAB2_LIB.BASEBOARD_FAB2(SCH_1):PAGE209_I16@MSTR_DISCRETE.CAP(CHIPS)':
 'A': CDS_PINID='A';
NODE_NAME     C1C25 1
 '@BASEBOARD_FAB2_LIB.BASEBOARD_FAB2(SCH_1):PAGE209_I17@DEV_DISCRETE.CAP_A(CHIPS)':
 'A': CDS_PINID='A';
NODE_NAME     C1C1 1
 '@BASEBOARD_FAB2_LIB.BASEBOARD_FAB2(SCH_1):PAGE209_I35@MSTR_DISCRETE.CAPP(CHIPS)':
 'A': CDS_PINID='A';
NODE_NAME     C1E18 1
 '@BASEBOARD_FAB2_LIB.BASEBOARD_FAB2(SCH_1):PAGE209_I37@MSTR_DISCRETE.CAPP(CHIPS)':
 'A': CDS_PINID='A';
NODE_NAME     C1C2 1
 '@BASEBOARD_FAB2_LIB.BASEBOARD_FAB2(SCH_1):PAGE209_I38@MSTR_DISCRETE.CAPP(CHIPS)':
 'A': CDS_PINID='A';
NODE_NAME     EU1C3 25
 '@BASEBOARD_FAB2_LIB.BASEBOARD_FAB2(SCH_1):PAGE209_I56@MSTR_DISCRETE.IR354XX(CHIPS)':
 'VIN'<0>: CDS_PINID='VIN(0)';
NODE_NAME     EU1C3 30
 '@BASEBOARD_FAB2_LIB.BASEBOARD_FAB2(SCH_1):PAGE209_I56@MSTR_DISCRETE.IR354XX(CHIPS)':
 'VIN'<1>: CDS_PINID='VIN(1)';
NODE_NAME     C1C17 1
 '@BASEBOARD_FAB2_LIB.BASEBOARD_FAB2(SCH_1):PAGE210_I27@DEV_DISCRETE.CAP_A(CHIPS)':
 'A': CDS_PINID='A';
NODE_NAME     C1C15 1
 '@BASEBOARD_FAB2_LIB.BASEBOARD_FAB2(SCH_1):PAGE210_I28@MSTR_DISCRETE.CAP(CHIPS)':
 'A': CDS_PINID='A';
NODE_NAME     C9N13 1
 '@BASEBOARD_FAB2_LIB.BASEBOARD_FAB2(SCH_1):PAGE210_I35@MSTR_DISCRETE.CAP(CHIPS)':
 'A': CDS_PINID='A';
NODE_NAME     C9N19 1
 '@BASEBOARD_FAB2_LIB.BASEBOARD_FAB2(SCH_1):PAGE210_I36@MSTR_DISCRETE.CAP(CHIPS)':
 'A': CDS_PINID='A';
NODE_NAME     C9N21 1
 '@BASEBOARD_FAB2_LIB.BASEBOARD_FAB2(SCH_1):PAGE210_I38@MSTR_DISCRETE.CAP(CHIPS)':
 'A': CDS_PINID='A';
NODE_NAME     EU1C1 25
 '@BASEBOARD_FAB2_LIB.BASEBOARD_FAB2(SCH_1):PAGE210_I51@MSTR_DISCRETE.IR354XX(CHIPS)':
 'VIN'<0>: CDS_PINID='VIN(0)';
NODE_NAME     EU1C1 30
 '@BASEBOARD_FAB2_LIB.BASEBOARD_FAB2(SCH_1):PAGE210_I51@MSTR_DISCRETE.IR354XX(CHIPS)':
 'VIN'<1>: CDS_PINID='VIN(1)';
NODE_NAME     L1B2 2
 '@BASEBOARD_FAB2_LIB.BASEBOARD_FAB2(SCH_1):PAGE209_I81@W_HDL.IND-80NH-1-GP(CHIPS)':
 'F': CDS_PINID='F';
NODE_NAME     EU1D4 25
 '@BASEBOARD_FAB2_LIB.BASEBOARD_FAB2(SCH_1):PAGE207_I113@MSTR_DISCRETE.IR354XX(CHIPS)':
 'VIN'<0>: CDS_PINID='VIN(0)';
NODE_NAME     EU1D4 30
 '@BASEBOARD_FAB2_LIB.BASEBOARD_FAB2(SCH_1):PAGE207_I113@MSTR_DISCRETE.IR354XX(CHIPS)':
 'VIN'<1>: CDS_PINID='VIN(1)';
NET_NAME
'VR_FET_SW_P12V_STBY_PVCCIO_CPU0'
 '@BASEBOARD_FAB2_LIB.BASEBOARD_FAB2(SCH_1):VR_FET_SW_P12V_STBY_PVCCIO_CPU0':
 C_SIGNAL='@baseboard_fab2_lib.baseboard_fab2(sch_1):vr_fet_sw_p12v_stby_pvccio_~
cpu0';
NODE_NAME     R3P12 1
 '@BASEBOARD_FAB2_LIB.BASEBOARD_FAB2(SCH_1):PAGE211_I31@MSTR_DISCRETE.RES(CHIPS)':
 'A': CDS_PINID='A';
NODE_NAME     C7C11 1
 '@BASEBOARD_FAB2_LIB.BASEBOARD_FAB2(SCH_1):PAGE212_I38@DEV_DISCRETE.CAP_A(CHIPS)':
 'A': CDS_PINID='A';
NODE_NAME     C7C12 1
 '@BASEBOARD_FAB2_LIB.BASEBOARD_FAB2(SCH_1):PAGE212_I39@MSTR_DISCRETE.CAP(CHIPS)':
 'A': CDS_PINID='A';
NODE_NAME     C3N36 1
 '@BASEBOARD_FAB2_LIB.BASEBOARD_FAB2(SCH_1):PAGE212_I40@MSTR_DISCRETE.CAP(CHIPS)':
 'A': CDS_PINID='A';
NODE_NAME     C3N33 1
 '@BASEBOARD_FAB2_LIB.BASEBOARD_FAB2(SCH_1):PAGE212_I41@MSTR_DISCRETE.CAP(CHIPS)':
 'A': CDS_PINID='A';
NODE_NAME     C3N34 1
 '@BASEBOARD_FAB2_LIB.BASEBOARD_FAB2(SCH_1):PAGE212_I43@MSTR_DISCRETE.CAP(CHIPS)':
 'A': CDS_PINID='A';
NODE_NAME     EU7C1 25
 '@BASEBOARD_FAB2_LIB.BASEBOARD_FAB2(SCH_1):PAGE212_I101@MSTR_DISCRETE.IR354XX(CHIPS)':
 'VIN'<0>: CDS_PINID='VIN(0)';
NODE_NAME     EU7C1 30
 '@BASEBOARD_FAB2_LIB.BASEBOARD_FAB2(SCH_1):PAGE212_I101@MSTR_DISCRETE.IR354XX(CHIPS)':
 'VIN'<1>: CDS_PINID='VIN(1)';
NODE_NAME     C22W33 1
 '@BASEBOARD_FAB2_LIB.BASEBOARD_FAB2(SCH_1):PAGE212_I124@W_HDL.SC22U16V5MX-4-GP(CHIPS)':
 '1': CDS_PINID='\1\';
NODE_NAME     C22W32 1
 '@BASEBOARD_FAB2_LIB.BASEBOARD_FAB2(SCH_1):PAGE212_I126@W_HDL.SC22U16V5MX-4-GP(CHIPS)':
 '1': CDS_PINID='\1\';
NODE_NAME     C22W31 1
 '@BASEBOARD_FAB2_LIB.BASEBOARD_FAB2(SCH_1):PAGE212_I129@W_HDL.SC22U16V5MX-4-GP(CHIPS)':
 '1': CDS_PINID='\1\';
NODE_NAME     C7C8 1
 '@BASEBOARD_FAB2_LIB.BASEBOARD_FAB2(SCH_1):PAGE212_I130@W_HDL.SC22U16V5MX-4-GP(CHIPS)':
 '1': CDS_PINID='\1\';
NODE_NAME     C22W30 1
 '@BASEBOARD_FAB2_LIB.BASEBOARD_FAB2(SCH_1):PAGE212_I132@W_HDL.SC22U16V5MX-4-GP(CHIPS)':
 '1': CDS_PINID='\1\';
NODE_NAME     C22W29 1
 '@BASEBOARD_FAB2_LIB.BASEBOARD_FAB2(SCH_1):PAGE212_I134@W_HDL.SC22U16V5MX-4-GP(CHIPS)':
 '1': CDS_PINID='\1\';
NODE_NAME     C22W28 1
 '@BASEBOARD_FAB2_LIB.BASEBOARD_FAB2(SCH_1):PAGE212_I136@W_HDL.SC22U16V5MX-4-GP(CHIPS)':
 '1': CDS_PINID='\1\';
NODE_NAME     C7C7 1
 '@BASEBOARD_FAB2_LIB.BASEBOARD_FAB2(SCH_1):PAGE212_I138@W_HDL.SC22U16V5MX-4-GP(CHIPS)':
 '1': CDS_PINID='\1\';
NODE_NAME     L7C1 2
 '@BASEBOARD_FAB2_LIB.BASEBOARD_FAB2(SCH_1):PAGE212_I142@W_HDL.IND-100NH-35-GP(CHIPS)':
 'F': CDS_PINID='F';
NET_NAME
'VR_FET_SW_P12V_STBY_PVDDQ_ABC'
 '@BASEBOARD_FAB2_LIB.BASEBOARD_FAB2(SCH_1):VR_FET_SW_P12V_STBY_PVDDQ_ABC':
 C_SIGNAL='@baseboard_fab2_lib.baseboard_fab2(sch_1):vr_fet_sw_p12v_stby_pvddq_a~
bc';
NODE_NAME     C3U2 1
 '@BASEBOARD_FAB2_LIB.BASEBOARD_FAB2(SCH_1):PAGE216_I45@MSTR_DISCRETE.CAP(CHIPS)':
 'A': CDS_PINID='A';
NODE_NAME     C3U3 1
 '@BASEBOARD_FAB2_LIB.BASEBOARD_FAB2(SCH_1):PAGE216_I46@MSTR_DISCRETE.CAP(CHIPS)':
 'A': CDS_PINID='A';
NODE_NAME     C3U4 1
 '@BASEBOARD_FAB2_LIB.BASEBOARD_FAB2(SCH_1):PAGE216_I47@MSTR_DISCRETE.CAP(CHIPS)':
 'A': CDS_PINID='A';
NODE_NAME     C7G37 1
 '@BASEBOARD_FAB2_LIB.BASEBOARD_FAB2(SCH_1):PAGE216_I48@MSTR_DISCRETE.CAP(CHIPS)':
 'A': CDS_PINID='A';
NODE_NAME     C7G29 1
 '@BASEBOARD_FAB2_LIB.BASEBOARD_FAB2(SCH_1):PAGE216_I51@DEV_DISCRETE.CAP_A(CHIPS)':
 'A': CDS_PINID='A';
NODE_NAME     C7G36 1
 '@BASEBOARD_FAB2_LIB.BASEBOARD_FAB2(SCH_1):PAGE216_I78@DEV_DISCRETE.CAP_A(CHIPS)':
 'A': CDS_PINID='A';
NODE_NAME     C7G30 1
 '@BASEBOARD_FAB2_LIB.BASEBOARD_FAB2(SCH_1):PAGE216_I79@MSTR_DISCRETE.CAP(CHIPS)':
 'A': CDS_PINID='A';
NODE_NAME     C3U9 1
 '@BASEBOARD_FAB2_LIB.BASEBOARD_FAB2(SCH_1):PAGE216_I80@MSTR_DISCRETE.CAP(CHIPS)':
 'A': CDS_PINID='A';
NODE_NAME     C3U7 1
 '@BASEBOARD_FAB2_LIB.BASEBOARD_FAB2(SCH_1):PAGE216_I81@MSTR_DISCRETE.CAP(CHIPS)':
 'A': CDS_PINID='A';
NODE_NAME     C3U6 1
 '@BASEBOARD_FAB2_LIB.BASEBOARD_FAB2(SCH_1):PAGE216_I84@MSTR_DISCRETE.CAP(CHIPS)':
 'A': CDS_PINID='A';
NODE_NAME     EU7G2 25
 '@BASEBOARD_FAB2_LIB.BASEBOARD_FAB2(SCH_1):PAGE216_I102@MSTR_DISCRETE.IR354XX(CHIPS)':
 'VIN'<0>: CDS_PINID='VIN(0)';
NODE_NAME     EU7G2 30
 '@BASEBOARD_FAB2_LIB.BASEBOARD_FAB2(SCH_1):PAGE216_I102@MSTR_DISCRETE.IR354XX(CHIPS)':
 'VIN'<1>: CDS_PINID='VIN(1)';
NODE_NAME     EU7G3 25
 '@BASEBOARD_FAB2_LIB.BASEBOARD_FAB2(SCH_1):PAGE216_I103@MSTR_DISCRETE.IR354XX(CHIPS)':
 'VIN'<0>: CDS_PINID='VIN(0)';
NODE_NAME     EU7G3 30
 '@BASEBOARD_FAB2_LIB.BASEBOARD_FAB2(SCH_1):PAGE216_I103@MSTR_DISCRETE.IR354XX(CHIPS)':
 'VIN'<1>: CDS_PINID='VIN(1)';
NODE_NAME     C7G2 1
 '@BASEBOARD_FAB2_LIB.BASEBOARD_FAB2(SCH_1):PAGE217_I175@MSTR_DISCRETE.CAPP(CHIPS)':
 'A': CDS_PINID='A';
NODE_NAME     L7F2 2
 '@BASEBOARD_FAB2_LIB.BASEBOARD_FAB2(SCH_1):PAGE217_I261@W_HDL.IND-100NH-35-GP(CHIPS)':
 'F': CDS_PINID='F';
NET_NAME
'VR_FET_SW_P12V_STBY_PVDDQ_DEF'
 '@BASEBOARD_FAB2_LIB.BASEBOARD_FAB2(SCH_1):VR_FET_SW_P12V_STBY_PVDDQ_DEF':
 C_SIGNAL='@baseboard_fab2_lib.baseboard_fab2(sch_1):vr_fet_sw_p12v_stby_pvddq_d~
ef';
NODE_NAME     C3L2 1
 '@BASEBOARD_FAB2_LIB.BASEBOARD_FAB2(SCH_1):PAGE219_I45@MSTR_DISCRETE.CAP(CHIPS)':
 'A': CDS_PINID='A';
NODE_NAME     C3L4 1
 '@BASEBOARD_FAB2_LIB.BASEBOARD_FAB2(SCH_1):PAGE219_I46@MSTR_DISCRETE.CAP(CHIPS)':
 'A': CDS_PINID='A';
NODE_NAME     C3L13 1
 '@BASEBOARD_FAB2_LIB.BASEBOARD_FAB2(SCH_1):PAGE219_I47@MSTR_DISCRETE.CAP(CHIPS)':
 'A': CDS_PINID='A';
NODE_NAME     C7A11 1
 '@BASEBOARD_FAB2_LIB.BASEBOARD_FAB2(SCH_1):PAGE219_I48@MSTR_DISCRETE.CAP(CHIPS)':
 'A': CDS_PINID='A';
NODE_NAME     C7A5 1
 '@BASEBOARD_FAB2_LIB.BASEBOARD_FAB2(SCH_1):PAGE219_I51@DEV_DISCRETE.CAP_A(CHIPS)':
 'A': CDS_PINID='A';
NODE_NAME     C7A20 1
 '@BASEBOARD_FAB2_LIB.BASEBOARD_FAB2(SCH_1):PAGE219_I78@DEV_DISCRETE.CAP_A(CHIPS)':
 'A': CDS_PINID='A';
NODE_NAME     C7A21 1
 '@BASEBOARD_FAB2_LIB.BASEBOARD_FAB2(SCH_1):PAGE219_I79@MSTR_DISCRETE.CAP(CHIPS)':
 'A': CDS_PINID='A';
NODE_NAME     C3L17 1
 '@BASEBOARD_FAB2_LIB.BASEBOARD_FAB2(SCH_1):PAGE219_I80@MSTR_DISCRETE.CAP(CHIPS)':
 'A': CDS_PINID='A';
NODE_NAME     C3L16 1
 '@BASEBOARD_FAB2_LIB.BASEBOARD_FAB2(SCH_1):PAGE219_I81@MSTR_DISCRETE.CAP(CHIPS)':
 'A': CDS_PINID='A';
NODE_NAME     C3L15 1
 '@BASEBOARD_FAB2_LIB.BASEBOARD_FAB2(SCH_1):PAGE219_I84@MSTR_DISCRETE.CAP(CHIPS)':
 'A': CDS_PINID='A';
NODE_NAME     EU7A1 25
 '@BASEBOARD_FAB2_LIB.BASEBOARD_FAB2(SCH_1):PAGE219_I106@MSTR_DISCRETE.IR354XX(CHIPS)':
 'VIN'<0>: CDS_PINID='VIN(0)';
NODE_NAME     EU7A1 30
 '@BASEBOARD_FAB2_LIB.BASEBOARD_FAB2(SCH_1):PAGE219_I106@MSTR_DISCRETE.IR354XX(CHIPS)':
 'VIN'<1>: CDS_PINID='VIN(1)';
NODE_NAME     EU7A4 25
 '@BASEBOARD_FAB2_LIB.BASEBOARD_FAB2(SCH_1):PAGE219_I107@MSTR_DISCRETE.IR354XX(CHIPS)':
 'VIN'<0>: CDS_PINID='VIN(0)';
NODE_NAME     EU7A4 30
 '@BASEBOARD_FAB2_LIB.BASEBOARD_FAB2(SCH_1):PAGE219_I107@MSTR_DISCRETE.IR354XX(CHIPS)':
 'VIN'<1>: CDS_PINID='VIN(1)';
NODE_NAME     R8A4 1
 '@BASEBOARD_FAB2_LIB.BASEBOARD_FAB2(SCH_1):PAGE235_I165@MSTR_DISCRETE.RES(CHIPS)':
 'A': CDS_PINID='A';
NODE_NAME     C7A39 1
 '@BASEBOARD_FAB2_LIB.BASEBOARD_FAB2(SCH_1):PAGE236_I20@DEV_DISCRETE.CAP_A(CHIPS)':
 'A': CDS_PINID='A';
NODE_NAME     C7A7 1
 '@BASEBOARD_FAB2_LIB.BASEBOARD_FAB2(SCH_1):PAGE236_I22@MSTR_DISCRETE.CAP(CHIPS)':
 'A': CDS_PINID='A';
NODE_NAME     C3L12 1
 '@BASEBOARD_FAB2_LIB.BASEBOARD_FAB2(SCH_1):PAGE236_I23@MSTR_DISCRETE.CAP(CHIPS)':
 'A': CDS_PINID='A';
NODE_NAME     C3L11 1
 '@BASEBOARD_FAB2_LIB.BASEBOARD_FAB2(SCH_1):PAGE236_I24@MSTR_DISCRETE.CAP(CHIPS)':
 'A': CDS_PINID='A';
NODE_NAME     C3L8 1
 '@BASEBOARD_FAB2_LIB.BASEBOARD_FAB2(SCH_1):PAGE236_I26@MSTR_DISCRETE.CAP(CHIPS)':
 'A': CDS_PINID='A';
NODE_NAME     C3L9 1
 '@BASEBOARD_FAB2_LIB.BASEBOARD_FAB2(SCH_1):PAGE236_I29@MSTR_DISCRETE.CAP(CHIPS)':
 'A': CDS_PINID='A';
NODE_NAME     C3L7 1
 '@BASEBOARD_FAB2_LIB.BASEBOARD_FAB2(SCH_1):PAGE236_I31@MSTR_DISCRETE.CAP(CHIPS)':
 'A': CDS_PINID='A';
NODE_NAME     C3L10 1
 '@BASEBOARD_FAB2_LIB.BASEBOARD_FAB2(SCH_1):PAGE236_I32@MSTR_DISCRETE.CAP(CHIPS)':
 'A': CDS_PINID='A';
NODE_NAME     C7A9 1
 '@BASEBOARD_FAB2_LIB.BASEBOARD_FAB2(SCH_1):PAGE236_I33@MSTR_DISCRETE.CAP(CHIPS)':
 'A': CDS_PINID='A';
NODE_NAME     C7A40 1
 '@BASEBOARD_FAB2_LIB.BASEBOARD_FAB2(SCH_1):PAGE236_I35@DEV_DISCRETE.CAP_A(CHIPS)':
 'A': CDS_PINID='A';
NODE_NAME     EU7A3 25
 '@BASEBOARD_FAB2_LIB.BASEBOARD_FAB2(SCH_1):PAGE236_I116@MSTR_DISCRETE.IR354XX(CHIPS)':
 'VIN'<0>: CDS_PINID='VIN(0)';
NODE_NAME     EU7A3 30
 '@BASEBOARD_FAB2_LIB.BASEBOARD_FAB2(SCH_1):PAGE236_I116@MSTR_DISCRETE.IR354XX(CHIPS)':
 'VIN'<1>: CDS_PINID='VIN(1)';
NODE_NAME     EU7A2 25
 '@BASEBOARD_FAB2_LIB.BASEBOARD_FAB2(SCH_1):PAGE236_I117@MSTR_DISCRETE.IR354XX(CHIPS)':
 'VIN'<0>: CDS_PINID='VIN(0)';
NODE_NAME     EU7A2 30
 '@BASEBOARD_FAB2_LIB.BASEBOARD_FAB2(SCH_1):PAGE236_I117@MSTR_DISCRETE.IR354XX(CHIPS)':
 'VIN'<1>: CDS_PINID='VIN(1)';
NODE_NAME     C22W23 1
 '@BASEBOARD_FAB2_LIB.BASEBOARD_FAB2(SCH_1):PAGE236_I159@W_HDL.SC22U16V5MX-4-GP(CHIPS)':
 '1': CDS_PINID='\1\';
NODE_NAME     C22W24 1
 '@BASEBOARD_FAB2_LIB.BASEBOARD_FAB2(SCH_1):PAGE236_I160@W_HDL.SC22U16V5MX-4-GP(CHIPS)':
 '1': CDS_PINID='\1\';
NODE_NAME     C7A13 1
 '@BASEBOARD_FAB2_LIB.BASEBOARD_FAB2(SCH_1):PAGE236_I161@W_HDL.SC22U16V5MX-4-GP(CHIPS)':
 '1': CDS_PINID='\1\';
NODE_NAME     C22W25 1
 '@BASEBOARD_FAB2_LIB.BASEBOARD_FAB2(SCH_1):PAGE236_I162@W_HDL.SC22U16V5MX-4-GP(CHIPS)':
 '1': CDS_PINID='\1\';
NODE_NAME     C22W27 1
 '@BASEBOARD_FAB2_LIB.BASEBOARD_FAB2(SCH_1):PAGE236_I163@W_HDL.SC22U16V5MX-4-GP(CHIPS)':
 '1': CDS_PINID='\1\';
NODE_NAME     C22W26 1
 '@BASEBOARD_FAB2_LIB.BASEBOARD_FAB2(SCH_1):PAGE236_I165@W_HDL.SC22U16V5MX-4-GP(CHIPS)':
 '1': CDS_PINID='\1\';
NODE_NAME     C22W22 1
 '@BASEBOARD_FAB2_LIB.BASEBOARD_FAB2(SCH_1):PAGE236_I171@W_HDL.SC22U16V5MX-4-GP(CHIPS)':
 '1': CDS_PINID='\1\';
NODE_NAME     C7A14 1
 '@BASEBOARD_FAB2_LIB.BASEBOARD_FAB2(SCH_1):PAGE236_I172@W_HDL.SC22U16V5MX-4-GP(CHIPS)':
 '1': CDS_PINID='\1\';
NODE_NAME     L7A5 2
 '@BASEBOARD_FAB2_LIB.BASEBOARD_FAB2(SCH_1):PAGE220_I241@W_HDL.IND-100NH-35-GP(CHIPS)':
 'F': CDS_PINID='F';
NODE_NAME     C7W5 1
 '@BASEBOARD_FAB2_LIB.BASEBOARD_FAB2(SCH_1):PAGE220_I298@W_HDL.SC22U16V5MX-4-GP(CHIPS)':
 '1': CDS_PINID='\1\';
NODE_NAME     C7W9 1
 '@BASEBOARD_FAB2_LIB.BASEBOARD_FAB2(SCH_1):PAGE220_I299@W_HDL.SC22U16V5MX-4-GP(CHIPS)':
 '1': CDS_PINID='\1\';
NODE_NAME     C7W8 1
 '@BASEBOARD_FAB2_LIB.BASEBOARD_FAB2(SCH_1):PAGE220_I300@W_HDL.SC22U16V5MX-4-GP(CHIPS)':
 '1': CDS_PINID='\1\';
NODE_NAME     C7W7 1
 '@BASEBOARD_FAB2_LIB.BASEBOARD_FAB2(SCH_1):PAGE220_I301@W_HDL.SC22U16V5MX-4-GP(CHIPS)':
 '1': CDS_PINID='\1\';
NODE_NAME     C7W6 1
 '@BASEBOARD_FAB2_LIB.BASEBOARD_FAB2(SCH_1):PAGE220_I302@W_HDL.SC22U16V5MX-4-GP(CHIPS)':
 '1': CDS_PINID='\1\';
NODE_NAME     C7W13 1
 '@BASEBOARD_FAB2_LIB.BASEBOARD_FAB2(SCH_1):PAGE220_I303@W_HDL.SC22U16V5MX-4-GP(CHIPS)':
 '1': CDS_PINID='\1\';
NODE_NAME     C7W12 1
 '@BASEBOARD_FAB2_LIB.BASEBOARD_FAB2(SCH_1):PAGE220_I304@W_HDL.SC22U16V5MX-4-GP(CHIPS)':
 '1': CDS_PINID='\1\';
NODE_NAME     C7W11 1
 '@BASEBOARD_FAB2_LIB.BASEBOARD_FAB2(SCH_1):PAGE220_I305@W_HDL.SC22U16V5MX-4-GP(CHIPS)':
 '1': CDS_PINID='\1\';
NODE_NAME     C7W10 1
 '@BASEBOARD_FAB2_LIB.BASEBOARD_FAB2(SCH_1):PAGE220_I306@W_HDL.SC22U16V5MX-4-GP(CHIPS)':
 '1': CDS_PINID='\1\';
NODE_NAME     C7W2 1
 '@BASEBOARD_FAB2_LIB.BASEBOARD_FAB2(SCH_1):PAGE220_I324@W_HDL.SE100U16VM-48-GP(CHIPS)':
 '1': CDS_PINID='\1\';
NET_NAME
'VR_FET_SW_P12V_STBY_PVDDQ_GHJ'
 '@BASEBOARD_FAB2_LIB.BASEBOARD_FAB2(SCH_1):VR_FET_SW_P12V_STBY_PVDDQ_GHJ':
 C_SIGNAL='@baseboard_fab2_lib.baseboard_fab2(sch_1):vr_fet_sw_p12v_stby_pvddq_g~
hj';
NODE_NAME     C9U6 1
 '@BASEBOARD_FAB2_LIB.BASEBOARD_FAB2(SCH_1):PAGE224_I45@MSTR_DISCRETE.CAP(CHIPS)':
 'A': CDS_PINID='A';
NODE_NAME     C9U4 1
 '@BASEBOARD_FAB2_LIB.BASEBOARD_FAB2(SCH_1):PAGE224_I46@MSTR_DISCRETE.CAP(CHIPS)':
 'A': CDS_PINID='A';
NODE_NAME     C9T4 1
 '@BASEBOARD_FAB2_LIB.BASEBOARD_FAB2(SCH_1):PAGE224_I47@MSTR_DISCRETE.CAP(CHIPS)':
 'A': CDS_PINID='A';
NODE_NAME     C1F27 1
 '@BASEBOARD_FAB2_LIB.BASEBOARD_FAB2(SCH_1):PAGE224_I48@MSTR_DISCRETE.CAP(CHIPS)':
 'A': CDS_PINID='A';
NODE_NAME     C1G14 1
 '@BASEBOARD_FAB2_LIB.BASEBOARD_FAB2(SCH_1):PAGE224_I51@DEV_DISCRETE.CAP_A(CHIPS)':
 'A': CDS_PINID='A';
NODE_NAME     C1F28 1
 '@BASEBOARD_FAB2_LIB.BASEBOARD_FAB2(SCH_1):PAGE224_I78@DEV_DISCRETE.CAP_A(CHIPS)':
 'A': CDS_PINID='A';
NODE_NAME     C1G13 1
 '@BASEBOARD_FAB2_LIB.BASEBOARD_FAB2(SCH_1):PAGE224_I79@MSTR_DISCRETE.CAP(CHIPS)':
 'A': CDS_PINID='A';
NODE_NAME     C9U3 1
 '@BASEBOARD_FAB2_LIB.BASEBOARD_FAB2(SCH_1):PAGE224_I80@MSTR_DISCRETE.CAP(CHIPS)':
 'A': CDS_PINID='A';
NODE_NAME     C9T6 1
 '@BASEBOARD_FAB2_LIB.BASEBOARD_FAB2(SCH_1):PAGE224_I81@MSTR_DISCRETE.CAP(CHIPS)':
 'A': CDS_PINID='A';
NODE_NAME     C9T9 1
 '@BASEBOARD_FAB2_LIB.BASEBOARD_FAB2(SCH_1):PAGE224_I84@MSTR_DISCRETE.CAP(CHIPS)':
 'A': CDS_PINID='A';
NODE_NAME     EU1G1 25
 '@BASEBOARD_FAB2_LIB.BASEBOARD_FAB2(SCH_1):PAGE224_I110@MSTR_DISCRETE.IR354XX(CHIPS)':
 'VIN'<0>: CDS_PINID='VIN(0)';
NODE_NAME     EU1G1 30
 '@BASEBOARD_FAB2_LIB.BASEBOARD_FAB2(SCH_1):PAGE224_I110@MSTR_DISCRETE.IR354XX(CHIPS)':
 'VIN'<1>: CDS_PINID='VIN(1)';
NODE_NAME     EU1F1 25
 '@BASEBOARD_FAB2_LIB.BASEBOARD_FAB2(SCH_1):PAGE224_I111@MSTR_DISCRETE.IR354XX(CHIPS)':
 'VIN'<0>: CDS_PINID='VIN(0)';
NODE_NAME     EU1F1 30
 '@BASEBOARD_FAB2_LIB.BASEBOARD_FAB2(SCH_1):PAGE224_I111@MSTR_DISCRETE.IR354XX(CHIPS)':
 'VIN'<1>: CDS_PINID='VIN(1)';
NODE_NAME     C22W1 1
 '@BASEBOARD_FAB2_LIB.BASEBOARD_FAB2(SCH_1):PAGE225_I246@W_HDL.SC22U16V5MX-4-GP(CHIPS)':
 '1': CDS_PINID='\1\';
NODE_NAME     C22W2 1
 '@BASEBOARD_FAB2_LIB.BASEBOARD_FAB2(SCH_1):PAGE225_I247@W_HDL.SC22U16V5MX-4-GP(CHIPS)':
 '1': CDS_PINID='\1\';
NODE_NAME     C22W3 1
 '@BASEBOARD_FAB2_LIB.BASEBOARD_FAB2(SCH_1):PAGE225_I249@W_HDL.SC22U16V5MX-4-GP(CHIPS)':
 '1': CDS_PINID='\1\';
NODE_NAME     C1G2 1
 '@BASEBOARD_FAB2_LIB.BASEBOARD_FAB2(SCH_1):PAGE225_I250@W_HDL.SC22U16V5MX-4-GP(CHIPS)':
 '1': CDS_PINID='\1\';
NODE_NAME     C22W4 1
 '@BASEBOARD_FAB2_LIB.BASEBOARD_FAB2(SCH_1):PAGE225_I251@W_HDL.SC22U16V5MX-4-GP(CHIPS)':
 '1': CDS_PINID='\1\';
NODE_NAME     L1F1 2
 '@BASEBOARD_FAB2_LIB.BASEBOARD_FAB2(SCH_1):PAGE225_I253@W_HDL.IND-100NH-35-GP(CHIPS)':
 'F': CDS_PINID='F';
NODE_NAME     C1G15 1
 '@BASEBOARD_FAB2_LIB.BASEBOARD_FAB2(SCH_1):PAGE225_I327@W_HDL.ST270U2D5VBM-GP(CHIPS)':
 '1': CDS_PINID='\1\';
NODE_NAME     C1G12 1
 '@BASEBOARD_FAB2_LIB.BASEBOARD_FAB2(SCH_1):PAGE225_I328@W_HDL.ST270U2D5VBM-GP(CHIPS)':
 '1': CDS_PINID='\1\';
NODE_NAME     C1G7 1
 '@BASEBOARD_FAB2_LIB.BASEBOARD_FAB2(SCH_1):PAGE225_I329@W_HDL.ST270U2D5VBM-GP(CHIPS)':
 '1': CDS_PINID='\1\';
NET_NAME
'VR_FET_SW_P12V_STBY_PVDDQ_KLM'
 '@BASEBOARD_FAB2_LIB.BASEBOARD_FAB2(SCH_1):VR_FET_SW_P12V_STBY_PVDDQ_KLM':
 C_SIGNAL='@baseboard_fab2_lib.baseboard_fab2(sch_1):vr_fet_sw_p12v_stby_pvddq_k~
lm';
NODE_NAME     C9L11 1
 '@BASEBOARD_FAB2_LIB.BASEBOARD_FAB2(SCH_1):PAGE227_I45@MSTR_DISCRETE.CAP(CHIPS)':
 'A': CDS_PINID='A';
NODE_NAME     C9L10 1
 '@BASEBOARD_FAB2_LIB.BASEBOARD_FAB2(SCH_1):PAGE227_I46@MSTR_DISCRETE.CAP(CHIPS)':
 'A': CDS_PINID='A';
NODE_NAME     C9L6 1
 '@BASEBOARD_FAB2_LIB.BASEBOARD_FAB2(SCH_1):PAGE227_I47@MSTR_DISCRETE.CAP(CHIPS)':
 'A': CDS_PINID='A';
NODE_NAME     C1A19 1
 '@BASEBOARD_FAB2_LIB.BASEBOARD_FAB2(SCH_1):PAGE227_I48@MSTR_DISCRETE.CAP(CHIPS)':
 'A': CDS_PINID='A';
NODE_NAME     C1A10 1
 '@BASEBOARD_FAB2_LIB.BASEBOARD_FAB2(SCH_1):PAGE227_I51@DEV_DISCRETE.CAP_A(CHIPS)':
 'A': CDS_PINID='A';
NODE_NAME     C1A20 1
 '@BASEBOARD_FAB2_LIB.BASEBOARD_FAB2(SCH_1):PAGE227_I78@DEV_DISCRETE.CAP_A(CHIPS)':
 'A': CDS_PINID='A';
NODE_NAME     C1A9 1
 '@BASEBOARD_FAB2_LIB.BASEBOARD_FAB2(SCH_1):PAGE227_I79@MSTR_DISCRETE.CAP(CHIPS)':
 'A': CDS_PINID='A';
NODE_NAME     C9L5 1
 '@BASEBOARD_FAB2_LIB.BASEBOARD_FAB2(SCH_1):PAGE227_I80@MSTR_DISCRETE.CAP(CHIPS)':
 'A': CDS_PINID='A';
NODE_NAME     C9L13 1
 '@BASEBOARD_FAB2_LIB.BASEBOARD_FAB2(SCH_1):PAGE227_I81@MSTR_DISCRETE.CAP(CHIPS)':
 'A': CDS_PINID='A';
NODE_NAME     C9L14 1
 '@BASEBOARD_FAB2_LIB.BASEBOARD_FAB2(SCH_1):PAGE227_I84@MSTR_DISCRETE.CAP(CHIPS)':
 'A': CDS_PINID='A';
NODE_NAME     EU1A2 25
 '@BASEBOARD_FAB2_LIB.BASEBOARD_FAB2(SCH_1):PAGE227_I101@MSTR_DISCRETE.IR354XX(CHIPS)':
 'VIN'<0>: CDS_PINID='VIN(0)';
NODE_NAME     EU1A2 30
 '@BASEBOARD_FAB2_LIB.BASEBOARD_FAB2(SCH_1):PAGE227_I101@MSTR_DISCRETE.IR354XX(CHIPS)':
 'VIN'<1>: CDS_PINID='VIN(1)';
NODE_NAME     EU1A1 25
 '@BASEBOARD_FAB2_LIB.BASEBOARD_FAB2(SCH_1):PAGE227_I102@MSTR_DISCRETE.IR354XX(CHIPS)':
 'VIN'<0>: CDS_PINID='VIN(0)';
NODE_NAME     EU1A1 30
 '@BASEBOARD_FAB2_LIB.BASEBOARD_FAB2(SCH_1):PAGE227_I102@MSTR_DISCRETE.IR354XX(CHIPS)':
 'VIN'<1>: CDS_PINID='VIN(1)';
NODE_NAME     C1B10 1
 '@BASEBOARD_FAB2_LIB.BASEBOARD_FAB2(SCH_1):PAGE228_I175@MSTR_DISCRETE.CAPP(CHIPS)':
 'A': CDS_PINID='A';
NODE_NAME     L1B1 2
 '@BASEBOARD_FAB2_LIB.BASEBOARD_FAB2(SCH_1):PAGE228_I247@W_HDL.IND-100NH-35-GP(CHIPS)':
 'F': CDS_PINID='F';
NET_NAME
'VR_FET_SW_P12V_STBY_PVPP_ABC'
 '@BASEBOARD_FAB2_LIB.BASEBOARD_FAB2(SCH_1):VR_FET_SW_P12V_STBY_PVPP_ABC':
 C_SIGNAL='@baseboard_fab2_lib.baseboard_fab2(sch_1):vr_fet_sw_p12v_stby_pvpp_ab~
c';
NODE_NAME     C3T10 1
 '@BASEBOARD_FAB2_LIB.BASEBOARD_FAB2(SCH_1):PAGE231_I161@MSTR_DISCRETE.CAP(CHIPS)':
 'A': CDS_PINID='A';
NODE_NAME     FB7F1 2
 '@BASEBOARD_FAB2_LIB.BASEBOARD_FAB2(SCH_1):PAGE231_I162@MSTR_DISCRETE.FERRITE(CHIPS)':
 'B': CDS_PINID='B';
NODE_NAME     EU7F1 39
 '@BASEBOARD_FAB2_LIB.BASEBOARD_FAB2(SCH_1):PAGE231_I193@MSTR_VREG.NCP3232L(CHIPS)':
 'VCC': CDS_PINID='VCC';
NODE_NAME     EU7F1 8
 '@BASEBOARD_FAB2_LIB.BASEBOARD_FAB2(SCH_1):PAGE231_I193@MSTR_VREG.NCP3232L(CHIPS)':
 'VIN'<0>: CDS_PINID='VIN(0)';
NODE_NAME     EU7F1 9
 '@BASEBOARD_FAB2_LIB.BASEBOARD_FAB2(SCH_1):PAGE231_I193@MSTR_VREG.NCP3232L(CHIPS)':
 'VIN'<1>: CDS_PINID='VIN(1)';
NODE_NAME     EU7F1 10
 '@BASEBOARD_FAB2_LIB.BASEBOARD_FAB2(SCH_1):PAGE231_I193@MSTR_VREG.NCP3232L(CHIPS)':
 'VIN'<2>: CDS_PINID='VIN(2)';
NODE_NAME     EU7F1 11
 '@BASEBOARD_FAB2_LIB.BASEBOARD_FAB2(SCH_1):PAGE231_I193@MSTR_VREG.NCP3232L(CHIPS)':
 'VIN'<3>: CDS_PINID='VIN(3)';
NODE_NAME     EU7F1 12
 '@BASEBOARD_FAB2_LIB.BASEBOARD_FAB2(SCH_1):PAGE231_I193@MSTR_VREG.NCP3232L(CHIPS)':
 'VIN'<4>: CDS_PINID='VIN(4)';
NODE_NAME     EU7F1 13
 '@BASEBOARD_FAB2_LIB.BASEBOARD_FAB2(SCH_1):PAGE231_I193@MSTR_VREG.NCP3232L(CHIPS)':
 'VIN'<5>: CDS_PINID='VIN(5)';
NODE_NAME     EU7F1 14
 '@BASEBOARD_FAB2_LIB.BASEBOARD_FAB2(SCH_1):PAGE231_I193@MSTR_VREG.NCP3232L(CHIPS)':
 'VIN'<6>: CDS_PINID='VIN(6)';
NODE_NAME     EU7F1 42
 '@BASEBOARD_FAB2_LIB.BASEBOARD_FAB2(SCH_1):PAGE231_I193@MSTR_VREG.NCP3232L(CHIPS)':
 'VIN'<7>: CDS_PINID='VIN(7)';
NODE_NAME     C7F6 1
 '@BASEBOARD_FAB2_LIB.BASEBOARD_FAB2(SCH_1):PAGE231_I205@DEV_DISCRETE.CAP_A(CHIPS)':
 'A': CDS_PINID='A';
NODE_NAME     C7F5 1
 '@BASEBOARD_FAB2_LIB.BASEBOARD_FAB2(SCH_1):PAGE231_I209@MSTR_DISCRETE.CAP(CHIPS)':
 'A': CDS_PINID='A';
NODE_NAME     C3T8 1
 '@BASEBOARD_FAB2_LIB.BASEBOARD_FAB2(SCH_1):PAGE231_I210@MSTR_DISCRETE.CAP(CHIPS)':
 'A': CDS_PINID='A';
NODE_NAME     C3T14 1
 '@BASEBOARD_FAB2_LIB.BASEBOARD_FAB2(SCH_1):PAGE231_I211@MSTR_DISCRETE.CAP(CHIPS)':
 'A': CDS_PINID='A';
NODE_NAME     C3T12 1
 '@BASEBOARD_FAB2_LIB.BASEBOARD_FAB2(SCH_1):PAGE231_I215@MSTR_DISCRETE.CAP(CHIPS)':
 'A': CDS_PINID='A';
NODE_NAME     C22W10 1
 '@BASEBOARD_FAB2_LIB.BASEBOARD_FAB2(SCH_1):PAGE231_I225@W_HDL.SC22U16V5MX-4-GP(CHIPS)':
 '1': CDS_PINID='\1\';
NODE_NAME     C7F7 1
 '@BASEBOARD_FAB2_LIB.BASEBOARD_FAB2(SCH_1):PAGE231_I226@W_HDL.SC22U16V5MX-4-GP(CHIPS)':
 '1': CDS_PINID='\1\';
NET_NAME
'VR_FET_SW_P12V_STBY_PVPP_DEF'
 '@BASEBOARD_FAB2_LIB.BASEBOARD_FAB2(SCH_1):VR_FET_SW_P12V_STBY_PVPP_DEF':
 C_SIGNAL='@baseboard_fab2_lib.baseboard_fab2(sch_1):vr_fet_sw_p12v_stby_pvpp_de~
f';
NODE_NAME     FB7B1 2
 '@BASEBOARD_FAB2_LIB.BASEBOARD_FAB2(SCH_1):PAGE232_I200@MSTR_DISCRETE.FERRITE(CHIPS)':
 'B': CDS_PINID='B';
NODE_NAME     C3M9 1
 '@BASEBOARD_FAB2_LIB.BASEBOARD_FAB2(SCH_1):PAGE232_I207@MSTR_DISCRETE.CAP(CHIPS)':
 'A': CDS_PINID='A';
NODE_NAME     EU7B1 39
 '@BASEBOARD_FAB2_LIB.BASEBOARD_FAB2(SCH_1):PAGE232_I214@MSTR_VREG.NCP3232L(CHIPS)':
 'VCC': CDS_PINID='VCC';
NODE_NAME     EU7B1 8
 '@BASEBOARD_FAB2_LIB.BASEBOARD_FAB2(SCH_1):PAGE232_I214@MSTR_VREG.NCP3232L(CHIPS)':
 'VIN'<0>: CDS_PINID='VIN(0)';
NODE_NAME     EU7B1 9
 '@BASEBOARD_FAB2_LIB.BASEBOARD_FAB2(SCH_1):PAGE232_I214@MSTR_VREG.NCP3232L(CHIPS)':
 'VIN'<1>: CDS_PINID='VIN(1)';
NODE_NAME     EU7B1 10
 '@BASEBOARD_FAB2_LIB.BASEBOARD_FAB2(SCH_1):PAGE232_I214@MSTR_VREG.NCP3232L(CHIPS)':
 'VIN'<2>: CDS_PINID='VIN(2)';
NODE_NAME     EU7B1 11
 '@BASEBOARD_FAB2_LIB.BASEBOARD_FAB2(SCH_1):PAGE232_I214@MSTR_VREG.NCP3232L(CHIPS)':
 'VIN'<3>: CDS_PINID='VIN(3)';
NODE_NAME     EU7B1 12
 '@BASEBOARD_FAB2_LIB.BASEBOARD_FAB2(SCH_1):PAGE232_I214@MSTR_VREG.NCP3232L(CHIPS)':
 'VIN'<4>: CDS_PINID='VIN(4)';
NODE_NAME     EU7B1 13
 '@BASEBOARD_FAB2_LIB.BASEBOARD_FAB2(SCH_1):PAGE232_I214@MSTR_VREG.NCP3232L(CHIPS)':
 'VIN'<5>: CDS_PINID='VIN(5)';
NODE_NAME     EU7B1 14
 '@BASEBOARD_FAB2_LIB.BASEBOARD_FAB2(SCH_1):PAGE232_I214@MSTR_VREG.NCP3232L(CHIPS)':
 'VIN'<6>: CDS_PINID='VIN(6)';
NODE_NAME     EU7B1 42
 '@BASEBOARD_FAB2_LIB.BASEBOARD_FAB2(SCH_1):PAGE232_I214@MSTR_VREG.NCP3232L(CHIPS)':
 'VIN'<7>: CDS_PINID='VIN(7)';
NODE_NAME     C7B6 1
 '@BASEBOARD_FAB2_LIB.BASEBOARD_FAB2(SCH_1):PAGE232_I252@DEV_DISCRETE.CAP_A(CHIPS)':
 'A': CDS_PINID='A';
NODE_NAME     C3M8 1
 '@BASEBOARD_FAB2_LIB.BASEBOARD_FAB2(SCH_1):PAGE232_I259@MSTR_DISCRETE.CAP(CHIPS)':
 'A': CDS_PINID='A';
NODE_NAME     C3M15 1
 '@BASEBOARD_FAB2_LIB.BASEBOARD_FAB2(SCH_1):PAGE232_I260@MSTR_DISCRETE.CAP(CHIPS)':
 'A': CDS_PINID='A';
NODE_NAME     C3M16 1
 '@BASEBOARD_FAB2_LIB.BASEBOARD_FAB2(SCH_1):PAGE232_I261@MSTR_DISCRETE.CAP(CHIPS)':
 'A': CDS_PINID='A';
NODE_NAME     C7B5 1
 '@BASEBOARD_FAB2_LIB.BASEBOARD_FAB2(SCH_1):PAGE232_I262@MSTR_DISCRETE.CAP(CHIPS)':
 'A': CDS_PINID='A';
NODE_NAME     C7B8 1
 '@BASEBOARD_FAB2_LIB.BASEBOARD_FAB2(SCH_1):PAGE232_I309@W_HDL.SC22U16V5MX-4-GP(CHIPS)':
 '1': CDS_PINID='\1\';
NODE_NAME     C22W7 1
 '@BASEBOARD_FAB2_LIB.BASEBOARD_FAB2(SCH_1):PAGE232_I311@W_HDL.SC22U16V5MX-4-GP(CHIPS)':
 '1': CDS_PINID='\1\';
NET_NAME
'VR_FET_SW_P12V_STBY_PVPP_GHJ'
 '@BASEBOARD_FAB2_LIB.BASEBOARD_FAB2(SCH_1):VR_FET_SW_P12V_STBY_PVPP_GHJ':
 C_SIGNAL='@baseboard_fab2_lib.baseboard_fab2(sch_1):vr_fet_sw_p12v_stby_pvpp_gh~
j';
NODE_NAME     C4G4 1
 '@BASEBOARD_FAB2_LIB.BASEBOARD_FAB2(SCH_1):PAGE233_I196@MSTR_DISCRETE.CAP(CHIPS)':
 'A': CDS_PINID='A';
NODE_NAME     FB4G1 2
 '@BASEBOARD_FAB2_LIB.BASEBOARD_FAB2(SCH_1):PAGE233_I198@MSTR_DISCRETE.FERRITE(CHIPS)':
 'B': CDS_PINID='B';
NODE_NAME     EU4G1 39
 '@BASEBOARD_FAB2_LIB.BASEBOARD_FAB2(SCH_1):PAGE233_I225@MSTR_VREG.NCP3232L(CHIPS)':
 'VCC': CDS_PINID='VCC';
NODE_NAME     EU4G1 8
 '@BASEBOARD_FAB2_LIB.BASEBOARD_FAB2(SCH_1):PAGE233_I225@MSTR_VREG.NCP3232L(CHIPS)':
 'VIN'<0>: CDS_PINID='VIN(0)';
NODE_NAME     EU4G1 9
 '@BASEBOARD_FAB2_LIB.BASEBOARD_FAB2(SCH_1):PAGE233_I225@MSTR_VREG.NCP3232L(CHIPS)':
 'VIN'<1>: CDS_PINID='VIN(1)';
NODE_NAME     EU4G1 10
 '@BASEBOARD_FAB2_LIB.BASEBOARD_FAB2(SCH_1):PAGE233_I225@MSTR_VREG.NCP3232L(CHIPS)':
 'VIN'<2>: CDS_PINID='VIN(2)';
NODE_NAME     EU4G1 11
 '@BASEBOARD_FAB2_LIB.BASEBOARD_FAB2(SCH_1):PAGE233_I225@MSTR_VREG.NCP3232L(CHIPS)':
 'VIN'<3>: CDS_PINID='VIN(3)';
NODE_NAME     EU4G1 12
 '@BASEBOARD_FAB2_LIB.BASEBOARD_FAB2(SCH_1):PAGE233_I225@MSTR_VREG.NCP3232L(CHIPS)':
 'VIN'<4>: CDS_PINID='VIN(4)';
NODE_NAME     EU4G1 13
 '@BASEBOARD_FAB2_LIB.BASEBOARD_FAB2(SCH_1):PAGE233_I225@MSTR_VREG.NCP3232L(CHIPS)':
 'VIN'<5>: CDS_PINID='VIN(5)';
NODE_NAME     EU4G1 14
 '@BASEBOARD_FAB2_LIB.BASEBOARD_FAB2(SCH_1):PAGE233_I225@MSTR_VREG.NCP3232L(CHIPS)':
 'VIN'<6>: CDS_PINID='VIN(6)';
NODE_NAME     EU4G1 42
 '@BASEBOARD_FAB2_LIB.BASEBOARD_FAB2(SCH_1):PAGE233_I225@MSTR_VREG.NCP3232L(CHIPS)':
 'VIN'<7>: CDS_PINID='VIN(7)';
NODE_NAME     C6U5 1
 '@BASEBOARD_FAB2_LIB.BASEBOARD_FAB2(SCH_1):PAGE233_I242@DEV_DISCRETE.CAP_A(CHIPS)':
 'A': CDS_PINID='A';
NODE_NAME     C6U4 1
 '@BASEBOARD_FAB2_LIB.BASEBOARD_FAB2(SCH_1):PAGE233_I248@MSTR_DISCRETE.CAP(CHIPS)':
 'A': CDS_PINID='A';
NODE_NAME     C4G2 1
 '@BASEBOARD_FAB2_LIB.BASEBOARD_FAB2(SCH_1):PAGE233_I253@MSTR_DISCRETE.CAP(CHIPS)':
 'A': CDS_PINID='A';
NODE_NAME     C6U7 1
 '@BASEBOARD_FAB2_LIB.BASEBOARD_FAB2(SCH_1):PAGE233_I254@MSTR_DISCRETE.CAP(CHIPS)':
 'A': CDS_PINID='A';
NODE_NAME     C6U8 1
 '@BASEBOARD_FAB2_LIB.BASEBOARD_FAB2(SCH_1):PAGE233_I255@MSTR_DISCRETE.CAP(CHIPS)':
 'A': CDS_PINID='A';
NODE_NAME     C22W6 1
 '@BASEBOARD_FAB2_LIB.BASEBOARD_FAB2(SCH_1):PAGE233_I278@W_HDL.SC22U16V5MX-4-GP(CHIPS)':
 '1': CDS_PINID='\1\';
NODE_NAME     C4G5 1
 '@BASEBOARD_FAB2_LIB.BASEBOARD_FAB2(SCH_1):PAGE233_I280@W_HDL.SC22U16V5MX-4-GP(CHIPS)':
 '1': CDS_PINID='\1\';
NET_NAME
'VR_FET_SW_P12V_STBY_PVPP_KLM'
 '@BASEBOARD_FAB2_LIB.BASEBOARD_FAB2(SCH_1):VR_FET_SW_P12V_STBY_PVPP_KLM':
 C_SIGNAL='@baseboard_fab2_lib.baseboard_fab2(sch_1):vr_fet_sw_p12v_stby_pvpp_kl~
m';
NODE_NAME     C6L11 1
 '@BASEBOARD_FAB2_LIB.BASEBOARD_FAB2(SCH_1):PAGE234_I152@MSTR_DISCRETE.CAP(CHIPS)':
 'A': CDS_PINID='A';
NODE_NAME     FB4A1 2
 '@BASEBOARD_FAB2_LIB.BASEBOARD_FAB2(SCH_1):PAGE234_I154@MSTR_DISCRETE.FERRITE(CHIPS)':
 'B': CDS_PINID='B';
NODE_NAME     EU4A3 39
 '@BASEBOARD_FAB2_LIB.BASEBOARD_FAB2(SCH_1):PAGE234_I184@MSTR_VREG.NCP3232L(CHIPS)':
 'VCC': CDS_PINID='VCC';
NODE_NAME     EU4A3 8
 '@BASEBOARD_FAB2_LIB.BASEBOARD_FAB2(SCH_1):PAGE234_I184@MSTR_VREG.NCP3232L(CHIPS)':
 'VIN'<0>: CDS_PINID='VIN(0)';
NODE_NAME     EU4A3 9
 '@BASEBOARD_FAB2_LIB.BASEBOARD_FAB2(SCH_1):PAGE234_I184@MSTR_VREG.NCP3232L(CHIPS)':
 'VIN'<1>: CDS_PINID='VIN(1)';
NODE_NAME     EU4A3 10
 '@BASEBOARD_FAB2_LIB.BASEBOARD_FAB2(SCH_1):PAGE234_I184@MSTR_VREG.NCP3232L(CHIPS)':
 'VIN'<2>: CDS_PINID='VIN(2)';
NODE_NAME     EU4A3 11
 '@BASEBOARD_FAB2_LIB.BASEBOARD_FAB2(SCH_1):PAGE234_I184@MSTR_VREG.NCP3232L(CHIPS)':
 'VIN'<3>: CDS_PINID='VIN(3)';
NODE_NAME     EU4A3 12
 '@BASEBOARD_FAB2_LIB.BASEBOARD_FAB2(SCH_1):PAGE234_I184@MSTR_VREG.NCP3232L(CHIPS)':
 'VIN'<4>: CDS_PINID='VIN(4)';
NODE_NAME     EU4A3 13
 '@BASEBOARD_FAB2_LIB.BASEBOARD_FAB2(SCH_1):PAGE234_I184@MSTR_VREG.NCP3232L(CHIPS)':
 'VIN'<5>: CDS_PINID='VIN(5)';
NODE_NAME     EU4A3 14
 '@BASEBOARD_FAB2_LIB.BASEBOARD_FAB2(SCH_1):PAGE234_I184@MSTR_VREG.NCP3232L(CHIPS)':
 'VIN'<6>: CDS_PINID='VIN(6)';
NODE_NAME     EU4A3 42
 '@BASEBOARD_FAB2_LIB.BASEBOARD_FAB2(SCH_1):PAGE234_I184@MSTR_VREG.NCP3232L(CHIPS)':
 'VIN'<7>: CDS_PINID='VIN(7)';
NODE_NAME     C4A20 1
 '@BASEBOARD_FAB2_LIB.BASEBOARD_FAB2(SCH_1):PAGE234_I199@DEV_DISCRETE.CAP_A(CHIPS)':
 'A': CDS_PINID='A';
NODE_NAME     C6L10 1
 '@BASEBOARD_FAB2_LIB.BASEBOARD_FAB2(SCH_1):PAGE234_I202@MSTR_DISCRETE.CAP(CHIPS)':
 'A': CDS_PINID='A';
NODE_NAME     C6M3 1
 '@BASEBOARD_FAB2_LIB.BASEBOARD_FAB2(SCH_1):PAGE234_I203@MSTR_DISCRETE.CAP(CHIPS)':
 'A': CDS_PINID='A';
NODE_NAME     C6M5 1
 '@BASEBOARD_FAB2_LIB.BASEBOARD_FAB2(SCH_1):PAGE234_I204@MSTR_DISCRETE.CAP(CHIPS)':
 'A': CDS_PINID='A';
NODE_NAME     C4A19 1
 '@BASEBOARD_FAB2_LIB.BASEBOARD_FAB2(SCH_1):PAGE234_I205@MSTR_DISCRETE.CAP(CHIPS)':
 'A': CDS_PINID='A';
NODE_NAME     C22W5 1
 '@BASEBOARD_FAB2_LIB.BASEBOARD_FAB2(SCH_1):PAGE234_I222@W_HDL.SC22U16V5MX-4-GP(CHIPS)':
 '1': CDS_PINID='\1\';
NODE_NAME     C4B1 1
 '@BASEBOARD_FAB2_LIB.BASEBOARD_FAB2(SCH_1):PAGE234_I223@W_HDL.SC22U16V5MX-4-GP(CHIPS)':
 '1': CDS_PINID='\1\';
NET_NAME
'VR_FET_SW_P5V_STBY_PVIN'
 '@BASEBOARD_FAB2_LIB.BASEBOARD_FAB2(SCH_1):VR_FET_SW_P5V_STBY_PVIN':
 C_SIGNAL='@baseboard_fab2_lib.baseboard_fab2(sch_1):vr_fet_sw_p5v_stby_pvin';
NODE_NAME     R7E17 1
 '@BASEBOARD_FAB2_LIB.BASEBOARD_FAB2(SCH_1):PAGE241_I37@MSTR_DISCRETE.RES(CHIPS)':
 'A': CDS_PINID='A';
NODE_NAME     C7E11 1
 '@BASEBOARD_FAB2_LIB.BASEBOARD_FAB2(SCH_1):PAGE241_I39@MSTR_DISCRETE.CAP(CHIPS)':
 'A': CDS_PINID='A';
NODE_NAME     FB7E1 2
 '@BASEBOARD_FAB2_LIB.BASEBOARD_FAB2(SCH_1):PAGE241_I82@MSTR_DISCRETE.FERRITE(CHIPS)':
 'B': CDS_PINID='B';
NODE_NAME     EU7E2 4
 '@BASEBOARD_FAB2_LIB.BASEBOARD_FAB2(SCH_1):PAGE241_I83@MSTR_VREG.TPS54821(CHIPS)':
 'PVIN'<0>: CDS_PINID='PVIN(0)';
NODE_NAME     EU7E2 5
 '@BASEBOARD_FAB2_LIB.BASEBOARD_FAB2(SCH_1):PAGE241_I83@MSTR_VREG.TPS54821(CHIPS)':
 'PVIN'<1>: CDS_PINID='PVIN(1)';
NODE_NAME     C7E13 1
 '@BASEBOARD_FAB2_LIB.BASEBOARD_FAB2(SCH_1):PAGE241_I92@W_HDL.SC22U16V5MX-4-GP(CHIPS)':
 '1': CDS_PINID='\1\';
NODE_NAME     C22W9 1
 '@BASEBOARD_FAB2_LIB.BASEBOARD_FAB2(SCH_1):PAGE241_I95@W_HDL.SC22U16V5MX-4-GP(CHIPS)':
 '1': CDS_PINID='\1\';
NODE_NAME     C22W8 1
 '@BASEBOARD_FAB2_LIB.BASEBOARD_FAB2(SCH_1):PAGE241_I96@W_HDL.SC22U16V5MX-4-GP(CHIPS)':
 '1': CDS_PINID='\1\';
NODE_NAME     C7E12 1
 '@BASEBOARD_FAB2_LIB.BASEBOARD_FAB2(SCH_1):PAGE241_I98@W_HDL.SC22U16V5MX-4-GP(CHIPS)':
 '1': CDS_PINID='\1\';
NET_NAME
'VR_P1V05_PCH_BIREF1'
 '@BASEBOARD_FAB2_LIB.BASEBOARD_FAB2(SCH_1):VR_P1V05_PCH_BIREF1':
 C_SIGNAL='@baseboard_fab2_lib.baseboard_fab2(sch_1):vr_p1v05_pch_biref1';
NODE_NAME     EU8A1 25
 '@BASEBOARD_FAB2_LIB.BASEBOARD_FAB2(SCH_1):PAGE235_I229@MSTR_CONTROLLER.PXE1110B(CHIPS)':
 'BIREF1': CDS_PINID='BIREF1';
NODE_NAME     EU7A2 39
 '@BASEBOARD_FAB2_LIB.BASEBOARD_FAB2(SCH_1):PAGE236_I117@MSTR_DISCRETE.IR354XX(CHIPS)':
 'REFIN': CDS_PINID='REFIN';
NODE_NAME     CT67 1
 '@BASEBOARD_FAB2_LIB.BASEBOARD_FAB2(SCH_1):PAGE236_I124@DEV_DISCRETE.CAP_A(CHIPS)':
 'A': CDS_PINID='A';
NODE_NAME     CF24 1
 '@BASEBOARD_FAB2_LIB.BASEBOARD_FAB2(SCH_1):PAGE235_I240@W_HDL.SC22P50V2JN-4GP(CHIPS)':
 '1': CDS_PINID='\1\';
NODE_NAME     RF24 1
 '@BASEBOARD_FAB2_LIB.BASEBOARD_FAB2(SCH_1):PAGE235_I242@MSTR_DISCRETE.RES(CHIPS)':
 'A': CDS_PINID='A';
NET_NAME
'VR_P1V05_PCH_STBY_AVSP'
 '@BASEBOARD_FAB2_LIB.BASEBOARD_FAB2(SCH_1):VR_P1V05_PCH_STBY_AVSP':
 C_SIGNAL='@baseboard_fab2_lib.baseboard_fab2(sch_1):vr_p1v05_pch_stby_avsp';
NODE_NAME     C2L2 1
 '@BASEBOARD_FAB2_LIB.BASEBOARD_FAB2(SCH_1):PAGE235_I153@MSTR_DISCRETE.CAP(CHIPS)':
 'A': CDS_PINID='A';
NODE_NAME     R2L8 2
 '@BASEBOARD_FAB2_LIB.BASEBOARD_FAB2(SCH_1):PAGE235_I154@MSTR_DISCRETE.RES(CHIPS)':
 'B': CDS_PINID='B';
NODE_NAME     EU8A1 29
 '@BASEBOARD_FAB2_LIB.BASEBOARD_FAB2(SCH_1):PAGE235_I229@MSTR_CONTROLLER.PXE1110B(CHIPS)':
 'BVSEN': CDS_PINID='BVSEN';
NET_NAME
'VR_P1V05_PCH_STBY_OCSET'
 '@BASEBOARD_FAB2_LIB.BASEBOARD_FAB2(SCH_1):VR_P1V05_PCH_STBY_OCSET':
 C_SIGNAL='@baseboard_fab2_lib.baseboard_fab2(sch_1):vr_p1v05_pch_stby_ocset';
NODE_NAME     EU7A2 37
 '@BASEBOARD_FAB2_LIB.BASEBOARD_FAB2(SCH_1):PAGE236_I117@MSTR_DISCRETE.IR354XX(CHIPS)':
 'OCSET': CDS_PINID='OCSET';
NODE_NAME     R3L14 1
 '@BASEBOARD_FAB2_LIB.BASEBOARD_FAB2(SCH_1):PAGE236_I120@MSTR_DISCRETE.RES(CHIPS)':
 'A': CDS_PINID='A';
NET_NAME
'VR_P1V05_PCH_STBY_PH1_BOOT'
 '@BASEBOARD_FAB2_LIB.BASEBOARD_FAB2(SCH_1):VR_P1V05_PCH_STBY_PH1_BOOT':
 C_SIGNAL='@baseboard_fab2_lib.baseboard_fab2(sch_1):vr_p1v05_pch_stby_ph1_boot';
NODE_NAME     C7A44 1
 '@BASEBOARD_FAB2_LIB.BASEBOARD_FAB2(SCH_1):PAGE236_I34@MSTR_DISCRETE.CAP(CHIPS)':
 'A': CDS_PINID='A';
NODE_NAME     RT46 1
 '@BASEBOARD_FAB2_LIB.BASEBOARD_FAB2(SCH_1):PAGE236_I154@MSTR_DISCRETE.RES(CHIPS)':
 'A': CDS_PINID='A';
NET_NAME
'VR_P1V05_PCH_STBY_PH1_BOOT_R'
 '@BASEBOARD_FAB2_LIB.BASEBOARD_FAB2(SCH_1):VR_P1V05_PCH_STBY_PH1_BOOT_R':
 C_SIGNAL='@baseboard_fab2_lib.baseboard_fab2(sch_1):vr_p1v05_pch_stby_ph1_boot_~
r';
NODE_NAME     EU7A2 33
 '@BASEBOARD_FAB2_LIB.BASEBOARD_FAB2(SCH_1):PAGE236_I117@MSTR_DISCRETE.IR354XX(CHIPS)':
 'BOOST': CDS_PINID='BOOST';
NODE_NAME     RT46 2
 '@BASEBOARD_FAB2_LIB.BASEBOARD_FAB2(SCH_1):PAGE236_I154@MSTR_DISCRETE.RES(CHIPS)':
 'B': CDS_PINID='B';
NET_NAME
'VR_P1V05_PCH_STBY_PH1_PHASE'
 '@BASEBOARD_FAB2_LIB.BASEBOARD_FAB2(SCH_1):VR_P1V05_PCH_STBY_PH1_PHASE':
 C_SIGNAL='@baseboard_fab2_lib.baseboard_fab2(sch_1):vr_p1v05_pch_stby_ph1_phase~
';
NODE_NAME     C7A44 2
 '@BASEBOARD_FAB2_LIB.BASEBOARD_FAB2(SCH_1):PAGE236_I34@MSTR_DISCRETE.CAP(CHIPS)':
 'B': CDS_PINID='B';
NODE_NAME     EU7A2 32
 '@BASEBOARD_FAB2_LIB.BASEBOARD_FAB2(SCH_1):PAGE236_I117@MSTR_DISCRETE.IR354XX(CHIPS)':
 'PHASE': CDS_PINID='PHASE';
NET_NAME
'VR_P1V05_PCH_STBY_PH1_PHASE_SW'
 '@BASEBOARD_FAB2_LIB.BASEBOARD_FAB2(SCH_1):VR_P1V05_PCH_STBY_PH1_PHASE_SW':
 C_SIGNAL='@baseboard_fab2_lib.baseboard_fab2(sch_1):vr_p1v05_pch_stby_ph1_phase~
_sw';
NODE_NAME     EU7A2 10
 '@BASEBOARD_FAB2_LIB.BASEBOARD_FAB2(SCH_1):PAGE236_I117@MSTR_DISCRETE.IR354XX(CHIPS)':
 'SW': CDS_PINID='SW';
NODE_NAME     CT68 1
 '@BASEBOARD_FAB2_LIB.BASEBOARD_FAB2(SCH_1):PAGE236_I150@MSTR_DISCRETE.CAP(CHIPS)':
 'A': CDS_PINID='A';
NODE_NAME     L7A4 1
 '@BASEBOARD_FAB2_LIB.BASEBOARD_FAB2(SCH_1):PAGE236_I179@W_HDL.IND-300NH-20-GP(CHIPS)':
 'S': CDS_PINID='S';
NET_NAME
'VR_P1V05_PCH_STBY_PH1_SW_RC'
 '@BASEBOARD_FAB2_LIB.BASEBOARD_FAB2(SCH_1):VR_P1V05_PCH_STBY_PH1_SW_RC':
 C_SIGNAL='@baseboard_fab2_lib.baseboard_fab2(sch_1):vr_p1v05_pch_stby_ph1_sw_rc~
';
NODE_NAME     CT68 2
 '@BASEBOARD_FAB2_LIB.BASEBOARD_FAB2(SCH_1):PAGE236_I150@MSTR_DISCRETE.CAP(CHIPS)':
 'B': CDS_PINID='B';
NODE_NAME     RT45 1
 '@BASEBOARD_FAB2_LIB.BASEBOARD_FAB2(SCH_1):PAGE236_I183@W_HDL.1R3F-GP(CHIPS)':
 '1': CDS_PINID='\1\';
NET_NAME
'VR_P1V05_PCH_STBY_PH1_VCIN'
 '@BASEBOARD_FAB2_LIB.BASEBOARD_FAB2(SCH_1):VR_P1V05_PCH_STBY_PH1_VCIN':
 C_SIGNAL='@baseboard_fab2_lib.baseboard_fab2(sch_1):vr_p1v05_pch_stby_ph1_vcin';
NODE_NAME     C7A10 1
 '@BASEBOARD_FAB2_LIB.BASEBOARD_FAB2(SCH_1):PAGE236_I36@MSTR_DISCRETE.CAP(CHIPS)':
 'A': CDS_PINID='A';
NODE_NAME     EU7A2 3
 '@BASEBOARD_FAB2_LIB.BASEBOARD_FAB2(SCH_1):PAGE236_I117@MSTR_DISCRETE.IR354XX(CHIPS)':
 'VCC': CDS_PINID='VCC';
NODE_NAME     R3L4 1
 '@BASEBOARD_FAB2_LIB.BASEBOARD_FAB2(SCH_1):PAGE236_I177@MSTR_DISCRETE.RES(CHIPS)':
 'A': CDS_PINID='A';
NET_NAME
'VR_P1V05_PCH_STBY_PWM1'
 '@BASEBOARD_FAB2_LIB.BASEBOARD_FAB2(SCH_1):VR_P1V05_PCH_STBY_PWM1':
 C_SIGNAL='@baseboard_fab2_lib.baseboard_fab2(sch_1):vr_p1v05_pch_stby_pwm1';
NODE_NAME     EU8A1 3
 '@BASEBOARD_FAB2_LIB.BASEBOARD_FAB2(SCH_1):PAGE235_I229@MSTR_CONTROLLER.PXE1110B(CHIPS)':
 'BPWM1': CDS_PINID='BPWM1';
NODE_NAME     EU7A2 34
 '@BASEBOARD_FAB2_LIB.BASEBOARD_FAB2(SCH_1):PAGE236_I117@MSTR_DISCRETE.IR354XX(CHIPS)':
 'PWM': CDS_PINID='PWM';
NET_NAME
'VR_P1V15_BMC_STBY_FB'
 '@BASEBOARD_FAB2_LIB.BASEBOARD_FAB2(SCH_1):VR_P1V15_BMC_STBY_FB':
 C_SIGNAL='@baseboard_fab2_lib.baseboard_fab2(sch_1):vr_p1v15_bmc_stby_fb';
NODE_NAME     R9F8 2
 '@BASEBOARD_FAB2_LIB.BASEBOARD_FAB2(SCH_1):PAGE238_I14@MSTR_DISCRETE.RES(CHIPS)':
 'B': CDS_PINID='B';
NODE_NAME     EU9F1 4
 '@BASEBOARD_FAB2_LIB.BASEBOARD_FAB2(SCH_1):PAGE238_I40@MSTR_VREG.RT9059(CHIPS)':
 'ADJ_NC': CDS_PINID='ADJ_NC';
NODE_NAME     R9F6 2
 '@BASEBOARD_FAB2_LIB.BASEBOARD_FAB2(SCH_1):PAGE238_I45@W_HDL.4K42R2F-GP(CHIPS)':
 '2': CDS_PINID='\2\';
NET_NAME
'VR_P1V2_BMC_STBY_FB'
 '@BASEBOARD_FAB2_LIB.BASEBOARD_FAB2(SCH_1):VR_P1V2_BMC_STBY_FB':
 C_SIGNAL='@baseboard_fab2_lib.baseboard_fab2(sch_1):vr_p1v2_bmc_stby_fb';
NODE_NAME     EU9F2 4
 '@BASEBOARD_FAB2_LIB.BASEBOARD_FAB2(SCH_1):PAGE239_I70@MSTR_VREG.RT9059(CHIPS)':
 'ADJ_NC': CDS_PINID='ADJ_NC';
NODE_NAME     R9F31 2
 '@BASEBOARD_FAB2_LIB.BASEBOARD_FAB2(SCH_1):PAGE239_I98@W_HDL.5K1R2F-2-GP(CHIPS)':
 '2': CDS_PINID='\2\';
NODE_NAME     R9F32 1
 '@BASEBOARD_FAB2_LIB.BASEBOARD_FAB2(SCH_1):PAGE239_I100@MSTR_DISCRETE.RES(CHIPS)':
 'A': CDS_PINID='A';
NET_NAME
'VR_P1V8_PCH_STBY_FB'
 '@BASEBOARD_FAB2_LIB.BASEBOARD_FAB2(SCH_1):VR_P1V8_PCH_STBY_FB':
 C_SIGNAL='@baseboard_fab2_lib.baseboard_fab2(sch_1):vr_p1v8_pch_stby_fb';
NODE_NAME     R2L19 1
 '@BASEBOARD_FAB2_LIB.BASEBOARD_FAB2(SCH_1):PAGE237_I80@MSTR_DISCRETE.RES(CHIPS)':
 'A': CDS_PINID='A';
NODE_NAME     R2L20 2
 '@BASEBOARD_FAB2_LIB.BASEBOARD_FAB2(SCH_1):PAGE237_I81@MSTR_DISCRETE.RES(CHIPS)':
 'B': CDS_PINID='B';
NODE_NAME     EU8A2 4
 '@BASEBOARD_FAB2_LIB.BASEBOARD_FAB2(SCH_1):PAGE237_I86@MSTR_VREG.RT9059(CHIPS)':
 'ADJ_NC': CDS_PINID='ADJ_NC';
NET_NAME
'VR_P2V5_BMC_STBY_FB'
 '@BASEBOARD_FAB2_LIB.BASEBOARD_FAB2(SCH_1):VR_P2V5_BMC_STBY_FB':
 C_SIGNAL='@baseboard_fab2_lib.baseboard_fab2(sch_1):vr_p2v5_bmc_stby_fb';
NODE_NAME     EU25F2 4
 '@BASEBOARD_FAB2_LIB.BASEBOARD_FAB2(SCH_1):PAGE239_I73@MSTR_VREG.RT9059(CHIPS)':
 'ADJ_NC': CDS_PINID='ADJ_NC';
NODE_NAME     R9W32 1
 '@BASEBOARD_FAB2_LIB.BASEBOARD_FAB2(SCH_1):PAGE239_I101@MSTR_DISCRETE.RES(CHIPS)':
 'A': CDS_PINID='A';
NODE_NAME     R9W31 2
 '@BASEBOARD_FAB2_LIB.BASEBOARD_FAB2(SCH_1):PAGE239_I102@W_HDL.21K5R2F-GP(CHIPS)':
 '2': CDS_PINID='\2\';
NET_NAME
'VR_P3V3_STBY_BOOT'
 '@BASEBOARD_FAB2_LIB.BASEBOARD_FAB2(SCH_1):VR_P3V3_STBY_BOOT':
 C_SIGNAL='@baseboard_fab2_lib.baseboard_fab2(sch_1):vr_p3v3_stby_boot';
NODE_NAME     EU8F1 4
 '@BASEBOARD_FAB2_LIB.BASEBOARD_FAB2(SCH_1):PAGE240_I125@MSTR_VREG.RT8240(CHIPS)':
 'BOOT': CDS_PINID='BOOT';
NODE_NAME     R8E35 1
 '@BASEBOARD_FAB2_LIB.BASEBOARD_FAB2(SCH_1):PAGE240_I127@MSTR_DISCRETE.RES(CHIPS)':
 'A': CDS_PINID='A';
NET_NAME
'VR_P3V3_STBY_BOOT_R'
 '@BASEBOARD_FAB2_LIB.BASEBOARD_FAB2(SCH_1):VR_P3V3_STBY_BOOT_R':
 C_SIGNAL='@baseboard_fab2_lib.baseboard_fab2(sch_1):vr_p3v3_stby_boot_r';
NODE_NAME     R8E35 2
 '@BASEBOARD_FAB2_LIB.BASEBOARD_FAB2(SCH_1):PAGE240_I127@MSTR_DISCRETE.RES(CHIPS)':
 'B': CDS_PINID='B';
NODE_NAME     C8E12 2
 '@BASEBOARD_FAB2_LIB.BASEBOARD_FAB2(SCH_1):PAGE240_I129@MSTR_DISCRETE.CAP(CHIPS)':
 'B': CDS_PINID='B';
NET_NAME
'VR_P3V3_STBY_EN'
 '@BASEBOARD_FAB2_LIB.BASEBOARD_FAB2(SCH_1):VR_P3V3_STBY_EN':
 C_SIGNAL='@baseboard_fab2_lib.baseboard_fab2(sch_1):vr_p3v3_stby_en';
NODE_NAME     EU8F1 8
 '@BASEBOARD_FAB2_LIB.BASEBOARD_FAB2(SCH_1):PAGE240_I125@MSTR_VREG.RT8240(CHIPS)':
 'EN': CDS_PINID='EN';
NODE_NAME     R8F2 2
 '@BASEBOARD_FAB2_LIB.BASEBOARD_FAB2(SCH_1):PAGE240_I176@MSTR_DISCRETE.RES(CHIPS)':
 'B': CDS_PINID='B';
NODE_NAME     R8E40 2
 '@BASEBOARD_FAB2_LIB.BASEBOARD_FAB2(SCH_1):PAGE240_I177@MSTR_DISCRETE.RES(CHIPS)':
 'B': CDS_PINID='B';
NET_NAME
'VR_P3V3_STBY_LGATE'
 '@BASEBOARD_FAB2_LIB.BASEBOARD_FAB2(SCH_1):VR_P3V3_STBY_LGATE':
 C_SIGNAL='@baseboard_fab2_lib.baseboard_fab2(sch_1):vr_p3v3_stby_lgate';
NODE_NAME     EU8F1 1
 '@BASEBOARD_FAB2_LIB.BASEBOARD_FAB2(SCH_1):PAGE240_I125@MSTR_VREG.RT8240(CHIPS)':
 'LGATE': CDS_PINID='LGATE';
NODE_NAME     EU8E1 4
 '@BASEBOARD_FAB2_LIB.BASEBOARD_FAB2(SCH_1):PAGE240_I170@MSTR_DISCRETE.CSD87384M(CHIPS)':
 'BG': CDS_PINID='BG';
NET_NAME
'VR_P3V3_STBY_OCSELECT'
 '@BASEBOARD_FAB2_LIB.BASEBOARD_FAB2(SCH_1):VR_P3V3_STBY_OCSELECT':
 C_SIGNAL='@baseboard_fab2_lib.baseboard_fab2(sch_1):vr_p3v3_stby_ocselect';
NODE_NAME     EU8F1 10
 '@BASEBOARD_FAB2_LIB.BASEBOARD_FAB2(SCH_1):PAGE240_I125@MSTR_VREG.RT8240(CHIPS)':
 'CS': CDS_PINID='CS';
NODE_NAME     R8F9 1
 '@BASEBOARD_FAB2_LIB.BASEBOARD_FAB2(SCH_1):PAGE240_I195@MSTR_DISCRETE.RES(CHIPS)':
 'A': CDS_PINID='A';
NET_NAME
'VR_P3V3_STBY_PHASE'
 '@BASEBOARD_FAB2_LIB.BASEBOARD_FAB2(SCH_1):VR_P3V3_STBY_PHASE':
 C_SIGNAL='@baseboard_fab2_lib.baseboard_fab2(sch_1):vr_p3v3_stby_phase';
NODE_NAME     EU8F1 2
 '@BASEBOARD_FAB2_LIB.BASEBOARD_FAB2(SCH_1):PAGE240_I125@MSTR_VREG.RT8240(CHIPS)':
 'PHASE': CDS_PINID='PHASE';
NODE_NAME     C8E12 1
 '@BASEBOARD_FAB2_LIB.BASEBOARD_FAB2(SCH_1):PAGE240_I129@MSTR_DISCRETE.CAP(CHIPS)':
 'A': CDS_PINID='A';
NODE_NAME     C8F3 1
 '@BASEBOARD_FAB2_LIB.BASEBOARD_FAB2(SCH_1):PAGE240_I163@MSTR_DISCRETE.CAP(CHIPS)':
 'A': CDS_PINID='A';
NODE_NAME     EU8E1 5
 '@BASEBOARD_FAB2_LIB.BASEBOARD_FAB2(SCH_1):PAGE240_I170@MSTR_DISCRETE.CSD87384M(CHIPS)':
 'VSW': CDS_PINID='VSW';
NODE_NAME     L8F1 1
 '@BASEBOARD_FAB2_LIB.BASEBOARD_FAB2(SCH_1):PAGE240_I188@W_HDL.IND-1UH-361-GP(CHIPS)':
 '1': CDS_PINID='\1\';
NET_NAME
'VR_P3V3_STBY_SNUB'
 '@BASEBOARD_FAB2_LIB.BASEBOARD_FAB2(SCH_1):VR_P3V3_STBY_SNUB':
 C_SIGNAL='@baseboard_fab2_lib.baseboard_fab2(sch_1):vr_p3v3_stby_snub';
NODE_NAME     R8F3 1
 '@BASEBOARD_FAB2_LIB.BASEBOARD_FAB2(SCH_1):PAGE240_I148@MSTR_DISCRETE.RES(CHIPS)':
 'A': CDS_PINID='A';
NODE_NAME     C8F3 2
 '@BASEBOARD_FAB2_LIB.BASEBOARD_FAB2(SCH_1):PAGE240_I163@MSTR_DISCRETE.CAP(CHIPS)':
 'B': CDS_PINID='B';
NET_NAME
'VR_P3V3_STBY_UGATE'
 '@BASEBOARD_FAB2_LIB.BASEBOARD_FAB2(SCH_1):VR_P3V3_STBY_UGATE':
 C_SIGNAL='@baseboard_fab2_lib.baseboard_fab2(sch_1):vr_p3v3_stby_ugate';
NODE_NAME     EU8F1 3
 '@BASEBOARD_FAB2_LIB.BASEBOARD_FAB2(SCH_1):PAGE240_I125@MSTR_VREG.RT8240(CHIPS)':
 'UGATE': CDS_PINID='UGATE';
NODE_NAME     EU8E1 1
 '@BASEBOARD_FAB2_LIB.BASEBOARD_FAB2(SCH_1):PAGE240_I170@MSTR_DISCRETE.CSD87384M(CHIPS)':
 'TG': CDS_PINID='TG';
NET_NAME
'VR_P5V_STBY_BOOT'
 '@BASEBOARD_FAB2_LIB.BASEBOARD_FAB2(SCH_1):VR_P5V_STBY_BOOT':
 C_SIGNAL='@baseboard_fab2_lib.baseboard_fab2(sch_1):vr_p5v_stby_boot';
NODE_NAME     C8E6 1
 '@BASEBOARD_FAB2_LIB.BASEBOARD_FAB2(SCH_1):PAGE241_I12@MSTR_DISCRETE.CAP(CHIPS)':
 'A': CDS_PINID='A';
NODE_NAME     EU7E2 13
 '@BASEBOARD_FAB2_LIB.BASEBOARD_FAB2(SCH_1):PAGE241_I83@MSTR_VREG.TPS54821(CHIPS)':
 'BOOT': CDS_PINID='BOOT';
NET_NAME
'VR_P5V_STBY_COMP'
 '@BASEBOARD_FAB2_LIB.BASEBOARD_FAB2(SCH_1):VR_P5V_STBY_COMP':
 C_SIGNAL='@baseboard_fab2_lib.baseboard_fab2(sch_1):vr_p5v_stby_comp';
NODE_NAME     C8E16 1
 '@BASEBOARD_FAB2_LIB.BASEBOARD_FAB2(SCH_1):PAGE241_I53@MSTR_DISCRETE.CAP(CHIPS)':
 'A': CDS_PINID='A';
NODE_NAME     R8E39 1
 '@BASEBOARD_FAB2_LIB.BASEBOARD_FAB2(SCH_1):PAGE241_I54@MSTR_DISCRETE.RES(CHIPS)':
 'A': CDS_PINID='A';
NODE_NAME     EU7E2 8
 '@BASEBOARD_FAB2_LIB.BASEBOARD_FAB2(SCH_1):PAGE241_I83@MSTR_VREG.TPS54821(CHIPS)':
 'COMP': CDS_PINID='COMP';
NET_NAME
'VR_P5V_STBY_EN'
 '@BASEBOARD_FAB2_LIB.BASEBOARD_FAB2(SCH_1):VR_P5V_STBY_EN':
 C_SIGNAL='@baseboard_fab2_lib.baseboard_fab2(sch_1):vr_p5v_stby_en';
NODE_NAME     EU7E2 10
 '@BASEBOARD_FAB2_LIB.BASEBOARD_FAB2(SCH_1):PAGE241_I83@MSTR_VREG.TPS54821(CHIPS)':
 'EN': CDS_PINID='EN';
NODE_NAME     R8E33 2
 '@BASEBOARD_FAB2_LIB.BASEBOARD_FAB2(SCH_1):PAGE241_I91@MSTR_DISCRETE.RES(CHIPS)':
 'B': CDS_PINID='B';
NET_NAME
'VR_P5V_STBY_PHASE'
 '@BASEBOARD_FAB2_LIB.BASEBOARD_FAB2(SCH_1):VR_P5V_STBY_PHASE':
 C_SIGNAL='@baseboard_fab2_lib.baseboard_fab2(sch_1):vr_p5v_stby_phase';
NODE_NAME     C8E6 2
 '@BASEBOARD_FAB2_LIB.BASEBOARD_FAB2(SCH_1):PAGE241_I12@MSTR_DISCRETE.CAP(CHIPS)':
 'B': CDS_PINID='B';
NODE_NAME     EU7E2 11
 '@BASEBOARD_FAB2_LIB.BASEBOARD_FAB2(SCH_1):PAGE241_I83@MSTR_VREG.TPS54821(CHIPS)':
 'PH'<0>: CDS_PINID='PH(0)';
NODE_NAME     EU7E2 12
 '@BASEBOARD_FAB2_LIB.BASEBOARD_FAB2(SCH_1):PAGE241_I83@MSTR_VREG.TPS54821(CHIPS)':
 'PH'<1>: CDS_PINID='PH(1)';
NODE_NAME     L8E1 1
 '@BASEBOARD_FAB2_LIB.BASEBOARD_FAB2(SCH_1):PAGE241_I90@MSTR_DISCRETE.INDUCTOR(CHIPS)':
 'INA': CDS_PINID='INA';
NET_NAME
'VR_P5V_STBY_RC_COMP'
 '@BASEBOARD_FAB2_LIB.BASEBOARD_FAB2(SCH_1):VR_P5V_STBY_RC_COMP':
 C_SIGNAL='@baseboard_fab2_lib.baseboard_fab2(sch_1):vr_p5v_stby_rc_comp';
NODE_NAME     R8E39 2
 '@BASEBOARD_FAB2_LIB.BASEBOARD_FAB2(SCH_1):PAGE241_I54@MSTR_DISCRETE.RES(CHIPS)':
 'B': CDS_PINID='B';
NODE_NAME     C8F1 1
 '@BASEBOARD_FAB2_LIB.BASEBOARD_FAB2(SCH_1):PAGE241_I57@MSTR_DISCRETE.CAP(CHIPS)':
 'A': CDS_PINID='A';
NET_NAME
'VR_P5V_STBY_RT'
 '@BASEBOARD_FAB2_LIB.BASEBOARD_FAB2(SCH_1):VR_P5V_STBY_RT':
 C_SIGNAL='@baseboard_fab2_lib.baseboard_fab2(sch_1):vr_p5v_stby_rt';
NODE_NAME     R7E14 1
 '@BASEBOARD_FAB2_LIB.BASEBOARD_FAB2(SCH_1):PAGE241_I18@MSTR_DISCRETE.RES(CHIPS)':
 'A': CDS_PINID='A';
NODE_NAME     EU7E2 1
 '@BASEBOARD_FAB2_LIB.BASEBOARD_FAB2(SCH_1):PAGE241_I83@MSTR_VREG.TPS54821(CHIPS)':
 'RT_CLK': CDS_PINID='RT_CLK';
NET_NAME
'VR_P5V_STBY_SS'
 '@BASEBOARD_FAB2_LIB.BASEBOARD_FAB2(SCH_1):VR_P5V_STBY_SS':
 C_SIGNAL='@baseboard_fab2_lib.baseboard_fab2(sch_1):vr_p5v_stby_ss';
NODE_NAME     C8E15 1
 '@BASEBOARD_FAB2_LIB.BASEBOARD_FAB2(SCH_1):PAGE241_I63@MSTR_DISCRETE.CAP(CHIPS)':
 'A': CDS_PINID='A';
NODE_NAME     EU7E2 9
 '@BASEBOARD_FAB2_LIB.BASEBOARD_FAB2(SCH_1):PAGE241_I83@MSTR_VREG.TPS54821(CHIPS)':
 'SS_TR': CDS_PINID='SS_TR';
NET_NAME
'VR_P5V_STBY_VIN'
 '@BASEBOARD_FAB2_LIB.BASEBOARD_FAB2(SCH_1):VR_P5V_STBY_VIN':
 C_SIGNAL='@baseboard_fab2_lib.baseboard_fab2(sch_1):vr_p5v_stby_vin';
NODE_NAME     C7E14 1
 '@BASEBOARD_FAB2_LIB.BASEBOARD_FAB2(SCH_1):PAGE241_I30@MSTR_DISCRETE.CAP(CHIPS)':
 'A': CDS_PINID='A';
NODE_NAME     R7E17 2
 '@BASEBOARD_FAB2_LIB.BASEBOARD_FAB2(SCH_1):PAGE241_I37@MSTR_DISCRETE.RES(CHIPS)':
 'B': CDS_PINID='B';
NODE_NAME     EU7E2 6
 '@BASEBOARD_FAB2_LIB.BASEBOARD_FAB2(SCH_1):PAGE241_I83@MSTR_VREG.TPS54821(CHIPS)':
 'VIN': CDS_PINID='VIN';
NET_NAME
'VR_P5V_STBY_VSENSE'
 '@BASEBOARD_FAB2_LIB.BASEBOARD_FAB2(SCH_1):VR_P5V_STBY_VSENSE':
 C_SIGNAL='@baseboard_fab2_lib.baseboard_fab2(sch_1):vr_p5v_stby_vsense';
NODE_NAME     R7F1 2
 '@BASEBOARD_FAB2_LIB.BASEBOARD_FAB2(SCH_1):PAGE241_I50@MSTR_DISCRETE.RES(CHIPS)':
 'B': CDS_PINID='B';
NODE_NAME     R7E16 1
 '@BASEBOARD_FAB2_LIB.BASEBOARD_FAB2(SCH_1):PAGE241_I51@MSTR_DISCRETE.RES(CHIPS)':
 'A': CDS_PINID='A';
NODE_NAME     EU7E2 7
 '@BASEBOARD_FAB2_LIB.BASEBOARD_FAB2(SCH_1):PAGE241_I83@MSTR_VREG.TPS54821(CHIPS)':
 'VSENSE': CDS_PINID='VSENSE';
NET_NAME
'VR_P5V_STBY_VSENSE_R'
 '@BASEBOARD_FAB2_LIB.BASEBOARD_FAB2(SCH_1):VR_P5V_STBY_VSENSE_R':
 C_SIGNAL='@baseboard_fab2_lib.baseboard_fab2(sch_1):vr_p5v_stby_vsense_r';
NODE_NAME     R7F1 1
 '@BASEBOARD_FAB2_LIB.BASEBOARD_FAB2(SCH_1):PAGE241_I50@MSTR_DISCRETE.RES(CHIPS)':
 'A': CDS_PINID='A';
NODE_NAME     R8E37 1
 '@BASEBOARD_FAB2_LIB.BASEBOARD_FAB2(SCH_1):PAGE241_I78@MSTR_DISCRETE.RES(CHIPS)':
 'A': CDS_PINID='A';
NET_NAME
'VR_PVCCIN_CPU0_AIREF1'
 '@BASEBOARD_FAB2_LIB.BASEBOARD_FAB2(SCH_1):VR_PVCCIN_CPU0_AIREF1':
 C_SIGNAL='@baseboard_fab2_lib.baseboard_fab2(sch_1):vr_pvccin_cpu0_airef1';
NODE_NAME     EU4D4 23
 '@BASEBOARD_FAB2_LIB.BASEBOARD_FAB2(SCH_1):PAGE201_I155@MSTR_CONTROLLER.PXE1610B(CHIPS)':
 'AIREF1': CDS_PINID='AIREF1';
NODE_NAME     EU4E1 39
 '@BASEBOARD_FAB2_LIB.BASEBOARD_FAB2(SCH_1):PAGE202_I63@MSTR_DISCRETE.IR354XX(CHIPS)':
 'REFIN': CDS_PINID='REFIN';
NODE_NAME     CT1 1
 '@BASEBOARD_FAB2_LIB.BASEBOARD_FAB2(SCH_1):PAGE202_I70@DEV_DISCRETE.CAP_A(CHIPS)':
 'A': CDS_PINID='A';
NODE_NAME     CF1 1
 '@BASEBOARD_FAB2_LIB.BASEBOARD_FAB2(SCH_1):PAGE201_I168@W_HDL.SC22P50V2JN-4GP(CHIPS)':
 '1': CDS_PINID='\1\';
NODE_NAME     RF1 1
 '@BASEBOARD_FAB2_LIB.BASEBOARD_FAB2(SCH_1):PAGE201_I182@MSTR_DISCRETE.RES(CHIPS)':
 'A': CDS_PINID='A';
NET_NAME
'VR_PVCCIN_CPU0_AIREF2'
 '@BASEBOARD_FAB2_LIB.BASEBOARD_FAB2(SCH_1):VR_PVCCIN_CPU0_AIREF2':
 C_SIGNAL='@baseboard_fab2_lib.baseboard_fab2(sch_1):vr_pvccin_cpu0_airef2';
NODE_NAME     EU4D4 25
 '@BASEBOARD_FAB2_LIB.BASEBOARD_FAB2(SCH_1):PAGE201_I155@MSTR_CONTROLLER.PXE1610B(CHIPS)':
 'AIREF2': CDS_PINID='AIREF2';
NODE_NAME     EU4D6 39
 '@BASEBOARD_FAB2_LIB.BASEBOARD_FAB2(SCH_1):PAGE202_I64@MSTR_DISCRETE.IR354XX(CHIPS)':
 'REFIN': CDS_PINID='REFIN';
NODE_NAME     CT6 1
 '@BASEBOARD_FAB2_LIB.BASEBOARD_FAB2(SCH_1):PAGE202_I81@DEV_DISCRETE.CAP_A(CHIPS)':
 'A': CDS_PINID='A';
NODE_NAME     CF2 1
 '@BASEBOARD_FAB2_LIB.BASEBOARD_FAB2(SCH_1):PAGE201_I169@W_HDL.SC22P50V2JN-4GP(CHIPS)':
 '1': CDS_PINID='\1\';
NODE_NAME     RF2 1
 '@BASEBOARD_FAB2_LIB.BASEBOARD_FAB2(SCH_1):PAGE201_I183@MSTR_DISCRETE.RES(CHIPS)':
 'A': CDS_PINID='A';
NET_NAME
'VR_PVCCIN_CPU0_AIREF3'
 '@BASEBOARD_FAB2_LIB.BASEBOARD_FAB2(SCH_1):VR_PVCCIN_CPU0_AIREF3':
 C_SIGNAL='@baseboard_fab2_lib.baseboard_fab2(sch_1):vr_pvccin_cpu0_airef3';
NODE_NAME     EU4D4 27
 '@BASEBOARD_FAB2_LIB.BASEBOARD_FAB2(SCH_1):PAGE201_I155@MSTR_CONTROLLER.PXE1610B(CHIPS)':
 'AIREF3': CDS_PINID='AIREF3';
NODE_NAME     EU4D3 39
 '@BASEBOARD_FAB2_LIB.BASEBOARD_FAB2(SCH_1):PAGE203_I70@MSTR_DISCRETE.IR354XX(CHIPS)':
 'REFIN': CDS_PINID='REFIN';
NODE_NAME     CT39 1
 '@BASEBOARD_FAB2_LIB.BASEBOARD_FAB2(SCH_1):PAGE203_I96@DEV_DISCRETE.CAP_A(CHIPS)':
 'A': CDS_PINID='A';
NODE_NAME     CF3 1
 '@BASEBOARD_FAB2_LIB.BASEBOARD_FAB2(SCH_1):PAGE201_I170@W_HDL.SC22P50V2JN-4GP(CHIPS)':
 '1': CDS_PINID='\1\';
NODE_NAME     RF3 1
 '@BASEBOARD_FAB2_LIB.BASEBOARD_FAB2(SCH_1):PAGE201_I184@MSTR_DISCRETE.RES(CHIPS)':
 'A': CDS_PINID='A';
NET_NAME
'VR_PVCCIN_CPU0_AIREF4'
 '@BASEBOARD_FAB2_LIB.BASEBOARD_FAB2(SCH_1):VR_PVCCIN_CPU0_AIREF4':
 C_SIGNAL='@baseboard_fab2_lib.baseboard_fab2(sch_1):vr_pvccin_cpu0_airef4';
NODE_NAME     EU4D4 29
 '@BASEBOARD_FAB2_LIB.BASEBOARD_FAB2(SCH_1):PAGE201_I155@MSTR_CONTROLLER.PXE1610B(CHIPS)':
 'AIREF4': CDS_PINID='AIREF4';
NODE_NAME     EU4D1 39
 '@BASEBOARD_FAB2_LIB.BASEBOARD_FAB2(SCH_1):PAGE203_I71@MSTR_DISCRETE.IR354XX(CHIPS)':
 'REFIN': CDS_PINID='REFIN';
NODE_NAME     CT40 1
 '@BASEBOARD_FAB2_LIB.BASEBOARD_FAB2(SCH_1):PAGE203_I93@DEV_DISCRETE.CAP_A(CHIPS)':
 'A': CDS_PINID='A';
NODE_NAME     CF4 1
 '@BASEBOARD_FAB2_LIB.BASEBOARD_FAB2(SCH_1):PAGE201_I171@W_HDL.SC22P50V2JN-4GP(CHIPS)':
 '1': CDS_PINID='\1\';
NODE_NAME     RF4 1
 '@BASEBOARD_FAB2_LIB.BASEBOARD_FAB2(SCH_1):PAGE201_I185@MSTR_DISCRETE.RES(CHIPS)':
 'A': CDS_PINID='A';
NET_NAME
'VR_PVCCIN_CPU0_AIREF5'
 '@BASEBOARD_FAB2_LIB.BASEBOARD_FAB2(SCH_1):VR_PVCCIN_CPU0_AIREF5':
 C_SIGNAL='@baseboard_fab2_lib.baseboard_fab2(sch_1):vr_pvccin_cpu0_airef5';
NODE_NAME     EU4D4 31
 '@BASEBOARD_FAB2_LIB.BASEBOARD_FAB2(SCH_1):PAGE201_I155@MSTR_CONTROLLER.PXE1610B(CHIPS)':
 'AIREF5': CDS_PINID='AIREF5';
NODE_NAME     EU4C2 39
 '@BASEBOARD_FAB2_LIB.BASEBOARD_FAB2(SCH_1):PAGE204_I71@MSTR_DISCRETE.IR354XX(CHIPS)':
 'REFIN': CDS_PINID='REFIN';
NODE_NAME     CT36 1
 '@BASEBOARD_FAB2_LIB.BASEBOARD_FAB2(SCH_1):PAGE204_I85@DEV_DISCRETE.CAP_A(CHIPS)':
 'A': CDS_PINID='A';
NODE_NAME     CF5 1
 '@BASEBOARD_FAB2_LIB.BASEBOARD_FAB2(SCH_1):PAGE201_I172@W_HDL.SC22P50V2JN-4GP(CHIPS)':
 '1': CDS_PINID='\1\';
NODE_NAME     RF5 1
 '@BASEBOARD_FAB2_LIB.BASEBOARD_FAB2(SCH_1):PAGE201_I186@MSTR_DISCRETE.RES(CHIPS)':
 'A': CDS_PINID='A';
NET_NAME
'VR_PVCCIN_CPU0_AVINSEN'
 '@BASEBOARD_FAB2_LIB.BASEBOARD_FAB2(SCH_1):VR_PVCCIN_CPU0_AVINSEN':
 C_SIGNAL='@baseboard_fab2_lib.baseboard_fab2(sch_1):vr_pvccin_cpu0_avinsen';
NODE_NAME     R4D27 2
 '@BASEBOARD_FAB2_LIB.BASEBOARD_FAB2(SCH_1):PAGE201_I54@MSTR_DISCRETE.RES(CHIPS)':
 'B': CDS_PINID='B';
NODE_NAME     R4D32 1
 '@BASEBOARD_FAB2_LIB.BASEBOARD_FAB2(SCH_1):PAGE201_I55@MSTR_DISCRETE.RES(CHIPS)':
 'A': CDS_PINID='A';
NODE_NAME     EU4D4 45
 '@BASEBOARD_FAB2_LIB.BASEBOARD_FAB2(SCH_1):PAGE201_I155@MSTR_CONTROLLER.PXE1610B(CHIPS)':
 'VINSEN': CDS_PINID='VINSEN';
NODE_NAME     C4D20 1
 '@BASEBOARD_FAB2_LIB.BASEBOARD_FAB2(SCH_1):PAGE201_I192@DEV_DISCRETE.CAP_A(CHIPS)':
 'A': CDS_PINID='A';
NET_NAME
'VR_PVCCIN_CPU0_PH1_BOOT'
 '@BASEBOARD_FAB2_LIB.BASEBOARD_FAB2(SCH_1):VR_PVCCIN_CPU0_PH1_BOOT':
 C_SIGNAL='@baseboard_fab2_lib.baseboard_fab2(sch_1):vr_pvccin_cpu0_ph1_boot';
NODE_NAME     C4E17 1
 '@BASEBOARD_FAB2_LIB.BASEBOARD_FAB2(SCH_1):PAGE202_I22@MSTR_DISCRETE.CAP(CHIPS)':
 'A': CDS_PINID='A';
NODE_NAME     RT1 1
 '@BASEBOARD_FAB2_LIB.BASEBOARD_FAB2(SCH_1):PAGE202_I101@MSTR_DISCRETE.RES(CHIPS)':
 'A': CDS_PINID='A';
NET_NAME
'VR_PVCCIN_CPU0_PH1_BOOT_R'
 '@BASEBOARD_FAB2_LIB.BASEBOARD_FAB2(SCH_1):VR_PVCCIN_CPU0_PH1_BOOT_R':
 C_SIGNAL='@baseboard_fab2_lib.baseboard_fab2(sch_1):vr_pvccin_cpu0_ph1_boot_r';
NODE_NAME     EU4E1 33
 '@BASEBOARD_FAB2_LIB.BASEBOARD_FAB2(SCH_1):PAGE202_I63@MSTR_DISCRETE.IR354XX(CHIPS)':
 'BOOST': CDS_PINID='BOOST';
NODE_NAME     RT1 2
 '@BASEBOARD_FAB2_LIB.BASEBOARD_FAB2(SCH_1):PAGE202_I101@MSTR_DISCRETE.RES(CHIPS)':
 'B': CDS_PINID='B';
NET_NAME
'VR_PVCCIN_CPU0_PH1_OCSET'
 '@BASEBOARD_FAB2_LIB.BASEBOARD_FAB2(SCH_1):VR_PVCCIN_CPU0_PH1_OCSET':
 C_SIGNAL='@baseboard_fab2_lib.baseboard_fab2(sch_1):vr_pvccin_cpu0_ph1_ocset';
NODE_NAME     EU4E1 37
 '@BASEBOARD_FAB2_LIB.BASEBOARD_FAB2(SCH_1):PAGE202_I63@MSTR_DISCRETE.IR354XX(CHIPS)':
 'OCSET': CDS_PINID='OCSET';
NODE_NAME     R4E22 1
 '@BASEBOARD_FAB2_LIB.BASEBOARD_FAB2(SCH_1):PAGE202_I65@MSTR_DISCRETE.RES(CHIPS)':
 'A': CDS_PINID='A';
NET_NAME
'VR_PVCCIN_CPU0_PH1_PHASE'
 '@BASEBOARD_FAB2_LIB.BASEBOARD_FAB2(SCH_1):VR_PVCCIN_CPU0_PH1_PHASE':
 C_SIGNAL='@baseboard_fab2_lib.baseboard_fab2(sch_1):vr_pvccin_cpu0_ph1_phase';
NODE_NAME     C4E17 2
 '@BASEBOARD_FAB2_LIB.BASEBOARD_FAB2(SCH_1):PAGE202_I22@MSTR_DISCRETE.CAP(CHIPS)':
 'B': CDS_PINID='B';
NODE_NAME     EU4E1 32
 '@BASEBOARD_FAB2_LIB.BASEBOARD_FAB2(SCH_1):PAGE202_I63@MSTR_DISCRETE.IR354XX(CHIPS)':
 'PHASE': CDS_PINID='PHASE';
NET_NAME
'VR_PVCCIN_CPU0_PH1_VCIN'
 '@BASEBOARD_FAB2_LIB.BASEBOARD_FAB2(SCH_1):VR_PVCCIN_CPU0_PH1_VCIN':
 C_SIGNAL='@baseboard_fab2_lib.baseboard_fab2(sch_1):vr_pvccin_cpu0_ph1_vcin';
NODE_NAME     C4E10 1
 '@BASEBOARD_FAB2_LIB.BASEBOARD_FAB2(SCH_1):PAGE202_I34@MSTR_DISCRETE.CAP(CHIPS)':
 'A': CDS_PINID='A';
NODE_NAME     EU4E1 3
 '@BASEBOARD_FAB2_LIB.BASEBOARD_FAB2(SCH_1):PAGE202_I63@MSTR_DISCRETE.IR354XX(CHIPS)':
 'VCC': CDS_PINID='VCC';
NODE_NAME     R6R2 1
 '@BASEBOARD_FAB2_LIB.BASEBOARD_FAB2(SCH_1):PAGE202_I107@MSTR_DISCRETE.RES(CHIPS)':
 'A': CDS_PINID='A';
NET_NAME
'VR_PVCCIN_CPU0_PH2_BOOT'
 '@BASEBOARD_FAB2_LIB.BASEBOARD_FAB2(SCH_1):VR_PVCCIN_CPU0_PH2_BOOT':
 C_SIGNAL='@baseboard_fab2_lib.baseboard_fab2(sch_1):vr_pvccin_cpu0_ph2_boot';
NODE_NAME     C4D50 1
 '@BASEBOARD_FAB2_LIB.BASEBOARD_FAB2(SCH_1):PAGE202_I32@MSTR_DISCRETE.CAP(CHIPS)':
 'A': CDS_PINID='A';
NODE_NAME     RT3 1
 '@BASEBOARD_FAB2_LIB.BASEBOARD_FAB2(SCH_1):PAGE202_I102@MSTR_DISCRETE.RES(CHIPS)':
 'A': CDS_PINID='A';
NET_NAME
'VR_PVCCIN_CPU0_PH2_BOOT_R'
 '@BASEBOARD_FAB2_LIB.BASEBOARD_FAB2(SCH_1):VR_PVCCIN_CPU0_PH2_BOOT_R':
 C_SIGNAL='@baseboard_fab2_lib.baseboard_fab2(sch_1):vr_pvccin_cpu0_ph2_boot_r';
NODE_NAME     EU4D6 33
 '@BASEBOARD_FAB2_LIB.BASEBOARD_FAB2(SCH_1):PAGE202_I64@MSTR_DISCRETE.IR354XX(CHIPS)':
 'BOOST': CDS_PINID='BOOST';
NODE_NAME     RT3 2
 '@BASEBOARD_FAB2_LIB.BASEBOARD_FAB2(SCH_1):PAGE202_I102@MSTR_DISCRETE.RES(CHIPS)':
 'B': CDS_PINID='B';
NET_NAME
'VR_PVCCIN_CPU0_PH2_OCSET'
 '@BASEBOARD_FAB2_LIB.BASEBOARD_FAB2(SCH_1):VR_PVCCIN_CPU0_PH2_OCSET':
 C_SIGNAL='@baseboard_fab2_lib.baseboard_fab2(sch_1):vr_pvccin_cpu0_ph2_ocset';
NODE_NAME     EU4D6 37
 '@BASEBOARD_FAB2_LIB.BASEBOARD_FAB2(SCH_1):PAGE202_I64@MSTR_DISCRETE.IR354XX(CHIPS)':
 'OCSET': CDS_PINID='OCSET';
NODE_NAME     R4E19 1
 '@BASEBOARD_FAB2_LIB.BASEBOARD_FAB2(SCH_1):PAGE202_I67@MSTR_DISCRETE.RES(CHIPS)':
 'A': CDS_PINID='A';
NET_NAME
'VR_PVCCIN_CPU0_PH2_PHASE'
 '@BASEBOARD_FAB2_LIB.BASEBOARD_FAB2(SCH_1):VR_PVCCIN_CPU0_PH2_PHASE':
 C_SIGNAL='@baseboard_fab2_lib.baseboard_fab2(sch_1):vr_pvccin_cpu0_ph2_phase';
NODE_NAME     C4D50 2
 '@BASEBOARD_FAB2_LIB.BASEBOARD_FAB2(SCH_1):PAGE202_I32@MSTR_DISCRETE.CAP(CHIPS)':
 'B': CDS_PINID='B';
NODE_NAME     EU4D6 32
 '@BASEBOARD_FAB2_LIB.BASEBOARD_FAB2(SCH_1):PAGE202_I64@MSTR_DISCRETE.IR354XX(CHIPS)':
 'PHASE': CDS_PINID='PHASE';
NET_NAME
'VR_PVCCIN_CPU0_PH2_VCIN'
 '@BASEBOARD_FAB2_LIB.BASEBOARD_FAB2(SCH_1):VR_PVCCIN_CPU0_PH2_VCIN':
 C_SIGNAL='@baseboard_fab2_lib.baseboard_fab2(sch_1):vr_pvccin_cpu0_ph2_vcin';
NODE_NAME     C4E26 1
 '@BASEBOARD_FAB2_LIB.BASEBOARD_FAB2(SCH_1):PAGE202_I45@MSTR_DISCRETE.CAP(CHIPS)':
 'A': CDS_PINID='A';
NODE_NAME     EU4D6 3
 '@BASEBOARD_FAB2_LIB.BASEBOARD_FAB2(SCH_1):PAGE202_I64@MSTR_DISCRETE.IR354XX(CHIPS)':
 'VCC': CDS_PINID='VCC';
NODE_NAME     R6R6 1
 '@BASEBOARD_FAB2_LIB.BASEBOARD_FAB2(SCH_1):PAGE202_I108@MSTR_DISCRETE.RES(CHIPS)':
 'A': CDS_PINID='A';
NET_NAME
'VR_PVCCIN_CPU0_PH3_BOOT'
 '@BASEBOARD_FAB2_LIB.BASEBOARD_FAB2(SCH_1):VR_PVCCIN_CPU0_PH3_BOOT':
 C_SIGNAL='@baseboard_fab2_lib.baseboard_fab2(sch_1):vr_pvccin_cpu0_ph3_boot';
NODE_NAME     C4D28 1
 '@BASEBOARD_FAB2_LIB.BASEBOARD_FAB2(SCH_1):PAGE203_I42@MSTR_DISCRETE.CAP(CHIPS)':
 'A': CDS_PINID='A';
NODE_NAME     RT25 1
 '@BASEBOARD_FAB2_LIB.BASEBOARD_FAB2(SCH_1):PAGE203_I122@MSTR_DISCRETE.RES(CHIPS)':
 'A': CDS_PINID='A';
NET_NAME
'VR_PVCCIN_CPU0_PH3_BOOT_R'
 '@BASEBOARD_FAB2_LIB.BASEBOARD_FAB2(SCH_1):VR_PVCCIN_CPU0_PH3_BOOT_R':
 C_SIGNAL='@baseboard_fab2_lib.baseboard_fab2(sch_1):vr_pvccin_cpu0_ph3_boot_r';
NODE_NAME     EU4D3 33
 '@BASEBOARD_FAB2_LIB.BASEBOARD_FAB2(SCH_1):PAGE203_I70@MSTR_DISCRETE.IR354XX(CHIPS)':
 'BOOST': CDS_PINID='BOOST';
NODE_NAME     RT25 2
 '@BASEBOARD_FAB2_LIB.BASEBOARD_FAB2(SCH_1):PAGE203_I122@MSTR_DISCRETE.RES(CHIPS)':
 'B': CDS_PINID='B';
NET_NAME
'VR_PVCCIN_CPU0_PH3_OCSET'
 '@BASEBOARD_FAB2_LIB.BASEBOARD_FAB2(SCH_1):VR_PVCCIN_CPU0_PH3_OCSET':
 C_SIGNAL='@baseboard_fab2_lib.baseboard_fab2(sch_1):vr_pvccin_cpu0_ph3_ocset';
NODE_NAME     EU4D3 37
 '@BASEBOARD_FAB2_LIB.BASEBOARD_FAB2(SCH_1):PAGE203_I70@MSTR_DISCRETE.IR354XX(CHIPS)':
 'OCSET': CDS_PINID='OCSET';
NODE_NAME     R4D72 1
 '@BASEBOARD_FAB2_LIB.BASEBOARD_FAB2(SCH_1):PAGE203_I89@MSTR_DISCRETE.RES(CHIPS)':
 'A': CDS_PINID='A';
NET_NAME
'VR_PVCCIN_CPU0_PH3_PHASE'
 '@BASEBOARD_FAB2_LIB.BASEBOARD_FAB2(SCH_1):VR_PVCCIN_CPU0_PH3_PHASE':
 C_SIGNAL='@baseboard_fab2_lib.baseboard_fab2(sch_1):vr_pvccin_cpu0_ph3_phase';
NODE_NAME     C4D28 2
 '@BASEBOARD_FAB2_LIB.BASEBOARD_FAB2(SCH_1):PAGE203_I42@MSTR_DISCRETE.CAP(CHIPS)':
 'B': CDS_PINID='B';
NODE_NAME     EU4D3 32
 '@BASEBOARD_FAB2_LIB.BASEBOARD_FAB2(SCH_1):PAGE203_I70@MSTR_DISCRETE.IR354XX(CHIPS)':
 'PHASE': CDS_PINID='PHASE';
NET_NAME
'VR_PVCCIN_CPU0_PH3_VCIN'
 '@BASEBOARD_FAB2_LIB.BASEBOARD_FAB2(SCH_1):VR_PVCCIN_CPU0_PH3_VCIN':
 C_SIGNAL='@baseboard_fab2_lib.baseboard_fab2(sch_1):vr_pvccin_cpu0_ph3_vcin';
NODE_NAME     C4D16 1
 '@BASEBOARD_FAB2_LIB.BASEBOARD_FAB2(SCH_1):PAGE203_I45@MSTR_DISCRETE.CAP(CHIPS)':
 'A': CDS_PINID='A';
NODE_NAME     EU4D3 3
 '@BASEBOARD_FAB2_LIB.BASEBOARD_FAB2(SCH_1):PAGE203_I70@MSTR_DISCRETE.IR354XX(CHIPS)':
 'VCC': CDS_PINID='VCC';
NODE_NAME     R6P19 1
 '@BASEBOARD_FAB2_LIB.BASEBOARD_FAB2(SCH_1):PAGE203_I128@MSTR_DISCRETE.RES(CHIPS)':
 'A': CDS_PINID='A';
NET_NAME
'VR_PVCCIN_CPU0_PH4_BOOT'
 '@BASEBOARD_FAB2_LIB.BASEBOARD_FAB2(SCH_1):VR_PVCCIN_CPU0_PH4_BOOT':
 C_SIGNAL='@baseboard_fab2_lib.baseboard_fab2(sch_1):vr_pvccin_cpu0_ph4_boot';
NODE_NAME     C4D9 1
 '@BASEBOARD_FAB2_LIB.BASEBOARD_FAB2(SCH_1):PAGE203_I3@MSTR_DISCRETE.CAP(CHIPS)':
 'A': CDS_PINID='A';
NODE_NAME     RT28 1
 '@BASEBOARD_FAB2_LIB.BASEBOARD_FAB2(SCH_1):PAGE203_I123@MSTR_DISCRETE.RES(CHIPS)':
 'A': CDS_PINID='A';
NET_NAME
'VR_PVCCIN_CPU0_PH4_BOOT_R'
 '@BASEBOARD_FAB2_LIB.BASEBOARD_FAB2(SCH_1):VR_PVCCIN_CPU0_PH4_BOOT_R':
 C_SIGNAL='@baseboard_fab2_lib.baseboard_fab2(sch_1):vr_pvccin_cpu0_ph4_boot_r';
NODE_NAME     EU4D1 33
 '@BASEBOARD_FAB2_LIB.BASEBOARD_FAB2(SCH_1):PAGE203_I71@MSTR_DISCRETE.IR354XX(CHIPS)':
 'BOOST': CDS_PINID='BOOST';
NODE_NAME     RT28 2
 '@BASEBOARD_FAB2_LIB.BASEBOARD_FAB2(SCH_1):PAGE203_I123@MSTR_DISCRETE.RES(CHIPS)':
 'B': CDS_PINID='B';
NET_NAME
'VR_PVCCIN_CPU0_PH4_OCSET'
 '@BASEBOARD_FAB2_LIB.BASEBOARD_FAB2(SCH_1):VR_PVCCIN_CPU0_PH4_OCSET':
 C_SIGNAL='@baseboard_fab2_lib.baseboard_fab2(sch_1):vr_pvccin_cpu0_ph4_ocset';
NODE_NAME     EU4D1 37
 '@BASEBOARD_FAB2_LIB.BASEBOARD_FAB2(SCH_1):PAGE203_I71@MSTR_DISCRETE.IR354XX(CHIPS)':
 'OCSET': CDS_PINID='OCSET';
NODE_NAME     R4D71 1
 '@BASEBOARD_FAB2_LIB.BASEBOARD_FAB2(SCH_1):PAGE203_I91@MSTR_DISCRETE.RES(CHIPS)':
 'A': CDS_PINID='A';
NET_NAME
'VR_PVCCIN_CPU0_PH4_PHASE'
 '@BASEBOARD_FAB2_LIB.BASEBOARD_FAB2(SCH_1):VR_PVCCIN_CPU0_PH4_PHASE':
 C_SIGNAL='@baseboard_fab2_lib.baseboard_fab2(sch_1):vr_pvccin_cpu0_ph4_phase';
NODE_NAME     C4D9 2
 '@BASEBOARD_FAB2_LIB.BASEBOARD_FAB2(SCH_1):PAGE203_I3@MSTR_DISCRETE.CAP(CHIPS)':
 'B': CDS_PINID='B';
NODE_NAME     EU4D1 32
 '@BASEBOARD_FAB2_LIB.BASEBOARD_FAB2(SCH_1):PAGE203_I71@MSTR_DISCRETE.IR354XX(CHIPS)':
 'PHASE': CDS_PINID='PHASE';
NET_NAME
'VR_PVCCIN_CPU0_PH4_VCIN'
 '@BASEBOARD_FAB2_LIB.BASEBOARD_FAB2(SCH_1):VR_PVCCIN_CPU0_PH4_VCIN':
 C_SIGNAL='@baseboard_fab2_lib.baseboard_fab2(sch_1):vr_pvccin_cpu0_ph4_vcin';
NODE_NAME     C4D7 1
 '@BASEBOARD_FAB2_LIB.BASEBOARD_FAB2(SCH_1):PAGE203_I51@MSTR_DISCRETE.CAP(CHIPS)':
 'A': CDS_PINID='A';
NODE_NAME     EU4D1 3
 '@BASEBOARD_FAB2_LIB.BASEBOARD_FAB2(SCH_1):PAGE203_I71@MSTR_DISCRETE.IR354XX(CHIPS)':
 'VCC': CDS_PINID='VCC';
NODE_NAME     R6P10 1
 '@BASEBOARD_FAB2_LIB.BASEBOARD_FAB2(SCH_1):PAGE203_I129@MSTR_DISCRETE.RES(CHIPS)':
 'A': CDS_PINID='A';
NET_NAME
'VR_PVCCIN_CPU0_PH5_BOOT'
 '@BASEBOARD_FAB2_LIB.BASEBOARD_FAB2(SCH_1):VR_PVCCIN_CPU0_PH5_BOOT':
 C_SIGNAL='@baseboard_fab2_lib.baseboard_fab2(sch_1):vr_pvccin_cpu0_ph5_boot';
NODE_NAME     C4C17 1
 '@BASEBOARD_FAB2_LIB.BASEBOARD_FAB2(SCH_1):PAGE204_I22@MSTR_DISCRETE.CAP(CHIPS)':
 'A': CDS_PINID='A';
NODE_NAME     RT23 1
 '@BASEBOARD_FAB2_LIB.BASEBOARD_FAB2(SCH_1):PAGE204_I99@MSTR_DISCRETE.RES(CHIPS)':
 'A': CDS_PINID='A';
NET_NAME
'VR_PVCCIN_CPU0_PH5_BOOT_R'
 '@BASEBOARD_FAB2_LIB.BASEBOARD_FAB2(SCH_1):VR_PVCCIN_CPU0_PH5_BOOT_R':
 C_SIGNAL='@baseboard_fab2_lib.baseboard_fab2(sch_1):vr_pvccin_cpu0_ph5_boot_r';
NODE_NAME     EU4C2 33
 '@BASEBOARD_FAB2_LIB.BASEBOARD_FAB2(SCH_1):PAGE204_I71@MSTR_DISCRETE.IR354XX(CHIPS)':
 'BOOST': CDS_PINID='BOOST';
NODE_NAME     RT23 2
 '@BASEBOARD_FAB2_LIB.BASEBOARD_FAB2(SCH_1):PAGE204_I99@MSTR_DISCRETE.RES(CHIPS)':
 'B': CDS_PINID='B';
NET_NAME
'VR_PVCCIN_CPU0_PH5_OCSET'
 '@BASEBOARD_FAB2_LIB.BASEBOARD_FAB2(SCH_1):VR_PVCCIN_CPU0_PH5_OCSET':
 C_SIGNAL='@baseboard_fab2_lib.baseboard_fab2(sch_1):vr_pvccin_cpu0_ph5_ocset';
NODE_NAME     EU4C2 37
 '@BASEBOARD_FAB2_LIB.BASEBOARD_FAB2(SCH_1):PAGE204_I71@MSTR_DISCRETE.IR354XX(CHIPS)':
 'OCSET': CDS_PINID='OCSET';
NODE_NAME     R4D68 1
 '@BASEBOARD_FAB2_LIB.BASEBOARD_FAB2(SCH_1):PAGE204_I83@MSTR_DISCRETE.RES(CHIPS)':
 'A': CDS_PINID='A';
NET_NAME
'VR_PVCCIN_CPU0_PH5_PHASE'
 '@BASEBOARD_FAB2_LIB.BASEBOARD_FAB2(SCH_1):VR_PVCCIN_CPU0_PH5_PHASE':
 C_SIGNAL='@baseboard_fab2_lib.baseboard_fab2(sch_1):vr_pvccin_cpu0_ph5_phase';
NODE_NAME     C4C17 2
 '@BASEBOARD_FAB2_LIB.BASEBOARD_FAB2(SCH_1):PAGE204_I22@MSTR_DISCRETE.CAP(CHIPS)':
 'B': CDS_PINID='B';
NODE_NAME     EU4C2 32
 '@BASEBOARD_FAB2_LIB.BASEBOARD_FAB2(SCH_1):PAGE204_I71@MSTR_DISCRETE.IR354XX(CHIPS)':
 'PHASE': CDS_PINID='PHASE';
NET_NAME
'VR_PVCCIN_CPU0_PH5_VCIN'
 '@BASEBOARD_FAB2_LIB.BASEBOARD_FAB2(SCH_1):VR_PVCCIN_CPU0_PH5_VCIN':
 C_SIGNAL='@baseboard_fab2_lib.baseboard_fab2(sch_1):vr_pvccin_cpu0_ph5_vcin';
NODE_NAME     C4D46 1
 '@BASEBOARD_FAB2_LIB.BASEBOARD_FAB2(SCH_1):PAGE204_I34@MSTR_DISCRETE.CAP(CHIPS)':
 'A': CDS_PINID='A';
NODE_NAME     EU4C2 3
 '@BASEBOARD_FAB2_LIB.BASEBOARD_FAB2(SCH_1):PAGE204_I71@MSTR_DISCRETE.IR354XX(CHIPS)':
 'VCC': CDS_PINID='VCC';
NODE_NAME     R6P47 1
 '@BASEBOARD_FAB2_LIB.BASEBOARD_FAB2(SCH_1):PAGE204_I103@MSTR_DISCRETE.RES(CHIPS)':
 'A': CDS_PINID='A';
NET_NAME
'VR_PVCCIN_CPU0_PHASE1'
 '@BASEBOARD_FAB2_LIB.BASEBOARD_FAB2(SCH_1):VR_PVCCIN_CPU0_PHASE1':
 C_SIGNAL='@baseboard_fab2_lib.baseboard_fab2(sch_1):vr_pvccin_cpu0_phase1';
NODE_NAME     EU4E1 10
 '@BASEBOARD_FAB2_LIB.BASEBOARD_FAB2(SCH_1):PAGE202_I63@MSTR_DISCRETE.IR354XX(CHIPS)':
 'SW': CDS_PINID='SW';
NODE_NAME     CT3 1
 '@BASEBOARD_FAB2_LIB.BASEBOARD_FAB2(SCH_1):PAGE202_I97@MSTR_DISCRETE.CAP(CHIPS)':
 'A': CDS_PINID='A';
NODE_NAME     L4E1 1
 '@BASEBOARD_FAB2_LIB.BASEBOARD_FAB2(SCH_1):PAGE202_I109@W_HDL.IND-120NH-30-GP(CHIPS)':
 'S': CDS_PINID='S';
NET_NAME
'VR_PVCCIN_CPU0_PHASE1_RC'
 '@BASEBOARD_FAB2_LIB.BASEBOARD_FAB2(SCH_1):VR_PVCCIN_CPU0_PHASE1_RC':
 C_SIGNAL='@baseboard_fab2_lib.baseboard_fab2(sch_1):vr_pvccin_cpu0_phase1_rc';
NODE_NAME     CT3 2
 '@BASEBOARD_FAB2_LIB.BASEBOARD_FAB2(SCH_1):PAGE202_I97@MSTR_DISCRETE.CAP(CHIPS)':
 'B': CDS_PINID='B';
NODE_NAME     RT2 1
 '@BASEBOARD_FAB2_LIB.BASEBOARD_FAB2(SCH_1):PAGE202_I114@W_HDL.1R3F-GP(CHIPS)':
 '1': CDS_PINID='\1\';
NET_NAME
'VR_PVCCIN_CPU0_PHASE2'
 '@BASEBOARD_FAB2_LIB.BASEBOARD_FAB2(SCH_1):VR_PVCCIN_CPU0_PHASE2':
 C_SIGNAL='@baseboard_fab2_lib.baseboard_fab2(sch_1):vr_pvccin_cpu0_phase2';
NODE_NAME     EU4D6 10
 '@BASEBOARD_FAB2_LIB.BASEBOARD_FAB2(SCH_1):PAGE202_I64@MSTR_DISCRETE.IR354XX(CHIPS)':
 'SW': CDS_PINID='SW';
NODE_NAME     CT5 1
 '@BASEBOARD_FAB2_LIB.BASEBOARD_FAB2(SCH_1):PAGE202_I98@MSTR_DISCRETE.CAP(CHIPS)':
 'A': CDS_PINID='A';
NODE_NAME     L4D3 1
 '@BASEBOARD_FAB2_LIB.BASEBOARD_FAB2(SCH_1):PAGE202_I110@W_HDL.IND-120NH-30-GP(CHIPS)':
 'S': CDS_PINID='S';
NET_NAME
'VR_PVCCIN_CPU0_PHASE2_RC'
 '@BASEBOARD_FAB2_LIB.BASEBOARD_FAB2(SCH_1):VR_PVCCIN_CPU0_PHASE2_RC':
 C_SIGNAL='@baseboard_fab2_lib.baseboard_fab2(sch_1):vr_pvccin_cpu0_phase2_rc';
NODE_NAME     CT5 2
 '@BASEBOARD_FAB2_LIB.BASEBOARD_FAB2(SCH_1):PAGE202_I98@MSTR_DISCRETE.CAP(CHIPS)':
 'B': CDS_PINID='B';
NODE_NAME     RT4 1
 '@BASEBOARD_FAB2_LIB.BASEBOARD_FAB2(SCH_1):PAGE202_I115@W_HDL.1R3F-GP(CHIPS)':
 '1': CDS_PINID='\1\';
NET_NAME
'VR_PVCCIN_CPU0_PHASE3'
 '@BASEBOARD_FAB2_LIB.BASEBOARD_FAB2(SCH_1):VR_PVCCIN_CPU0_PHASE3':
 C_SIGNAL='@baseboard_fab2_lib.baseboard_fab2(sch_1):vr_pvccin_cpu0_phase3';
NODE_NAME     EU4D3 10
 '@BASEBOARD_FAB2_LIB.BASEBOARD_FAB2(SCH_1):PAGE203_I70@MSTR_DISCRETE.IR354XX(CHIPS)':
 'SW': CDS_PINID='SW';
NODE_NAME     CT38 1
 '@BASEBOARD_FAB2_LIB.BASEBOARD_FAB2(SCH_1):PAGE203_I118@MSTR_DISCRETE.CAP(CHIPS)':
 'A': CDS_PINID='A';
NODE_NAME     L4D2 1
 '@BASEBOARD_FAB2_LIB.BASEBOARD_FAB2(SCH_1):PAGE203_I130@W_HDL.IND-120NH-30-GP(CHIPS)':
 'S': CDS_PINID='S';
NET_NAME
'VR_PVCCIN_CPU0_PHASE3_RC'
 '@BASEBOARD_FAB2_LIB.BASEBOARD_FAB2(SCH_1):VR_PVCCIN_CPU0_PHASE3_RC':
 C_SIGNAL='@baseboard_fab2_lib.baseboard_fab2(sch_1):vr_pvccin_cpu0_phase3_rc';
NODE_NAME     CT38 2
 '@BASEBOARD_FAB2_LIB.BASEBOARD_FAB2(SCH_1):PAGE203_I118@MSTR_DISCRETE.CAP(CHIPS)':
 'B': CDS_PINID='B';
NODE_NAME     RT26 1
 '@BASEBOARD_FAB2_LIB.BASEBOARD_FAB2(SCH_1):PAGE203_I134@W_HDL.1R3F-GP(CHIPS)':
 '1': CDS_PINID='\1\';
NET_NAME
'VR_PVCCIN_CPU0_PHASE4'
 '@BASEBOARD_FAB2_LIB.BASEBOARD_FAB2(SCH_1):VR_PVCCIN_CPU0_PHASE4':
 C_SIGNAL='@baseboard_fab2_lib.baseboard_fab2(sch_1):vr_pvccin_cpu0_phase4';
NODE_NAME     EU4D1 10
 '@BASEBOARD_FAB2_LIB.BASEBOARD_FAB2(SCH_1):PAGE203_I71@MSTR_DISCRETE.IR354XX(CHIPS)':
 'SW': CDS_PINID='SW';
NODE_NAME     CT41 1
 '@BASEBOARD_FAB2_LIB.BASEBOARD_FAB2(SCH_1):PAGE203_I119@MSTR_DISCRETE.CAP(CHIPS)':
 'A': CDS_PINID='A';
NODE_NAME     L4D1 1
 '@BASEBOARD_FAB2_LIB.BASEBOARD_FAB2(SCH_1):PAGE203_I131@W_HDL.IND-120NH-30-GP(CHIPS)':
 'S': CDS_PINID='S';
NET_NAME
'VR_PVCCIN_CPU0_PHASE4_RC'
 '@BASEBOARD_FAB2_LIB.BASEBOARD_FAB2(SCH_1):VR_PVCCIN_CPU0_PHASE4_RC':
 C_SIGNAL='@baseboard_fab2_lib.baseboard_fab2(sch_1):vr_pvccin_cpu0_phase4_rc';
NODE_NAME     CT41 2
 '@BASEBOARD_FAB2_LIB.BASEBOARD_FAB2(SCH_1):PAGE203_I119@MSTR_DISCRETE.CAP(CHIPS)':
 'B': CDS_PINID='B';
NODE_NAME     RT27 1
 '@BASEBOARD_FAB2_LIB.BASEBOARD_FAB2(SCH_1):PAGE203_I135@W_HDL.1R3F-GP(CHIPS)':
 '1': CDS_PINID='\1\';
NET_NAME
'VR_PVCCIN_CPU0_PHASE5'
 '@BASEBOARD_FAB2_LIB.BASEBOARD_FAB2(SCH_1):VR_PVCCIN_CPU0_PHASE5':
 C_SIGNAL='@baseboard_fab2_lib.baseboard_fab2(sch_1):vr_pvccin_cpu0_phase5';
NODE_NAME     EU4C2 10
 '@BASEBOARD_FAB2_LIB.BASEBOARD_FAB2(SCH_1):PAGE204_I71@MSTR_DISCRETE.IR354XX(CHIPS)':
 'SW': CDS_PINID='SW';
NODE_NAME     CT35 1
 '@BASEBOARD_FAB2_LIB.BASEBOARD_FAB2(SCH_1):PAGE204_I97@MSTR_DISCRETE.CAP(CHIPS)':
 'A': CDS_PINID='A';
NODE_NAME     L4C3 1
 '@BASEBOARD_FAB2_LIB.BASEBOARD_FAB2(SCH_1):PAGE204_I104@W_HDL.IND-120NH-30-GP(CHIPS)':
 'S': CDS_PINID='S';
NET_NAME
'VR_PVCCIN_CPU0_PHASE5_RC'
 '@BASEBOARD_FAB2_LIB.BASEBOARD_FAB2(SCH_1):VR_PVCCIN_CPU0_PHASE5_RC':
 C_SIGNAL='@baseboard_fab2_lib.baseboard_fab2(sch_1):vr_pvccin_cpu0_phase5_rc';
NODE_NAME     CT35 2
 '@BASEBOARD_FAB2_LIB.BASEBOARD_FAB2(SCH_1):PAGE204_I97@MSTR_DISCRETE.CAP(CHIPS)':
 'B': CDS_PINID='B';
NODE_NAME     RT24 1
 '@BASEBOARD_FAB2_LIB.BASEBOARD_FAB2(SCH_1):PAGE204_I114@W_HDL.1R3F-GP(CHIPS)':
 '1': CDS_PINID='\1\';
NET_NAME
'VR_PVCCIN_CPU0_PWM1'
 '@BASEBOARD_FAB2_LIB.BASEBOARD_FAB2(SCH_1):VR_PVCCIN_CPU0_PWM1':
 C_SIGNAL='@baseboard_fab2_lib.baseboard_fab2(sch_1):vr_pvccin_cpu0_pwm1';
NODE_NAME     EU4D4 7
 '@BASEBOARD_FAB2_LIB.BASEBOARD_FAB2(SCH_1):PAGE201_I155@MSTR_CONTROLLER.PXE1610B(CHIPS)':
 'APWM1': CDS_PINID='APWM1';
NODE_NAME     EU4E1 34
 '@BASEBOARD_FAB2_LIB.BASEBOARD_FAB2(SCH_1):PAGE202_I63@MSTR_DISCRETE.IR354XX(CHIPS)':
 'PWM': CDS_PINID='PWM';
NET_NAME
'VR_PVCCIN_CPU0_PWM2'
 '@BASEBOARD_FAB2_LIB.BASEBOARD_FAB2(SCH_1):VR_PVCCIN_CPU0_PWM2':
 C_SIGNAL='@baseboard_fab2_lib.baseboard_fab2(sch_1):vr_pvccin_cpu0_pwm2';
NODE_NAME     EU4D4 6
 '@BASEBOARD_FAB2_LIB.BASEBOARD_FAB2(SCH_1):PAGE201_I155@MSTR_CONTROLLER.PXE1610B(CHIPS)':
 'APWM2': CDS_PINID='APWM2';
NODE_NAME     EU4D6 34
 '@BASEBOARD_FAB2_LIB.BASEBOARD_FAB2(SCH_1):PAGE202_I64@MSTR_DISCRETE.IR354XX(CHIPS)':
 'PWM': CDS_PINID='PWM';
NET_NAME
'VR_PVCCIN_CPU0_PWM3'
 '@BASEBOARD_FAB2_LIB.BASEBOARD_FAB2(SCH_1):VR_PVCCIN_CPU0_PWM3':
 C_SIGNAL='@baseboard_fab2_lib.baseboard_fab2(sch_1):vr_pvccin_cpu0_pwm3';
NODE_NAME     EU4D4 5
 '@BASEBOARD_FAB2_LIB.BASEBOARD_FAB2(SCH_1):PAGE201_I155@MSTR_CONTROLLER.PXE1610B(CHIPS)':
 'APWM3': CDS_PINID='APWM3';
NODE_NAME     EU4D3 34
 '@BASEBOARD_FAB2_LIB.BASEBOARD_FAB2(SCH_1):PAGE203_I70@MSTR_DISCRETE.IR354XX(CHIPS)':
 'PWM': CDS_PINID='PWM';
NET_NAME
'VR_PVCCIN_CPU0_PWM4'
 '@BASEBOARD_FAB2_LIB.BASEBOARD_FAB2(SCH_1):VR_PVCCIN_CPU0_PWM4':
 C_SIGNAL='@baseboard_fab2_lib.baseboard_fab2(sch_1):vr_pvccin_cpu0_pwm4';
NODE_NAME     EU4D4 4
 '@BASEBOARD_FAB2_LIB.BASEBOARD_FAB2(SCH_1):PAGE201_I155@MSTR_CONTROLLER.PXE1610B(CHIPS)':
 'APWM4': CDS_PINID='APWM4';
NODE_NAME     EU4D1 34
 '@BASEBOARD_FAB2_LIB.BASEBOARD_FAB2(SCH_1):PAGE203_I71@MSTR_DISCRETE.IR354XX(CHIPS)':
 'PWM': CDS_PINID='PWM';
NET_NAME
'VR_PVCCIN_CPU0_PWM5'
 '@BASEBOARD_FAB2_LIB.BASEBOARD_FAB2(SCH_1):VR_PVCCIN_CPU0_PWM5':
 C_SIGNAL='@baseboard_fab2_lib.baseboard_fab2(sch_1):vr_pvccin_cpu0_pwm5';
NODE_NAME     EU4D4 3
 '@BASEBOARD_FAB2_LIB.BASEBOARD_FAB2(SCH_1):PAGE201_I155@MSTR_CONTROLLER.PXE1610B(CHIPS)':
 'APWM5': CDS_PINID='APWM5';
NODE_NAME     EU4C2 34
 '@BASEBOARD_FAB2_LIB.BASEBOARD_FAB2(SCH_1):PAGE204_I71@MSTR_DISCRETE.IR354XX(CHIPS)':
 'PWM': CDS_PINID='PWM';
NET_NAME
'VR_PVCCIN_CPU0_VD12'
 '@BASEBOARD_FAB2_LIB.BASEBOARD_FAB2(SCH_1):VR_PVCCIN_CPU0_VD12':
 C_SIGNAL='@baseboard_fab2_lib.baseboard_fab2(sch_1):vr_pvccin_cpu0_vd12';
NODE_NAME     C4D25 1
 '@BASEBOARD_FAB2_LIB.BASEBOARD_FAB2(SCH_1):PAGE201_I30@DEV_DISCRETE.CAP_A(CHIPS)':
 'A': CDS_PINID='A';
NODE_NAME     C4D26 1
 '@BASEBOARD_FAB2_LIB.BASEBOARD_FAB2(SCH_1):PAGE201_I32@DEV_DISCRETE.CAP_A(CHIPS)':
 'A': CDS_PINID='A';
NODE_NAME     EU4D4 48
 '@BASEBOARD_FAB2_LIB.BASEBOARD_FAB2(SCH_1):PAGE201_I155@MSTR_CONTROLLER.PXE1610B(CHIPS)':
 'VD12': CDS_PINID='VD12';
NET_NAME
'VR_PVCCIN_CPU0_VDD'
 '@BASEBOARD_FAB2_LIB.BASEBOARD_FAB2(SCH_1):VR_PVCCIN_CPU0_VDD':
 C_SIGNAL='@baseboard_fab2_lib.baseboard_fab2(sch_1):vr_pvccin_cpu0_vdd';
NODE_NAME     C4D15 1
 '@BASEBOARD_FAB2_LIB.BASEBOARD_FAB2(SCH_1):PAGE201_I37@DEV_DISCRETE.CAP_A(CHIPS)':
 'A': CDS_PINID='A';
NODE_NAME     C4D19 1
 '@BASEBOARD_FAB2_LIB.BASEBOARD_FAB2(SCH_1):PAGE201_I39@DEV_DISCRETE.CAP_A(CHIPS)':
 'A': CDS_PINID='A';
NODE_NAME     R4D26 2
 '@BASEBOARD_FAB2_LIB.BASEBOARD_FAB2(SCH_1):PAGE201_I40@MSTR_DISCRETE.RES(CHIPS)':
 'B': CDS_PINID='B';
NODE_NAME     EU4D4 47
 '@BASEBOARD_FAB2_LIB.BASEBOARD_FAB2(SCH_1):PAGE201_I155@MSTR_CONTROLLER.PXE1610B(CHIPS)':
 'VDD': CDS_PINID='VDD';
NET_NAME
'VR_PVCCIN_CPU0_VREN'
 '@BASEBOARD_FAB2_LIB.BASEBOARD_FAB2(SCH_1):VR_PVCCIN_CPU0_VREN':
 C_SIGNAL='@baseboard_fab2_lib.baseboard_fab2(sch_1):vr_pvccin_cpu0_vren';
NODE_NAME     R6P18 2
 '@BASEBOARD_FAB2_LIB.BASEBOARD_FAB2(SCH_1):PAGE201_I131@MSTR_DISCRETE.RES(CHIPS)':
 'B': CDS_PINID='B';
NODE_NAME     R6P16 2
 '@BASEBOARD_FAB2_LIB.BASEBOARD_FAB2(SCH_1):PAGE201_I132@MSTR_DISCRETE.RES(CHIPS)':
 'B': CDS_PINID='B';
NODE_NAME     EU4D4 12
 '@BASEBOARD_FAB2_LIB.BASEBOARD_FAB2(SCH_1):PAGE201_I155@MSTR_CONTROLLER.PXE1610B(CHIPS)':
 'AVREN': CDS_PINID='AVREN';
NET_NAME
'VR_PVCCIN_CPU0_XADDR1'
 '@BASEBOARD_FAB2_LIB.BASEBOARD_FAB2(SCH_1):VR_PVCCIN_CPU0_XADDR1':
 C_SIGNAL='@baseboard_fab2_lib.baseboard_fab2(sch_1):vr_pvccin_cpu0_xaddr1';
NODE_NAME     R6P28 1
 '@BASEBOARD_FAB2_LIB.BASEBOARD_FAB2(SCH_1):PAGE201_I121@MSTR_DISCRETE.RES(CHIPS)':
 'A': CDS_PINID='A';
NODE_NAME     EU4D4 44
 '@BASEBOARD_FAB2_LIB.BASEBOARD_FAB2(SCH_1):PAGE201_I155@MSTR_CONTROLLER.PXE1610B(CHIPS)':
 'XADDR1': CDS_PINID='XADDR1';
NET_NAME
'VR_PVCCIN_CPU0_XADDR2'
 '@BASEBOARD_FAB2_LIB.BASEBOARD_FAB2(SCH_1):VR_PVCCIN_CPU0_XADDR2':
 C_SIGNAL='@baseboard_fab2_lib.baseboard_fab2(sch_1):vr_pvccin_cpu0_xaddr2';
NODE_NAME     R6P27 1
 '@BASEBOARD_FAB2_LIB.BASEBOARD_FAB2(SCH_1):PAGE201_I120@MSTR_DISCRETE.RES(CHIPS)':
 'A': CDS_PINID='A';
NODE_NAME     EU4D4 41
 '@BASEBOARD_FAB2_LIB.BASEBOARD_FAB2(SCH_1):PAGE201_I155@MSTR_CONTROLLER.PXE1610B(CHIPS)':
 'XADDR2': CDS_PINID='XADDR2';
NET_NAME
'VR_PVCCIN_CPU1_AIREF1'
 '@BASEBOARD_FAB2_LIB.BASEBOARD_FAB2(SCH_1):VR_PVCCIN_CPU1_AIREF1':
 C_SIGNAL='@baseboard_fab2_lib.baseboard_fab2(sch_1):vr_pvccin_cpu1_airef1';
NODE_NAME     EU1C2 23
 '@BASEBOARD_FAB2_LIB.BASEBOARD_FAB2(SCH_1):PAGE206_I130@MSTR_CONTROLLER.PXE1610B(CHIPS)':
 'AIREF1': CDS_PINID='AIREF1';
NODE_NAME     EU1E2 39
 '@BASEBOARD_FAB2_LIB.BASEBOARD_FAB2(SCH_1):PAGE207_I20@MSTR_DISCRETE.IR354XX(CHIPS)':
 'REFIN': CDS_PINID='REFIN';
NODE_NAME     CT24 1
 '@BASEBOARD_FAB2_LIB.BASEBOARD_FAB2(SCH_1):PAGE207_I71@DEV_DISCRETE.CAP_A(CHIPS)':
 'A': CDS_PINID='A';
NODE_NAME     CF7 1
 '@BASEBOARD_FAB2_LIB.BASEBOARD_FAB2(SCH_1):PAGE206_I137@W_HDL.SC22P50V2JN-4GP(CHIPS)':
 '1': CDS_PINID='\1\';
NODE_NAME     RF7 1
 '@BASEBOARD_FAB2_LIB.BASEBOARD_FAB2(SCH_1):PAGE206_I150@MSTR_DISCRETE.RES(CHIPS)':
 'A': CDS_PINID='A';
NET_NAME
'VR_PVCCIN_CPU1_AIREF2'
 '@BASEBOARD_FAB2_LIB.BASEBOARD_FAB2(SCH_1):VR_PVCCIN_CPU1_AIREF2':
 C_SIGNAL='@baseboard_fab2_lib.baseboard_fab2(sch_1):vr_pvccin_cpu1_airef2';
NODE_NAME     EU1C2 25
 '@BASEBOARD_FAB2_LIB.BASEBOARD_FAB2(SCH_1):PAGE206_I130@MSTR_CONTROLLER.PXE1610B(CHIPS)':
 'AIREF2': CDS_PINID='AIREF2';
NODE_NAME     CT25 1
 '@BASEBOARD_FAB2_LIB.BASEBOARD_FAB2(SCH_1):PAGE207_I81@DEV_DISCRETE.CAP_A(CHIPS)':
 'A': CDS_PINID='A';
NODE_NAME     CF8 1
 '@BASEBOARD_FAB2_LIB.BASEBOARD_FAB2(SCH_1):PAGE206_I138@W_HDL.SC22P50V2JN-4GP(CHIPS)':
 '1': CDS_PINID='\1\';
NODE_NAME     RF8 1
 '@BASEBOARD_FAB2_LIB.BASEBOARD_FAB2(SCH_1):PAGE206_I151@MSTR_DISCRETE.RES(CHIPS)':
 'A': CDS_PINID='A';
NODE_NAME     EU1D4 39
 '@BASEBOARD_FAB2_LIB.BASEBOARD_FAB2(SCH_1):PAGE207_I113@MSTR_DISCRETE.IR354XX(CHIPS)':
 'REFIN': CDS_PINID='REFIN';
NET_NAME
'VR_PVCCIN_CPU1_AIREF3'
 '@BASEBOARD_FAB2_LIB.BASEBOARD_FAB2(SCH_1):VR_PVCCIN_CPU1_AIREF3':
 C_SIGNAL='@baseboard_fab2_lib.baseboard_fab2(sch_1):vr_pvccin_cpu1_airef3';
NODE_NAME     EU1C2 27
 '@BASEBOARD_FAB2_LIB.BASEBOARD_FAB2(SCH_1):PAGE206_I130@MSTR_CONTROLLER.PXE1610B(CHIPS)':
 'AIREF3': CDS_PINID='AIREF3';
NODE_NAME     EU1D3 39
 '@BASEBOARD_FAB2_LIB.BASEBOARD_FAB2(SCH_1):PAGE208_I27@MSTR_DISCRETE.IR354XX(CHIPS)':
 'REFIN': CDS_PINID='REFIN';
NODE_NAME     CT16 1
 '@BASEBOARD_FAB2_LIB.BASEBOARD_FAB2(SCH_1):PAGE208_I80@DEV_DISCRETE.CAP_A(CHIPS)':
 'A': CDS_PINID='A';
NODE_NAME     CF9 1
 '@BASEBOARD_FAB2_LIB.BASEBOARD_FAB2(SCH_1):PAGE206_I139@W_HDL.SC22P50V2JN-4GP(CHIPS)':
 '1': CDS_PINID='\1\';
NODE_NAME     RF9 1
 '@BASEBOARD_FAB2_LIB.BASEBOARD_FAB2(SCH_1):PAGE206_I152@MSTR_DISCRETE.RES(CHIPS)':
 'A': CDS_PINID='A';
NET_NAME
'VR_PVCCIN_CPU1_AIREF4'
 '@BASEBOARD_FAB2_LIB.BASEBOARD_FAB2(SCH_1):VR_PVCCIN_CPU1_AIREF4':
 C_SIGNAL='@baseboard_fab2_lib.baseboard_fab2(sch_1):vr_pvccin_cpu1_airef4';
NODE_NAME     EU1C2 29
 '@BASEBOARD_FAB2_LIB.BASEBOARD_FAB2(SCH_1):PAGE206_I130@MSTR_CONTROLLER.PXE1610B(CHIPS)':
 'AIREF4': CDS_PINID='AIREF4';
NODE_NAME     EU1D1 39
 '@BASEBOARD_FAB2_LIB.BASEBOARD_FAB2(SCH_1):PAGE208_I71@MSTR_DISCRETE.IR354XX(CHIPS)':
 'REFIN': CDS_PINID='REFIN';
NODE_NAME     CT21 1
 '@BASEBOARD_FAB2_LIB.BASEBOARD_FAB2(SCH_1):PAGE208_I87@DEV_DISCRETE.CAP_A(CHIPS)':
 'A': CDS_PINID='A';
NODE_NAME     CF10 1
 '@BASEBOARD_FAB2_LIB.BASEBOARD_FAB2(SCH_1):PAGE206_I140@W_HDL.SC22P50V2JN-4GP(CHIPS)':
 '1': CDS_PINID='\1\';
NODE_NAME     RF10 1
 '@BASEBOARD_FAB2_LIB.BASEBOARD_FAB2(SCH_1):PAGE206_I153@MSTR_DISCRETE.RES(CHIPS)':
 'A': CDS_PINID='A';
NET_NAME
'VR_PVCCIN_CPU1_AIREF5'
 '@BASEBOARD_FAB2_LIB.BASEBOARD_FAB2(SCH_1):VR_PVCCIN_CPU1_AIREF5':
 C_SIGNAL='@baseboard_fab2_lib.baseboard_fab2(sch_1):vr_pvccin_cpu1_airef5';
NODE_NAME     EU1C2 31
 '@BASEBOARD_FAB2_LIB.BASEBOARD_FAB2(SCH_1):PAGE206_I130@MSTR_CONTROLLER.PXE1610B(CHIPS)':
 'AIREF5': CDS_PINID='AIREF5';
NODE_NAME     EU1C3 39
 '@BASEBOARD_FAB2_LIB.BASEBOARD_FAB2(SCH_1):PAGE209_I56@MSTR_DISCRETE.IR354XX(CHIPS)':
 'REFIN': CDS_PINID='REFIN';
NODE_NAME     CT13 1
 '@BASEBOARD_FAB2_LIB.BASEBOARD_FAB2(SCH_1):PAGE209_I62@DEV_DISCRETE.CAP_A(CHIPS)':
 'A': CDS_PINID='A';
NODE_NAME     CF11 1
 '@BASEBOARD_FAB2_LIB.BASEBOARD_FAB2(SCH_1):PAGE206_I141@W_HDL.SC22P50V2JN-4GP(CHIPS)':
 '1': CDS_PINID='\1\';
NODE_NAME     RF11 1
 '@BASEBOARD_FAB2_LIB.BASEBOARD_FAB2(SCH_1):PAGE206_I154@MSTR_DISCRETE.RES(CHIPS)':
 'A': CDS_PINID='A';
NET_NAME
'VR_PVCCIN_CPU1_AVINSEN'
 '@BASEBOARD_FAB2_LIB.BASEBOARD_FAB2(SCH_1):VR_PVCCIN_CPU1_AVINSEN':
 C_SIGNAL='@baseboard_fab2_lib.baseboard_fab2(sch_1):vr_pvccin_cpu1_avinsen';
NODE_NAME     R1C13 2
 '@BASEBOARD_FAB2_LIB.BASEBOARD_FAB2(SCH_1):PAGE206_I49@MSTR_DISCRETE.RES(CHIPS)':
 'B': CDS_PINID='B';
NODE_NAME     R1C16 1
 '@BASEBOARD_FAB2_LIB.BASEBOARD_FAB2(SCH_1):PAGE206_I56@MSTR_DISCRETE.RES(CHIPS)':
 'A': CDS_PINID='A';
NODE_NAME     EU1C2 45
 '@BASEBOARD_FAB2_LIB.BASEBOARD_FAB2(SCH_1):PAGE206_I130@MSTR_CONTROLLER.PXE1610B(CHIPS)':
 'VINSEN': CDS_PINID='VINSEN';
NODE_NAME     C1C8 1
 '@BASEBOARD_FAB2_LIB.BASEBOARD_FAB2(SCH_1):PAGE206_I156@DEV_DISCRETE.CAP_A(CHIPS)':
 'A': CDS_PINID='A';
NET_NAME
'VR_PVCCIN_CPU1_PH1_BOOT'
 '@BASEBOARD_FAB2_LIB.BASEBOARD_FAB2(SCH_1):VR_PVCCIN_CPU1_PH1_BOOT':
 C_SIGNAL='@baseboard_fab2_lib.baseboard_fab2(sch_1):vr_pvccin_cpu1_ph1_boot';
NODE_NAME     C1E11 1
 '@BASEBOARD_FAB2_LIB.BASEBOARD_FAB2(SCH_1):PAGE207_I30@MSTR_DISCRETE.CAP(CHIPS)':
 'A': CDS_PINID='A';
NODE_NAME     RT15 1
 '@BASEBOARD_FAB2_LIB.BASEBOARD_FAB2(SCH_1):PAGE207_I99@MSTR_DISCRETE.RES(CHIPS)':
 'A': CDS_PINID='A';
NET_NAME
'VR_PVCCIN_CPU1_PH1_BOOT_R'
 '@BASEBOARD_FAB2_LIB.BASEBOARD_FAB2(SCH_1):VR_PVCCIN_CPU1_PH1_BOOT_R':
 C_SIGNAL='@baseboard_fab2_lib.baseboard_fab2(sch_1):vr_pvccin_cpu1_ph1_boot_r';
NODE_NAME     EU1E2 33
 '@BASEBOARD_FAB2_LIB.BASEBOARD_FAB2(SCH_1):PAGE207_I20@MSTR_DISCRETE.IR354XX(CHIPS)':
 'BOOST': CDS_PINID='BOOST';
NODE_NAME     RT15 2
 '@BASEBOARD_FAB2_LIB.BASEBOARD_FAB2(SCH_1):PAGE207_I99@MSTR_DISCRETE.RES(CHIPS)':
 'B': CDS_PINID='B';
NET_NAME
'VR_PVCCIN_CPU1_PH1_OCSET'
 '@BASEBOARD_FAB2_LIB.BASEBOARD_FAB2(SCH_1):VR_PVCCIN_CPU1_PH1_OCSET':
 C_SIGNAL='@baseboard_fab2_lib.baseboard_fab2(sch_1):vr_pvccin_cpu1_ph1_ocset';
NODE_NAME     EU1E2 37
 '@BASEBOARD_FAB2_LIB.BASEBOARD_FAB2(SCH_1):PAGE207_I20@MSTR_DISCRETE.IR354XX(CHIPS)':
 'OCSET': CDS_PINID='OCSET';
NODE_NAME     R1E14 1
 '@BASEBOARD_FAB2_LIB.BASEBOARD_FAB2(SCH_1):PAGE207_I68@MSTR_DISCRETE.RES(CHIPS)':
 'A': CDS_PINID='A';
NET_NAME
'VR_PVCCIN_CPU1_PH1_PHASE'
 '@BASEBOARD_FAB2_LIB.BASEBOARD_FAB2(SCH_1):VR_PVCCIN_CPU1_PH1_PHASE':
 C_SIGNAL='@baseboard_fab2_lib.baseboard_fab2(sch_1):vr_pvccin_cpu1_ph1_phase';
NODE_NAME     EU1E2 32
 '@BASEBOARD_FAB2_LIB.BASEBOARD_FAB2(SCH_1):PAGE207_I20@MSTR_DISCRETE.IR354XX(CHIPS)':
 'PHASE': CDS_PINID='PHASE';
NODE_NAME     C1E11 2
 '@BASEBOARD_FAB2_LIB.BASEBOARD_FAB2(SCH_1):PAGE207_I30@MSTR_DISCRETE.CAP(CHIPS)':
 'B': CDS_PINID='B';
NET_NAME
'VR_PVCCIN_CPU1_PH1_VCIN'
 '@BASEBOARD_FAB2_LIB.BASEBOARD_FAB2(SCH_1):VR_PVCCIN_CPU1_PH1_VCIN':
 C_SIGNAL='@baseboard_fab2_lib.baseboard_fab2(sch_1):vr_pvccin_cpu1_ph1_vcin';
NODE_NAME     EU1E2 3
 '@BASEBOARD_FAB2_LIB.BASEBOARD_FAB2(SCH_1):PAGE207_I20@MSTR_DISCRETE.IR354XX(CHIPS)':
 'VCC': CDS_PINID='VCC';
NODE_NAME     C1E8 1
 '@BASEBOARD_FAB2_LIB.BASEBOARD_FAB2(SCH_1):PAGE207_I32@MSTR_DISCRETE.CAP(CHIPS)':
 'A': CDS_PINID='A';
NODE_NAME     R9R2 1
 '@BASEBOARD_FAB2_LIB.BASEBOARD_FAB2(SCH_1):PAGE207_I106@MSTR_DISCRETE.RES(CHIPS)':
 'A': CDS_PINID='A';
NET_NAME
'VR_PVCCIN_CPU1_PH2_BOOT'
 '@BASEBOARD_FAB2_LIB.BASEBOARD_FAB2(SCH_1):VR_PVCCIN_CPU1_PH2_BOOT':
 C_SIGNAL='@baseboard_fab2_lib.baseboard_fab2(sch_1):vr_pvccin_cpu1_ph2_boot';
NODE_NAME     C1D36 1
 '@BASEBOARD_FAB2_LIB.BASEBOARD_FAB2(SCH_1):PAGE207_I38@MSTR_DISCRETE.CAP(CHIPS)':
 'A': CDS_PINID='A';
NODE_NAME     RT17 1
 '@BASEBOARD_FAB2_LIB.BASEBOARD_FAB2(SCH_1):PAGE207_I100@MSTR_DISCRETE.RES(CHIPS)':
 'A': CDS_PINID='A';
NET_NAME
'VR_PVCCIN_CPU1_PH2_BOOT_R'
 '@BASEBOARD_FAB2_LIB.BASEBOARD_FAB2(SCH_1):VR_PVCCIN_CPU1_PH2_BOOT_R':
 C_SIGNAL='@baseboard_fab2_lib.baseboard_fab2(sch_1):vr_pvccin_cpu1_ph2_boot_r';
NODE_NAME     RT17 2
 '@BASEBOARD_FAB2_LIB.BASEBOARD_FAB2(SCH_1):PAGE207_I100@MSTR_DISCRETE.RES(CHIPS)':
 'B': CDS_PINID='B';
NODE_NAME     EU1D4 33
 '@BASEBOARD_FAB2_LIB.BASEBOARD_FAB2(SCH_1):PAGE207_I113@MSTR_DISCRETE.IR354XX(CHIPS)':
 'BOOST': CDS_PINID='BOOST';
NET_NAME
'VR_PVCCIN_CPU1_PH2_OCSET'
 '@BASEBOARD_FAB2_LIB.BASEBOARD_FAB2(SCH_1):VR_PVCCIN_CPU1_PH2_OCSET':
 C_SIGNAL='@baseboard_fab2_lib.baseboard_fab2(sch_1):vr_pvccin_cpu1_ph2_ocset';
NODE_NAME     R1E13 1
 '@BASEBOARD_FAB2_LIB.BASEBOARD_FAB2(SCH_1):PAGE207_I67@MSTR_DISCRETE.RES(CHIPS)':
 'A': CDS_PINID='A';
NODE_NAME     EU1D4 37
 '@BASEBOARD_FAB2_LIB.BASEBOARD_FAB2(SCH_1):PAGE207_I113@MSTR_DISCRETE.IR354XX(CHIPS)':
 'OCSET': CDS_PINID='OCSET';
NET_NAME
'VR_PVCCIN_CPU1_PH2_PHASE'
 '@BASEBOARD_FAB2_LIB.BASEBOARD_FAB2(SCH_1):VR_PVCCIN_CPU1_PH2_PHASE':
 C_SIGNAL='@baseboard_fab2_lib.baseboard_fab2(sch_1):vr_pvccin_cpu1_ph2_phase';
NODE_NAME     C1D36 2
 '@BASEBOARD_FAB2_LIB.BASEBOARD_FAB2(SCH_1):PAGE207_I38@MSTR_DISCRETE.CAP(CHIPS)':
 'B': CDS_PINID='B';
NODE_NAME     EU1D4 32
 '@BASEBOARD_FAB2_LIB.BASEBOARD_FAB2(SCH_1):PAGE207_I113@MSTR_DISCRETE.IR354XX(CHIPS)':
 'PHASE': CDS_PINID='PHASE';
NET_NAME
'VR_PVCCIN_CPU1_PH2_VCIN'
 '@BASEBOARD_FAB2_LIB.BASEBOARD_FAB2(SCH_1):VR_PVCCIN_CPU1_PH2_VCIN':
 C_SIGNAL='@baseboard_fab2_lib.baseboard_fab2(sch_1):vr_pvccin_cpu1_ph2_vcin';
NODE_NAME     C1E24 1
 '@BASEBOARD_FAB2_LIB.BASEBOARD_FAB2(SCH_1):PAGE207_I40@MSTR_DISCRETE.CAP(CHIPS)':
 'A': CDS_PINID='A';
NODE_NAME     R9R11 1
 '@BASEBOARD_FAB2_LIB.BASEBOARD_FAB2(SCH_1):PAGE207_I105@MSTR_DISCRETE.RES(CHIPS)':
 'A': CDS_PINID='A';
NODE_NAME     EU1D4 3
 '@BASEBOARD_FAB2_LIB.BASEBOARD_FAB2(SCH_1):PAGE207_I113@MSTR_DISCRETE.IR354XX(CHIPS)':
 'VCC': CDS_PINID='VCC';
NET_NAME
'VR_PVCCIN_CPU1_PH3_BOOT'
 '@BASEBOARD_FAB2_LIB.BASEBOARD_FAB2(SCH_1):VR_PVCCIN_CPU1_PH3_BOOT':
 C_SIGNAL='@baseboard_fab2_lib.baseboard_fab2(sch_1):vr_pvccin_cpu1_ph3_boot';
NODE_NAME     C1D20 1
 '@BASEBOARD_FAB2_LIB.BASEBOARD_FAB2(SCH_1):PAGE208_I40@MSTR_DISCRETE.CAP(CHIPS)':
 'A': CDS_PINID='A';
NODE_NAME     RT11 1
 '@BASEBOARD_FAB2_LIB.BASEBOARD_FAB2(SCH_1):PAGE208_I108@MSTR_DISCRETE.RES(CHIPS)':
 'A': CDS_PINID='A';
NET_NAME
'VR_PVCCIN_CPU1_PH3_BOOT_R'
 '@BASEBOARD_FAB2_LIB.BASEBOARD_FAB2(SCH_1):VR_PVCCIN_CPU1_PH3_BOOT_R':
 C_SIGNAL='@baseboard_fab2_lib.baseboard_fab2(sch_1):vr_pvccin_cpu1_ph3_boot_r';
NODE_NAME     EU1D3 33
 '@BASEBOARD_FAB2_LIB.BASEBOARD_FAB2(SCH_1):PAGE208_I27@MSTR_DISCRETE.IR354XX(CHIPS)':
 'BOOST': CDS_PINID='BOOST';
NODE_NAME     RT11 2
 '@BASEBOARD_FAB2_LIB.BASEBOARD_FAB2(SCH_1):PAGE208_I108@MSTR_DISCRETE.RES(CHIPS)':
 'B': CDS_PINID='B';
NET_NAME
'VR_PVCCIN_CPU1_PH3_OCSET'
 '@BASEBOARD_FAB2_LIB.BASEBOARD_FAB2(SCH_1):VR_PVCCIN_CPU1_PH3_OCSET':
 C_SIGNAL='@baseboard_fab2_lib.baseboard_fab2(sch_1):vr_pvccin_cpu1_ph3_ocset';
NODE_NAME     EU1D3 37
 '@BASEBOARD_FAB2_LIB.BASEBOARD_FAB2(SCH_1):PAGE208_I27@MSTR_DISCRETE.IR354XX(CHIPS)':
 'OCSET': CDS_PINID='OCSET';
NODE_NAME     R1D55 1
 '@BASEBOARD_FAB2_LIB.BASEBOARD_FAB2(SCH_1):PAGE208_I76@MSTR_DISCRETE.RES(CHIPS)':
 'A': CDS_PINID='A';
NET_NAME
'VR_PVCCIN_CPU1_PH3_PHASE'
 '@BASEBOARD_FAB2_LIB.BASEBOARD_FAB2(SCH_1):VR_PVCCIN_CPU1_PH3_PHASE':
 C_SIGNAL='@baseboard_fab2_lib.baseboard_fab2(sch_1):vr_pvccin_cpu1_ph3_phase';
NODE_NAME     EU1D3 32
 '@BASEBOARD_FAB2_LIB.BASEBOARD_FAB2(SCH_1):PAGE208_I27@MSTR_DISCRETE.IR354XX(CHIPS)':
 'PHASE': CDS_PINID='PHASE';
NODE_NAME     C1D20 2
 '@BASEBOARD_FAB2_LIB.BASEBOARD_FAB2(SCH_1):PAGE208_I40@MSTR_DISCRETE.CAP(CHIPS)':
 'B': CDS_PINID='B';
NET_NAME
'VR_PVCCIN_CPU1_PH3_VCIN'
 '@BASEBOARD_FAB2_LIB.BASEBOARD_FAB2(SCH_1):VR_PVCCIN_CPU1_PH3_VCIN':
 C_SIGNAL='@baseboard_fab2_lib.baseboard_fab2(sch_1):vr_pvccin_cpu1_ph3_vcin';
NODE_NAME     EU1D3 3
 '@BASEBOARD_FAB2_LIB.BASEBOARD_FAB2(SCH_1):PAGE208_I27@MSTR_DISCRETE.IR354XX(CHIPS)':
 'VCC': CDS_PINID='VCC';
NODE_NAME     C1D17 1
 '@BASEBOARD_FAB2_LIB.BASEBOARD_FAB2(SCH_1):PAGE208_I43@MSTR_DISCRETE.CAP(CHIPS)':
 'A': CDS_PINID='A';
NODE_NAME     R9P22 1
 '@BASEBOARD_FAB2_LIB.BASEBOARD_FAB2(SCH_1):PAGE208_I114@MSTR_DISCRETE.RES(CHIPS)':
 'A': CDS_PINID='A';
NET_NAME
'VR_PVCCIN_CPU1_PH4_BOOT'
 '@BASEBOARD_FAB2_LIB.BASEBOARD_FAB2(SCH_1):VR_PVCCIN_CPU1_PH4_BOOT':
 C_SIGNAL='@baseboard_fab2_lib.baseboard_fab2(sch_1):vr_pvccin_cpu1_ph4_boot';
NODE_NAME     C1D10 1
 '@BASEBOARD_FAB2_LIB.BASEBOARD_FAB2(SCH_1):PAGE208_I48@MSTR_DISCRETE.CAP(CHIPS)':
 'A': CDS_PINID='A';
NODE_NAME     RT14 1
 '@BASEBOARD_FAB2_LIB.BASEBOARD_FAB2(SCH_1):PAGE208_I109@MSTR_DISCRETE.RES(CHIPS)':
 'A': CDS_PINID='A';
NET_NAME
'VR_PVCCIN_CPU1_PH4_BOOT_R'
 '@BASEBOARD_FAB2_LIB.BASEBOARD_FAB2(SCH_1):VR_PVCCIN_CPU1_PH4_BOOT_R':
 C_SIGNAL='@baseboard_fab2_lib.baseboard_fab2(sch_1):vr_pvccin_cpu1_ph4_boot_r';
NODE_NAME     EU1D1 33
 '@BASEBOARD_FAB2_LIB.BASEBOARD_FAB2(SCH_1):PAGE208_I71@MSTR_DISCRETE.IR354XX(CHIPS)':
 'BOOST': CDS_PINID='BOOST';
NODE_NAME     RT14 2
 '@BASEBOARD_FAB2_LIB.BASEBOARD_FAB2(SCH_1):PAGE208_I109@MSTR_DISCRETE.RES(CHIPS)':
 'B': CDS_PINID='B';
NET_NAME
'VR_PVCCIN_CPU1_PH4_OCSET'
 '@BASEBOARD_FAB2_LIB.BASEBOARD_FAB2(SCH_1):VR_PVCCIN_CPU1_PH4_OCSET':
 C_SIGNAL='@baseboard_fab2_lib.baseboard_fab2(sch_1):vr_pvccin_cpu1_ph4_ocset';
NODE_NAME     EU1D1 37
 '@BASEBOARD_FAB2_LIB.BASEBOARD_FAB2(SCH_1):PAGE208_I71@MSTR_DISCRETE.IR354XX(CHIPS)':
 'OCSET': CDS_PINID='OCSET';
NODE_NAME     R1D54 1
 '@BASEBOARD_FAB2_LIB.BASEBOARD_FAB2(SCH_1):PAGE208_I75@MSTR_DISCRETE.RES(CHIPS)':
 'A': CDS_PINID='A';
NET_NAME
'VR_PVCCIN_CPU1_PH4_PHASE'
 '@BASEBOARD_FAB2_LIB.BASEBOARD_FAB2(SCH_1):VR_PVCCIN_CPU1_PH4_PHASE':
 C_SIGNAL='@baseboard_fab2_lib.baseboard_fab2(sch_1):vr_pvccin_cpu1_ph4_phase';
NODE_NAME     C1D10 2
 '@BASEBOARD_FAB2_LIB.BASEBOARD_FAB2(SCH_1):PAGE208_I48@MSTR_DISCRETE.CAP(CHIPS)':
 'B': CDS_PINID='B';
NODE_NAME     EU1D1 32
 '@BASEBOARD_FAB2_LIB.BASEBOARD_FAB2(SCH_1):PAGE208_I71@MSTR_DISCRETE.IR354XX(CHIPS)':
 'PHASE': CDS_PINID='PHASE';
NET_NAME
'VR_PVCCIN_CPU1_PH4_VCIN'
 '@BASEBOARD_FAB2_LIB.BASEBOARD_FAB2(SCH_1):VR_PVCCIN_CPU1_PH4_VCIN':
 C_SIGNAL='@baseboard_fab2_lib.baseboard_fab2(sch_1):vr_pvccin_cpu1_ph4_vcin';
NODE_NAME     C1D7 1
 '@BASEBOARD_FAB2_LIB.BASEBOARD_FAB2(SCH_1):PAGE208_I50@MSTR_DISCRETE.CAP(CHIPS)':
 'A': CDS_PINID='A';
NODE_NAME     EU1D1 3
 '@BASEBOARD_FAB2_LIB.BASEBOARD_FAB2(SCH_1):PAGE208_I71@MSTR_DISCRETE.IR354XX(CHIPS)':
 'VCC': CDS_PINID='VCC';
NODE_NAME     R9P8 1
 '@BASEBOARD_FAB2_LIB.BASEBOARD_FAB2(SCH_1):PAGE208_I115@MSTR_DISCRETE.RES(CHIPS)':
 'A': CDS_PINID='A';
NET_NAME
'VR_PVCCIN_CPU1_PH5_BOOT'
 '@BASEBOARD_FAB2_LIB.BASEBOARD_FAB2(SCH_1):VR_PVCCIN_CPU1_PH5_BOOT':
 C_SIGNAL='@baseboard_fab2_lib.baseboard_fab2(sch_1):vr_pvccin_cpu1_ph5_boot';
NODE_NAME     C1C24 1
 '@BASEBOARD_FAB2_LIB.BASEBOARD_FAB2(SCH_1):PAGE209_I20@MSTR_DISCRETE.CAP(CHIPS)':
 'A': CDS_PINID='A';
NODE_NAME     RT9 1
 '@BASEBOARD_FAB2_LIB.BASEBOARD_FAB2(SCH_1):PAGE209_I75@MSTR_DISCRETE.RES(CHIPS)':
 'A': CDS_PINID='A';
NET_NAME
'VR_PVCCIN_CPU1_PH5_BOOT_R'
 '@BASEBOARD_FAB2_LIB.BASEBOARD_FAB2(SCH_1):VR_PVCCIN_CPU1_PH5_BOOT_R':
 C_SIGNAL='@baseboard_fab2_lib.baseboard_fab2(sch_1):vr_pvccin_cpu1_ph5_boot_r';
NODE_NAME     EU1C3 33
 '@BASEBOARD_FAB2_LIB.BASEBOARD_FAB2(SCH_1):PAGE209_I56@MSTR_DISCRETE.IR354XX(CHIPS)':
 'BOOST': CDS_PINID='BOOST';
NODE_NAME     RT9 2
 '@BASEBOARD_FAB2_LIB.BASEBOARD_FAB2(SCH_1):PAGE209_I75@MSTR_DISCRETE.RES(CHIPS)':
 'B': CDS_PINID='B';
NET_NAME
'VR_PVCCIN_CPU1_PH5_OCSET'
 '@BASEBOARD_FAB2_LIB.BASEBOARD_FAB2(SCH_1):VR_PVCCIN_CPU1_PH5_OCSET':
 C_SIGNAL='@baseboard_fab2_lib.baseboard_fab2(sch_1):vr_pvccin_cpu1_ph5_ocset';
NODE_NAME     EU1C3 37
 '@BASEBOARD_FAB2_LIB.BASEBOARD_FAB2(SCH_1):PAGE209_I56@MSTR_DISCRETE.IR354XX(CHIPS)':
 'OCSET': CDS_PINID='OCSET';
NODE_NAME     R1D52 1
 '@BASEBOARD_FAB2_LIB.BASEBOARD_FAB2(SCH_1):PAGE209_I59@MSTR_DISCRETE.RES(CHIPS)':
 'A': CDS_PINID='A';
NET_NAME
'VR_PVCCIN_CPU1_PH5_PHASE'
 '@BASEBOARD_FAB2_LIB.BASEBOARD_FAB2(SCH_1):VR_PVCCIN_CPU1_PH5_PHASE':
 C_SIGNAL='@baseboard_fab2_lib.baseboard_fab2(sch_1):vr_pvccin_cpu1_ph5_phase';
NODE_NAME     C1C24 2
 '@BASEBOARD_FAB2_LIB.BASEBOARD_FAB2(SCH_1):PAGE209_I20@MSTR_DISCRETE.CAP(CHIPS)':
 'B': CDS_PINID='B';
NODE_NAME     EU1C3 32
 '@BASEBOARD_FAB2_LIB.BASEBOARD_FAB2(SCH_1):PAGE209_I56@MSTR_DISCRETE.IR354XX(CHIPS)':
 'PHASE': CDS_PINID='PHASE';
NET_NAME
'VR_PVCCIN_CPU1_PH5_VCIN'
 '@BASEBOARD_FAB2_LIB.BASEBOARD_FAB2(SCH_1):VR_PVCCIN_CPU1_PH5_VCIN':
 C_SIGNAL='@baseboard_fab2_lib.baseboard_fab2(sch_1):vr_pvccin_cpu1_ph5_vcin';
NODE_NAME     C1D32 1
 '@BASEBOARD_FAB2_LIB.BASEBOARD_FAB2(SCH_1):PAGE209_I18@MSTR_DISCRETE.CAP(CHIPS)':
 'A': CDS_PINID='A';
NODE_NAME     EU1C3 3
 '@BASEBOARD_FAB2_LIB.BASEBOARD_FAB2(SCH_1):PAGE209_I56@MSTR_DISCRETE.IR354XX(CHIPS)':
 'VCC': CDS_PINID='VCC';
NODE_NAME     R9P32 1
 '@BASEBOARD_FAB2_LIB.BASEBOARD_FAB2(SCH_1):PAGE209_I79@MSTR_DISCRETE.RES(CHIPS)':
 'A': CDS_PINID='A';
NET_NAME
'VR_PVCCIN_CPU1_PHASE1'
 '@BASEBOARD_FAB2_LIB.BASEBOARD_FAB2(SCH_1):VR_PVCCIN_CPU1_PHASE1':
 C_SIGNAL='@baseboard_fab2_lib.baseboard_fab2(sch_1):vr_pvccin_cpu1_phase1';
NODE_NAME     EU1E2 10
 '@BASEBOARD_FAB2_LIB.BASEBOARD_FAB2(SCH_1):PAGE207_I20@MSTR_DISCRETE.IR354XX(CHIPS)':
 'SW': CDS_PINID='SW';
NODE_NAME     CT23 1
 '@BASEBOARD_FAB2_LIB.BASEBOARD_FAB2(SCH_1):PAGE207_I95@MSTR_DISCRETE.CAP(CHIPS)':
 'A': CDS_PINID='A';
NODE_NAME     L1E1 1
 '@BASEBOARD_FAB2_LIB.BASEBOARD_FAB2(SCH_1):PAGE207_I107@W_HDL.IND-120NH-30-GP(CHIPS)':
 'S': CDS_PINID='S';
NET_NAME
'VR_PVCCIN_CPU1_PHASE1_RC'
 '@BASEBOARD_FAB2_LIB.BASEBOARD_FAB2(SCH_1):VR_PVCCIN_CPU1_PHASE1_RC':
 C_SIGNAL='@baseboard_fab2_lib.baseboard_fab2(sch_1):vr_pvccin_cpu1_phase1_rc';
NODE_NAME     CT23 2
 '@BASEBOARD_FAB2_LIB.BASEBOARD_FAB2(SCH_1):PAGE207_I95@MSTR_DISCRETE.CAP(CHIPS)':
 'B': CDS_PINID='B';
NODE_NAME     RT16 1
 '@BASEBOARD_FAB2_LIB.BASEBOARD_FAB2(SCH_1):PAGE207_I111@W_HDL.1R3F-GP(CHIPS)':
 '1': CDS_PINID='\1\';
NET_NAME
'VR_PVCCIN_CPU1_PHASE2'
 '@BASEBOARD_FAB2_LIB.BASEBOARD_FAB2(SCH_1):VR_PVCCIN_CPU1_PHASE2':
 C_SIGNAL='@baseboard_fab2_lib.baseboard_fab2(sch_1):vr_pvccin_cpu1_phase2';
NODE_NAME     CT27 1
 '@BASEBOARD_FAB2_LIB.BASEBOARD_FAB2(SCH_1):PAGE207_I96@MSTR_DISCRETE.CAP(CHIPS)':
 'A': CDS_PINID='A';
NODE_NAME     L1D3 1
 '@BASEBOARD_FAB2_LIB.BASEBOARD_FAB2(SCH_1):PAGE207_I108@W_HDL.IND-120NH-30-GP(CHIPS)':
 'S': CDS_PINID='S';
NODE_NAME     EU1D4 10
 '@BASEBOARD_FAB2_LIB.BASEBOARD_FAB2(SCH_1):PAGE207_I113@MSTR_DISCRETE.IR354XX(CHIPS)':
 'SW': CDS_PINID='SW';
NET_NAME
'VR_PVCCIN_CPU1_PHASE2_RC'
 '@BASEBOARD_FAB2_LIB.BASEBOARD_FAB2(SCH_1):VR_PVCCIN_CPU1_PHASE2_RC':
 C_SIGNAL='@baseboard_fab2_lib.baseboard_fab2(sch_1):vr_pvccin_cpu1_phase2_rc';
NODE_NAME     CT27 2
 '@BASEBOARD_FAB2_LIB.BASEBOARD_FAB2(SCH_1):PAGE207_I96@MSTR_DISCRETE.CAP(CHIPS)':
 'B': CDS_PINID='B';
NODE_NAME     RT18 1
 '@BASEBOARD_FAB2_LIB.BASEBOARD_FAB2(SCH_1):PAGE207_I112@W_HDL.1R3F-GP(CHIPS)':
 '1': CDS_PINID='\1\';
NET_NAME
'VR_PVCCIN_CPU1_PHASE3'
 '@BASEBOARD_FAB2_LIB.BASEBOARD_FAB2(SCH_1):VR_PVCCIN_CPU1_PHASE3':
 C_SIGNAL='@baseboard_fab2_lib.baseboard_fab2(sch_1):vr_pvccin_cpu1_phase3';
NODE_NAME     EU1D3 10
 '@BASEBOARD_FAB2_LIB.BASEBOARD_FAB2(SCH_1):PAGE208_I27@MSTR_DISCRETE.IR354XX(CHIPS)':
 'SW': CDS_PINID='SW';
NODE_NAME     CT18 1
 '@BASEBOARD_FAB2_LIB.BASEBOARD_FAB2(SCH_1):PAGE208_I104@MSTR_DISCRETE.CAP(CHIPS)':
 'A': CDS_PINID='A';
NODE_NAME     L1D2 1
 '@BASEBOARD_FAB2_LIB.BASEBOARD_FAB2(SCH_1):PAGE208_I116@W_HDL.IND-120NH-30-GP(CHIPS)':
 'S': CDS_PINID='S';
NET_NAME
'VR_PVCCIN_CPU1_PHASE3_RC'
 '@BASEBOARD_FAB2_LIB.BASEBOARD_FAB2(SCH_1):VR_PVCCIN_CPU1_PHASE3_RC':
 C_SIGNAL='@baseboard_fab2_lib.baseboard_fab2(sch_1):vr_pvccin_cpu1_phase3_rc';
NODE_NAME     CT18 2
 '@BASEBOARD_FAB2_LIB.BASEBOARD_FAB2(SCH_1):PAGE208_I104@MSTR_DISCRETE.CAP(CHIPS)':
 'B': CDS_PINID='B';
NODE_NAME     RT12 1
 '@BASEBOARD_FAB2_LIB.BASEBOARD_FAB2(SCH_1):PAGE208_I120@W_HDL.1R3F-GP(CHIPS)':
 '1': CDS_PINID='\1\';
NET_NAME
'VR_PVCCIN_CPU1_PHASE4'
 '@BASEBOARD_FAB2_LIB.BASEBOARD_FAB2(SCH_1):VR_PVCCIN_CPU1_PHASE4':
 C_SIGNAL='@baseboard_fab2_lib.baseboard_fab2(sch_1):vr_pvccin_cpu1_phase4';
NODE_NAME     EU1D1 10
 '@BASEBOARD_FAB2_LIB.BASEBOARD_FAB2(SCH_1):PAGE208_I71@MSTR_DISCRETE.IR354XX(CHIPS)':
 'SW': CDS_PINID='SW';
NODE_NAME     CT20 1
 '@BASEBOARD_FAB2_LIB.BASEBOARD_FAB2(SCH_1):PAGE208_I105@MSTR_DISCRETE.CAP(CHIPS)':
 'A': CDS_PINID='A';
NODE_NAME     L1D1 1
 '@BASEBOARD_FAB2_LIB.BASEBOARD_FAB2(SCH_1):PAGE208_I117@W_HDL.IND-120NH-30-GP(CHIPS)':
 'S': CDS_PINID='S';
NET_NAME
'VR_PVCCIN_CPU1_PHASE4_RC'
 '@BASEBOARD_FAB2_LIB.BASEBOARD_FAB2(SCH_1):VR_PVCCIN_CPU1_PHASE4_RC':
 C_SIGNAL='@baseboard_fab2_lib.baseboard_fab2(sch_1):vr_pvccin_cpu1_phase4_rc';
NODE_NAME     CT20 2
 '@BASEBOARD_FAB2_LIB.BASEBOARD_FAB2(SCH_1):PAGE208_I105@MSTR_DISCRETE.CAP(CHIPS)':
 'B': CDS_PINID='B';
NODE_NAME     RT13 1
 '@BASEBOARD_FAB2_LIB.BASEBOARD_FAB2(SCH_1):PAGE208_I121@W_HDL.1R3F-GP(CHIPS)':
 '1': CDS_PINID='\1\';
NET_NAME
'VR_PVCCIN_CPU1_PHASE5'
 '@BASEBOARD_FAB2_LIB.BASEBOARD_FAB2(SCH_1):VR_PVCCIN_CPU1_PHASE5':
 C_SIGNAL='@baseboard_fab2_lib.baseboard_fab2(sch_1):vr_pvccin_cpu1_phase5';
NODE_NAME     EU1C3 10
 '@BASEBOARD_FAB2_LIB.BASEBOARD_FAB2(SCH_1):PAGE209_I56@MSTR_DISCRETE.IR354XX(CHIPS)':
 'SW': CDS_PINID='SW';
NODE_NAME     CT14 1
 '@BASEBOARD_FAB2_LIB.BASEBOARD_FAB2(SCH_1):PAGE209_I73@MSTR_DISCRETE.CAP(CHIPS)':
 'A': CDS_PINID='A';
NODE_NAME     L1C2 1
 '@BASEBOARD_FAB2_LIB.BASEBOARD_FAB2(SCH_1):PAGE209_I80@W_HDL.IND-120NH-30-GP(CHIPS)':
 'S': CDS_PINID='S';
NET_NAME
'VR_PVCCIN_CPU1_PHASE5_RC'
 '@BASEBOARD_FAB2_LIB.BASEBOARD_FAB2(SCH_1):VR_PVCCIN_CPU1_PHASE5_RC':
 C_SIGNAL='@baseboard_fab2_lib.baseboard_fab2(sch_1):vr_pvccin_cpu1_phase5_rc';
NODE_NAME     CT14 2
 '@BASEBOARD_FAB2_LIB.BASEBOARD_FAB2(SCH_1):PAGE209_I73@MSTR_DISCRETE.CAP(CHIPS)':
 'B': CDS_PINID='B';
NODE_NAME     RT10 1
 '@BASEBOARD_FAB2_LIB.BASEBOARD_FAB2(SCH_1):PAGE209_I90@W_HDL.1R3F-GP(CHIPS)':
 '1': CDS_PINID='\1\';
NET_NAME
'VR_PVCCIN_CPU1_PWM1'
 '@BASEBOARD_FAB2_LIB.BASEBOARD_FAB2(SCH_1):VR_PVCCIN_CPU1_PWM1':
 C_SIGNAL='@baseboard_fab2_lib.baseboard_fab2(sch_1):vr_pvccin_cpu1_pwm1';
NODE_NAME     EU1C2 7
 '@BASEBOARD_FAB2_LIB.BASEBOARD_FAB2(SCH_1):PAGE206_I130@MSTR_CONTROLLER.PXE1610B(CHIPS)':
 'APWM1': CDS_PINID='APWM1';
NODE_NAME     EU1E2 34
 '@BASEBOARD_FAB2_LIB.BASEBOARD_FAB2(SCH_1):PAGE207_I20@MSTR_DISCRETE.IR354XX(CHIPS)':
 'PWM': CDS_PINID='PWM';
NET_NAME
'VR_PVCCIN_CPU1_PWM2'
 '@BASEBOARD_FAB2_LIB.BASEBOARD_FAB2(SCH_1):VR_PVCCIN_CPU1_PWM2':
 C_SIGNAL='@baseboard_fab2_lib.baseboard_fab2(sch_1):vr_pvccin_cpu1_pwm2';
NODE_NAME     EU1C2 6
 '@BASEBOARD_FAB2_LIB.BASEBOARD_FAB2(SCH_1):PAGE206_I130@MSTR_CONTROLLER.PXE1610B(CHIPS)':
 'APWM2': CDS_PINID='APWM2';
NODE_NAME     EU1D4 34
 '@BASEBOARD_FAB2_LIB.BASEBOARD_FAB2(SCH_1):PAGE207_I113@MSTR_DISCRETE.IR354XX(CHIPS)':
 'PWM': CDS_PINID='PWM';
NET_NAME
'VR_PVCCIN_CPU1_PWM3'
 '@BASEBOARD_FAB2_LIB.BASEBOARD_FAB2(SCH_1):VR_PVCCIN_CPU1_PWM3':
 C_SIGNAL='@baseboard_fab2_lib.baseboard_fab2(sch_1):vr_pvccin_cpu1_pwm3';
NODE_NAME     EU1C2 5
 '@BASEBOARD_FAB2_LIB.BASEBOARD_FAB2(SCH_1):PAGE206_I130@MSTR_CONTROLLER.PXE1610B(CHIPS)':
 'APWM3': CDS_PINID='APWM3';
NODE_NAME     EU1D3 34
 '@BASEBOARD_FAB2_LIB.BASEBOARD_FAB2(SCH_1):PAGE208_I27@MSTR_DISCRETE.IR354XX(CHIPS)':
 'PWM': CDS_PINID='PWM';
NET_NAME
'VR_PVCCIN_CPU1_PWM4'
 '@BASEBOARD_FAB2_LIB.BASEBOARD_FAB2(SCH_1):VR_PVCCIN_CPU1_PWM4':
 C_SIGNAL='@baseboard_fab2_lib.baseboard_fab2(sch_1):vr_pvccin_cpu1_pwm4';
NODE_NAME     EU1C2 4
 '@BASEBOARD_FAB2_LIB.BASEBOARD_FAB2(SCH_1):PAGE206_I130@MSTR_CONTROLLER.PXE1610B(CHIPS)':
 'APWM4': CDS_PINID='APWM4';
NODE_NAME     EU1D1 34
 '@BASEBOARD_FAB2_LIB.BASEBOARD_FAB2(SCH_1):PAGE208_I71@MSTR_DISCRETE.IR354XX(CHIPS)':
 'PWM': CDS_PINID='PWM';
NET_NAME
'VR_PVCCIN_CPU1_PWM5'
 '@BASEBOARD_FAB2_LIB.BASEBOARD_FAB2(SCH_1):VR_PVCCIN_CPU1_PWM5':
 C_SIGNAL='@baseboard_fab2_lib.baseboard_fab2(sch_1):vr_pvccin_cpu1_pwm5';
NODE_NAME     EU1C2 3
 '@BASEBOARD_FAB2_LIB.BASEBOARD_FAB2(SCH_1):PAGE206_I130@MSTR_CONTROLLER.PXE1610B(CHIPS)':
 'APWM5': CDS_PINID='APWM5';
NODE_NAME     EU1C3 34
 '@BASEBOARD_FAB2_LIB.BASEBOARD_FAB2(SCH_1):PAGE209_I56@MSTR_DISCRETE.IR354XX(CHIPS)':
 'PWM': CDS_PINID='PWM';
NET_NAME
'VR_PVCCIN_CPU1_VD12'
 '@BASEBOARD_FAB2_LIB.BASEBOARD_FAB2(SCH_1):VR_PVCCIN_CPU1_VD12':
 C_SIGNAL='@baseboard_fab2_lib.baseboard_fab2(sch_1):vr_pvccin_cpu1_vd12';
NODE_NAME     C1C13 1
 '@BASEBOARD_FAB2_LIB.BASEBOARD_FAB2(SCH_1):PAGE206_I29@DEV_DISCRETE.CAP_A(CHIPS)':
 'A': CDS_PINID='A';
NODE_NAME     C1C14 1
 '@BASEBOARD_FAB2_LIB.BASEBOARD_FAB2(SCH_1):PAGE206_I31@DEV_DISCRETE.CAP_A(CHIPS)':
 'A': CDS_PINID='A';
NODE_NAME     EU1C2 48
 '@BASEBOARD_FAB2_LIB.BASEBOARD_FAB2(SCH_1):PAGE206_I130@MSTR_CONTROLLER.PXE1610B(CHIPS)':
 'VD12': CDS_PINID='VD12';
NET_NAME
'VR_PVCCIN_CPU1_VDD'
 '@BASEBOARD_FAB2_LIB.BASEBOARD_FAB2(SCH_1):VR_PVCCIN_CPU1_VDD':
 C_SIGNAL='@baseboard_fab2_lib.baseboard_fab2(sch_1):vr_pvccin_cpu1_vdd';
NODE_NAME     C1C7 1
 '@BASEBOARD_FAB2_LIB.BASEBOARD_FAB2(SCH_1):PAGE206_I41@DEV_DISCRETE.CAP_A(CHIPS)':
 'A': CDS_PINID='A';
NODE_NAME     C1C9 1
 '@BASEBOARD_FAB2_LIB.BASEBOARD_FAB2(SCH_1):PAGE206_I42@DEV_DISCRETE.CAP_A(CHIPS)':
 'A': CDS_PINID='A';
NODE_NAME     R1C14 2
 '@BASEBOARD_FAB2_LIB.BASEBOARD_FAB2(SCH_1):PAGE206_I46@MSTR_DISCRETE.RES(CHIPS)':
 'B': CDS_PINID='B';
NODE_NAME     EU1C2 47
 '@BASEBOARD_FAB2_LIB.BASEBOARD_FAB2(SCH_1):PAGE206_I130@MSTR_CONTROLLER.PXE1610B(CHIPS)':
 'VDD': CDS_PINID='VDD';
NET_NAME
'VR_PVCCIN_CPU1_VREN'
 '@BASEBOARD_FAB2_LIB.BASEBOARD_FAB2(SCH_1):VR_PVCCIN_CPU1_VREN':
 C_SIGNAL='@baseboard_fab2_lib.baseboard_fab2(sch_1):vr_pvccin_cpu1_vren';
NODE_NAME     R9N16 2
 '@BASEBOARD_FAB2_LIB.BASEBOARD_FAB2(SCH_1):PAGE206_I119@MSTR_DISCRETE.RES(CHIPS)':
 'B': CDS_PINID='B';
NODE_NAME     R9N14 2
 '@BASEBOARD_FAB2_LIB.BASEBOARD_FAB2(SCH_1):PAGE206_I120@MSTR_DISCRETE.RES(CHIPS)':
 'B': CDS_PINID='B';
NODE_NAME     EU1C2 12
 '@BASEBOARD_FAB2_LIB.BASEBOARD_FAB2(SCH_1):PAGE206_I130@MSTR_CONTROLLER.PXE1610B(CHIPS)':
 'AVREN': CDS_PINID='AVREN';
NET_NAME
'VR_PVCCIN_CPU1_XADDR1'
 '@BASEBOARD_FAB2_LIB.BASEBOARD_FAB2(SCH_1):VR_PVCCIN_CPU1_XADDR1':
 C_SIGNAL='@baseboard_fab2_lib.baseboard_fab2(sch_1):vr_pvccin_cpu1_xaddr1';
NODE_NAME     R9N8 1
 '@BASEBOARD_FAB2_LIB.BASEBOARD_FAB2(SCH_1):PAGE206_I112@MSTR_DISCRETE.RES(CHIPS)':
 'A': CDS_PINID='A';
NODE_NAME     EU1C2 44
 '@BASEBOARD_FAB2_LIB.BASEBOARD_FAB2(SCH_1):PAGE206_I130@MSTR_CONTROLLER.PXE1610B(CHIPS)':
 'XADDR1': CDS_PINID='XADDR1';
NET_NAME
'VR_PVCCIN_CPU1_XADDR2'
 '@BASEBOARD_FAB2_LIB.BASEBOARD_FAB2(SCH_1):VR_PVCCIN_CPU1_XADDR2':
 C_SIGNAL='@baseboard_fab2_lib.baseboard_fab2(sch_1):vr_pvccin_cpu1_xaddr2';
NODE_NAME     R9N7 1
 '@BASEBOARD_FAB2_LIB.BASEBOARD_FAB2(SCH_1):PAGE206_I111@MSTR_DISCRETE.RES(CHIPS)':
 'A': CDS_PINID='A';
NODE_NAME     EU1C2 41
 '@BASEBOARD_FAB2_LIB.BASEBOARD_FAB2(SCH_1):PAGE206_I130@MSTR_CONTROLLER.PXE1610B(CHIPS)':
 'XADDR2': CDS_PINID='XADDR2';
NET_NAME
'VR_PVCCIOMCP_CPU0_XADDR1'
 '@BASEBOARD_FAB2_LIB.BASEBOARD_FAB2(SCH_1):VR_PVCCIOMCP_CPU0_XADDR1':
 C_SIGNAL='@baseboard_fab2_lib.baseboard_fab2(sch_1):vr_pvcciomcp_cpu0_xaddr1';
NODE_NAME     J6B1 E10
 '@BASEBOARD_FAB2_LIB.BASEBOARD_FAB2(SCH_1):PAGE194_I56@MSTR_SCONN.SCONN120_H61426002(CHIPS)':
 'IOE10': CDS_PINID='IOE10';
NODE_NAME     R3N29 1
 '@BASEBOARD_FAB2_LIB.BASEBOARD_FAB2(SCH_1):PAGE194_I156@MSTR_DISCRETE.RES(CHIPS)':
 'A': CDS_PINID='A';
NET_NAME
'VR_PVCCIOMCP_CPU1_XADDR1'
 '@BASEBOARD_FAB2_LIB.BASEBOARD_FAB2(SCH_1):VR_PVCCIOMCP_CPU1_XADDR1':
 C_SIGNAL='@baseboard_fab2_lib.baseboard_fab2(sch_1):vr_pvcciomcp_cpu1_xaddr1';
NODE_NAME     J4B2 E10
 '@BASEBOARD_FAB2_LIB.BASEBOARD_FAB2(SCH_1):PAGE193_I46@MSTR_SCONN.SCONN120_H61426002(CHIPS)':
 'IOE10': CDS_PINID='IOE10';
NODE_NAME     R4C12 1
 '@BASEBOARD_FAB2_LIB.BASEBOARD_FAB2(SCH_1):PAGE193_I169@MSTR_DISCRETE.RES(CHIPS)':
 'A': CDS_PINID='A';
NET_NAME
'VR_PVCCIO_CPU0_AIREF1'
 '@BASEBOARD_FAB2_LIB.BASEBOARD_FAB2(SCH_1):VR_PVCCIO_CPU0_AIREF1':
 C_SIGNAL='@baseboard_fab2_lib.baseboard_fab2(sch_1):vr_pvccio_cpu0_airef1';
NODE_NAME     EU3P1 21
 '@BASEBOARD_FAB2_LIB.BASEBOARD_FAB2(SCH_1):PAGE211_I93@MSTR_CONTROLLER.PXE1110B(CHIPS)':
 'AIREF1': CDS_PINID='AIREF1';
NODE_NAME     EU7C1 39
 '@BASEBOARD_FAB2_LIB.BASEBOARD_FAB2(SCH_1):PAGE212_I101@MSTR_DISCRETE.IR354XX(CHIPS)':
 'REFIN': CDS_PINID='REFIN';
NODE_NAME     CT70 1
 '@BASEBOARD_FAB2_LIB.BASEBOARD_FAB2(SCH_1):PAGE212_I106@DEV_DISCRETE.CAP_A(CHIPS)':
 'A': CDS_PINID='A';
NODE_NAME     CF13 1
 '@BASEBOARD_FAB2_LIB.BASEBOARD_FAB2(SCH_1):PAGE211_I95@W_HDL.SC22P50V2JN-4GP(CHIPS)':
 '1': CDS_PINID='\1\';
NODE_NAME     RF13 1
 '@BASEBOARD_FAB2_LIB.BASEBOARD_FAB2(SCH_1):PAGE211_I96@MSTR_DISCRETE.RES(CHIPS)':
 'A': CDS_PINID='A';
NET_NAME
'VR_PVCCIO_CPU0_AVSP'
 '@BASEBOARD_FAB2_LIB.BASEBOARD_FAB2(SCH_1):VR_PVCCIO_CPU0_AVSP':
 C_SIGNAL='@baseboard_fab2_lib.baseboard_fab2(sch_1):vr_pvccio_cpu0_avsp';
NODE_NAME     R3N19 2
 '@BASEBOARD_FAB2_LIB.BASEBOARD_FAB2(SCH_1):PAGE211_I81@MSTR_DISCRETE.RES(CHIPS)':
 'B': CDS_PINID='B';
NODE_NAME     C3N39 1
 '@BASEBOARD_FAB2_LIB.BASEBOARD_FAB2(SCH_1):PAGE211_I83@MSTR_DISCRETE.CAP(CHIPS)':
 'A': CDS_PINID='A';
NODE_NAME     EU3P1 19
 '@BASEBOARD_FAB2_LIB.BASEBOARD_FAB2(SCH_1):PAGE211_I93@MSTR_CONTROLLER.PXE1110B(CHIPS)':
 'AVSEN': CDS_PINID='AVSEN';
NET_NAME
'VR_PVCCIO_CPU0_EN'
 '@BASEBOARD_FAB2_LIB.BASEBOARD_FAB2(SCH_1):VR_PVCCIO_CPU0_EN':
 C_SIGNAL='@baseboard_fab2_lib.baseboard_fab2(sch_1):vr_pvccio_cpu0_en';
NODE_NAME     R3P26 2
 '@BASEBOARD_FAB2_LIB.BASEBOARD_FAB2(SCH_1):PAGE211_I87@MSTR_DISCRETE.RES(CHIPS)':
 'B': CDS_PINID='B';
NODE_NAME     R3P21 2
 '@BASEBOARD_FAB2_LIB.BASEBOARD_FAB2(SCH_1):PAGE211_I88@MSTR_DISCRETE.RES(CHIPS)':
 'B': CDS_PINID='B';
NODE_NAME     EU3P1 10
 '@BASEBOARD_FAB2_LIB.BASEBOARD_FAB2(SCH_1):PAGE211_I93@MSTR_CONTROLLER.PXE1110B(CHIPS)':
 'AVREN': CDS_PINID='AVREN';
NET_NAME
'VR_PVCCIO_CPU0_OCSET'
 '@BASEBOARD_FAB2_LIB.BASEBOARD_FAB2(SCH_1):VR_PVCCIO_CPU0_OCSET':
 C_SIGNAL='@baseboard_fab2_lib.baseboard_fab2(sch_1):vr_pvccio_cpu0_ocset';
NODE_NAME     EU7C1 37
 '@BASEBOARD_FAB2_LIB.BASEBOARD_FAB2(SCH_1):PAGE212_I101@MSTR_DISCRETE.IR354XX(CHIPS)':
 'OCSET': CDS_PINID='OCSET';
NODE_NAME     R7C25 1
 '@BASEBOARD_FAB2_LIB.BASEBOARD_FAB2(SCH_1):PAGE212_I103@MSTR_DISCRETE.RES(CHIPS)':
 'A': CDS_PINID='A';
NET_NAME
'VR_PVCCIO_CPU0_PH1_BOOT'
 '@BASEBOARD_FAB2_LIB.BASEBOARD_FAB2(SCH_1):VR_PVCCIO_CPU0_PH1_BOOT':
 C_SIGNAL='@baseboard_fab2_lib.baseboard_fab2(sch_1):vr_pvccio_cpu0_ph1_boot';
NODE_NAME     C7C14 1
 '@BASEBOARD_FAB2_LIB.BASEBOARD_FAB2(SCH_1):PAGE212_I37@MSTR_DISCRETE.CAP(CHIPS)':
 'A': CDS_PINID='A';
NODE_NAME     RT47 1
 '@BASEBOARD_FAB2_LIB.BASEBOARD_FAB2(SCH_1):PAGE212_I120@MSTR_DISCRETE.RES(CHIPS)':
 'A': CDS_PINID='A';
NET_NAME
'VR_PVCCIO_CPU0_PH1_BOOT_R'
 '@BASEBOARD_FAB2_LIB.BASEBOARD_FAB2(SCH_1):VR_PVCCIO_CPU0_PH1_BOOT_R':
 C_SIGNAL='@baseboard_fab2_lib.baseboard_fab2(sch_1):vr_pvccio_cpu0_ph1_boot_r';
NODE_NAME     EU7C1 33
 '@BASEBOARD_FAB2_LIB.BASEBOARD_FAB2(SCH_1):PAGE212_I101@MSTR_DISCRETE.IR354XX(CHIPS)':
 'BOOST': CDS_PINID='BOOST';
NODE_NAME     RT47 2
 '@BASEBOARD_FAB2_LIB.BASEBOARD_FAB2(SCH_1):PAGE212_I120@MSTR_DISCRETE.RES(CHIPS)':
 'B': CDS_PINID='B';
NET_NAME
'VR_PVCCIO_CPU0_PH1_PHASE'
 '@BASEBOARD_FAB2_LIB.BASEBOARD_FAB2(SCH_1):VR_PVCCIO_CPU0_PH1_PHASE':
 C_SIGNAL='@baseboard_fab2_lib.baseboard_fab2(sch_1):vr_pvccio_cpu0_ph1_phase';
NODE_NAME     C7C14 2
 '@BASEBOARD_FAB2_LIB.BASEBOARD_FAB2(SCH_1):PAGE212_I37@MSTR_DISCRETE.CAP(CHIPS)':
 'B': CDS_PINID='B';
NODE_NAME     EU7C1 32
 '@BASEBOARD_FAB2_LIB.BASEBOARD_FAB2(SCH_1):PAGE212_I101@MSTR_DISCRETE.IR354XX(CHIPS)':
 'PHASE': CDS_PINID='PHASE';
NET_NAME
'VR_PVCCIO_CPU0_PH1_SW'
 '@BASEBOARD_FAB2_LIB.BASEBOARD_FAB2(SCH_1):VR_PVCCIO_CPU0_PH1_SW':
 C_SIGNAL='@baseboard_fab2_lib.baseboard_fab2(sch_1):vr_pvccio_cpu0_ph1_sw';
NODE_NAME     EU7C1 10
 '@BASEBOARD_FAB2_LIB.BASEBOARD_FAB2(SCH_1):PAGE212_I101@MSTR_DISCRETE.IR354XX(CHIPS)':
 'SW': CDS_PINID='SW';
NODE_NAME     CT72 1
 '@BASEBOARD_FAB2_LIB.BASEBOARD_FAB2(SCH_1):PAGE212_I118@MSTR_DISCRETE.CAP(CHIPS)':
 'A': CDS_PINID='A';
NODE_NAME     L7C2 1
 '@BASEBOARD_FAB2_LIB.BASEBOARD_FAB2(SCH_1):PAGE212_I141@W_HDL.IND-150NH-56-GP(CHIPS)':
 'S': CDS_PINID='S';
NET_NAME
'VR_PVCCIO_CPU0_PH1_SW_RC'
 '@BASEBOARD_FAB2_LIB.BASEBOARD_FAB2(SCH_1):VR_PVCCIO_CPU0_PH1_SW_RC':
 C_SIGNAL='@baseboard_fab2_lib.baseboard_fab2(sch_1):vr_pvccio_cpu0_ph1_sw_rc';
NODE_NAME     CT72 2
 '@BASEBOARD_FAB2_LIB.BASEBOARD_FAB2(SCH_1):PAGE212_I118@MSTR_DISCRETE.CAP(CHIPS)':
 'B': CDS_PINID='B';
NODE_NAME     RT48 1
 '@BASEBOARD_FAB2_LIB.BASEBOARD_FAB2(SCH_1):PAGE212_I144@W_HDL.1R3F-GP(CHIPS)':
 '1': CDS_PINID='\1\';
NET_NAME
'VR_PVCCIO_CPU0_PH1_VCIN'
 '@BASEBOARD_FAB2_LIB.BASEBOARD_FAB2(SCH_1):VR_PVCCIO_CPU0_PH1_VCIN':
 C_SIGNAL='@baseboard_fab2_lib.baseboard_fab2(sch_1):vr_pvccio_cpu0_ph1_vcin';
NODE_NAME     C7C17 1
 '@BASEBOARD_FAB2_LIB.BASEBOARD_FAB2(SCH_1):PAGE212_I36@MSTR_DISCRETE.CAP(CHIPS)':
 'A': CDS_PINID='A';
NODE_NAME     EU7C1 3
 '@BASEBOARD_FAB2_LIB.BASEBOARD_FAB2(SCH_1):PAGE212_I101@MSTR_DISCRETE.IR354XX(CHIPS)':
 'VCC': CDS_PINID='VCC';
NODE_NAME     R3N7 1
 '@BASEBOARD_FAB2_LIB.BASEBOARD_FAB2(SCH_1):PAGE212_I140@MSTR_DISCRETE.RES(CHIPS)':
 'A': CDS_PINID='A';
NET_NAME
'VR_PVCCIO_CPU0_PWM1'
 '@BASEBOARD_FAB2_LIB.BASEBOARD_FAB2(SCH_1):VR_PVCCIO_CPU0_PWM1':
 C_SIGNAL='@baseboard_fab2_lib.baseboard_fab2(sch_1):vr_pvccio_cpu0_pwm1';
NODE_NAME     EU3P1 5
 '@BASEBOARD_FAB2_LIB.BASEBOARD_FAB2(SCH_1):PAGE211_I93@MSTR_CONTROLLER.PXE1110B(CHIPS)':
 'APWM1': CDS_PINID='APWM1';
NODE_NAME     EU7C1 34
 '@BASEBOARD_FAB2_LIB.BASEBOARD_FAB2(SCH_1):PAGE212_I101@MSTR_DISCRETE.IR354XX(CHIPS)':
 'PWM': CDS_PINID='PWM';
NET_NAME
'VR_PVCCIO_CPU0_VD12'
 '@BASEBOARD_FAB2_LIB.BASEBOARD_FAB2(SCH_1):VR_PVCCIO_CPU0_VD12':
 C_SIGNAL='@baseboard_fab2_lib.baseboard_fab2(sch_1):vr_pvccio_cpu0_vd12';
NODE_NAME     C3P4 1
 '@BASEBOARD_FAB2_LIB.BASEBOARD_FAB2(SCH_1):PAGE211_I11@DEV_DISCRETE.CAP_A(CHIPS)':
 'A': CDS_PINID='A';
NODE_NAME     C3P5 1
 '@BASEBOARD_FAB2_LIB.BASEBOARD_FAB2(SCH_1):PAGE211_I13@DEV_DISCRETE.CAP_A(CHIPS)':
 'A': CDS_PINID='A';
NODE_NAME     EU3P1 40
 '@BASEBOARD_FAB2_LIB.BASEBOARD_FAB2(SCH_1):PAGE211_I93@MSTR_CONTROLLER.PXE1110B(CHIPS)':
 'VD12': CDS_PINID='VD12';
NET_NAME
'VR_PVCCIO_CPU0_VDD'
 '@BASEBOARD_FAB2_LIB.BASEBOARD_FAB2(SCH_1):VR_PVCCIO_CPU0_VDD':
 C_SIGNAL='@baseboard_fab2_lib.baseboard_fab2(sch_1):vr_pvccio_cpu0_vdd';
NODE_NAME     C3P3 1
 '@BASEBOARD_FAB2_LIB.BASEBOARD_FAB2(SCH_1):PAGE211_I20@DEV_DISCRETE.CAP_A(CHIPS)':
 'A': CDS_PINID='A';
NODE_NAME     C3P7 1
 '@BASEBOARD_FAB2_LIB.BASEBOARD_FAB2(SCH_1):PAGE211_I22@DEV_DISCRETE.CAP_A(CHIPS)':
 'A': CDS_PINID='A';
NODE_NAME     R3P22 2
 '@BASEBOARD_FAB2_LIB.BASEBOARD_FAB2(SCH_1):PAGE211_I24@MSTR_DISCRETE.RES(CHIPS)':
 'B': CDS_PINID='B';
NODE_NAME     EU3P1 39
 '@BASEBOARD_FAB2_LIB.BASEBOARD_FAB2(SCH_1):PAGE211_I93@MSTR_CONTROLLER.PXE1110B(CHIPS)':
 'VDD': CDS_PINID='VDD';
NET_NAME
'VR_PVCCIO_CPU0_VINSEN'
 '@BASEBOARD_FAB2_LIB.BASEBOARD_FAB2(SCH_1):VR_PVCCIO_CPU0_VINSEN':
 C_SIGNAL='@baseboard_fab2_lib.baseboard_fab2(sch_1):vr_pvccio_cpu0_vinsen';
NODE_NAME     R3P12 2
 '@BASEBOARD_FAB2_LIB.BASEBOARD_FAB2(SCH_1):PAGE211_I31@MSTR_DISCRETE.RES(CHIPS)':
 'B': CDS_PINID='B';
NODE_NAME     R3P16 1
 '@BASEBOARD_FAB2_LIB.BASEBOARD_FAB2(SCH_1):PAGE211_I32@MSTR_DISCRETE.RES(CHIPS)':
 'A': CDS_PINID='A';
NODE_NAME     EU3P1 37
 '@BASEBOARD_FAB2_LIB.BASEBOARD_FAB2(SCH_1):PAGE211_I93@MSTR_CONTROLLER.PXE1110B(CHIPS)':
 'VINSEN': CDS_PINID='VINSEN';
NODE_NAME     C3P2 1
 '@BASEBOARD_FAB2_LIB.BASEBOARD_FAB2(SCH_1):PAGE211_I103@DEV_DISCRETE.CAP_A(CHIPS)':
 'A': CDS_PINID='A';
NET_NAME
'VR_PVCCIO_CPU0_XADDR1'
 '@BASEBOARD_FAB2_LIB.BASEBOARD_FAB2(SCH_1):VR_PVCCIO_CPU0_XADDR1':
 C_SIGNAL='@baseboard_fab2_lib.baseboard_fab2(sch_1):vr_pvccio_cpu0_xaddr1';
NODE_NAME     R3N31 1
 '@BASEBOARD_FAB2_LIB.BASEBOARD_FAB2(SCH_1):PAGE211_I52@MSTR_DISCRETE.RES(CHIPS)':
 'A': CDS_PINID='A';
NODE_NAME     EU3P1 36
 '@BASEBOARD_FAB2_LIB.BASEBOARD_FAB2(SCH_1):PAGE211_I93@MSTR_CONTROLLER.PXE1110B(CHIPS)':
 'XADDR1': CDS_PINID='XADDR1';
NET_NAME
'VR_PVCCIO_CPU0_XADDR2'
 '@BASEBOARD_FAB2_LIB.BASEBOARD_FAB2(SCH_1):VR_PVCCIO_CPU0_XADDR2':
 C_SIGNAL='@baseboard_fab2_lib.baseboard_fab2(sch_1):vr_pvccio_cpu0_xaddr2';
NODE_NAME     EU3P1 33
 '@BASEBOARD_FAB2_LIB.BASEBOARD_FAB2(SCH_1):PAGE211_I93@MSTR_CONTROLLER.PXE1110B(CHIPS)':
 'XADDR2': CDS_PINID='XADDR2';
NODE_NAME     R3N22 1
 '@BASEBOARD_FAB2_LIB.BASEBOARD_FAB2(SCH_1):PAGE211_I102@MSTR_DISCRETE.RES(CHIPS)':
 'A': CDS_PINID='A';
NET_NAME
'VR_PVCCIO_CPU1_AIREF1'
 '@BASEBOARD_FAB2_LIB.BASEBOARD_FAB2(SCH_1):VR_PVCCIO_CPU1_AIREF1':
 C_SIGNAL='@baseboard_fab2_lib.baseboard_fab2(sch_1):vr_pvccio_cpu1_airef1';
NODE_NAME     EU4D5 21
 '@BASEBOARD_FAB2_LIB.BASEBOARD_FAB2(SCH_1):PAGE213_I96@MSTR_CONTROLLER.PXE1110B(CHIPS)':
 'AIREF1': CDS_PINID='AIREF1';
NODE_NAME     EU4E2 39
 '@BASEBOARD_FAB2_LIB.BASEBOARD_FAB2(SCH_1):PAGE214_I126@MSTR_DISCRETE.IR354XX(CHIPS)':
 'REFIN': CDS_PINID='REFIN';
NODE_NAME     CT63 1
 '@BASEBOARD_FAB2_LIB.BASEBOARD_FAB2(SCH_1):PAGE214_I137@DEV_DISCRETE.CAP_A(CHIPS)':
 'A': CDS_PINID='A';
NODE_NAME     CF14 1
 '@BASEBOARD_FAB2_LIB.BASEBOARD_FAB2(SCH_1):PAGE213_I98@W_HDL.SC22P50V2JN-4GP(CHIPS)':
 '1': CDS_PINID='\1\';
NODE_NAME     RF14 1
 '@BASEBOARD_FAB2_LIB.BASEBOARD_FAB2(SCH_1):PAGE213_I99@MSTR_DISCRETE.RES(CHIPS)':
 'A': CDS_PINID='A';
NET_NAME
'VR_PVCCIO_CPU1_AVSP'
 '@BASEBOARD_FAB2_LIB.BASEBOARD_FAB2(SCH_1):VR_PVCCIO_CPU1_AVSP':
 C_SIGNAL='@baseboard_fab2_lib.baseboard_fab2(sch_1):vr_pvccio_cpu1_avsp';
NODE_NAME     C4D44 1
 '@BASEBOARD_FAB2_LIB.BASEBOARD_FAB2(SCH_1):PAGE213_I83@MSTR_DISCRETE.CAP(CHIPS)':
 'A': CDS_PINID='A';
NODE_NAME     R4E7 2
 '@BASEBOARD_FAB2_LIB.BASEBOARD_FAB2(SCH_1):PAGE213_I84@MSTR_DISCRETE.RES(CHIPS)':
 'B': CDS_PINID='B';
NODE_NAME     EU4D5 19
 '@BASEBOARD_FAB2_LIB.BASEBOARD_FAB2(SCH_1):PAGE213_I96@MSTR_CONTROLLER.PXE1110B(CHIPS)':
 'AVSEN': CDS_PINID='AVSEN';
NET_NAME
'VR_PVCCIO_CPU1_EN'
 '@BASEBOARD_FAB2_LIB.BASEBOARD_FAB2(SCH_1):VR_PVCCIO_CPU1_EN':
 C_SIGNAL='@baseboard_fab2_lib.baseboard_fab2(sch_1):vr_pvccio_cpu1_en';
NODE_NAME     R6P41 2
 '@BASEBOARD_FAB2_LIB.BASEBOARD_FAB2(SCH_1):PAGE213_I90@MSTR_DISCRETE.RES(CHIPS)':
 'B': CDS_PINID='B';
NODE_NAME     R6P40 2
 '@BASEBOARD_FAB2_LIB.BASEBOARD_FAB2(SCH_1):PAGE213_I91@MSTR_DISCRETE.RES(CHIPS)':
 'B': CDS_PINID='B';
NODE_NAME     EU4D5 10
 '@BASEBOARD_FAB2_LIB.BASEBOARD_FAB2(SCH_1):PAGE213_I96@MSTR_CONTROLLER.PXE1110B(CHIPS)':
 'AVREN': CDS_PINID='AVREN';
NET_NAME
'VR_PVCCIO_CPU1_OCSET'
 '@BASEBOARD_FAB2_LIB.BASEBOARD_FAB2(SCH_1):VR_PVCCIO_CPU1_OCSET':
 C_SIGNAL='@baseboard_fab2_lib.baseboard_fab2(sch_1):vr_pvccio_cpu1_ocset';
NODE_NAME     EU4E2 37
 '@BASEBOARD_FAB2_LIB.BASEBOARD_FAB2(SCH_1):PAGE214_I126@MSTR_DISCRETE.IR354XX(CHIPS)':
 'OCSET': CDS_PINID='OCSET';
NODE_NAME     R4E21 1
 '@BASEBOARD_FAB2_LIB.BASEBOARD_FAB2(SCH_1):PAGE214_I127@MSTR_DISCRETE.RES(CHIPS)':
 'A': CDS_PINID='A';
NET_NAME
'VR_PVCCIO_CPU1_PH1_BOOT'
 '@BASEBOARD_FAB2_LIB.BASEBOARD_FAB2(SCH_1):VR_PVCCIO_CPU1_PH1_BOOT':
 C_SIGNAL='@baseboard_fab2_lib.baseboard_fab2(sch_1):vr_pvccio_cpu1_ph1_boot';
NODE_NAME     C4E18 1
 '@BASEBOARD_FAB2_LIB.BASEBOARD_FAB2(SCH_1):PAGE214_I78@MSTR_DISCRETE.CAP(CHIPS)':
 'A': CDS_PINID='A';
NODE_NAME     RT41 1
 '@BASEBOARD_FAB2_LIB.BASEBOARD_FAB2(SCH_1):PAGE214_I145@MSTR_DISCRETE.RES(CHIPS)':
 'A': CDS_PINID='A';
NET_NAME
'VR_PVCCIO_CPU1_PH1_BOOT_R'
 '@BASEBOARD_FAB2_LIB.BASEBOARD_FAB2(SCH_1):VR_PVCCIO_CPU1_PH1_BOOT_R':
 C_SIGNAL='@baseboard_fab2_lib.baseboard_fab2(sch_1):vr_pvccio_cpu1_ph1_boot_r';
NODE_NAME     EU4E2 33
 '@BASEBOARD_FAB2_LIB.BASEBOARD_FAB2(SCH_1):PAGE214_I126@MSTR_DISCRETE.IR354XX(CHIPS)':
 'BOOST': CDS_PINID='BOOST';
NODE_NAME     RT41 2
 '@BASEBOARD_FAB2_LIB.BASEBOARD_FAB2(SCH_1):PAGE214_I145@MSTR_DISCRETE.RES(CHIPS)':
 'B': CDS_PINID='B';
NET_NAME
'VR_PVCCIO_CPU1_PH1_PHASE'
 '@BASEBOARD_FAB2_LIB.BASEBOARD_FAB2(SCH_1):VR_PVCCIO_CPU1_PH1_PHASE':
 C_SIGNAL='@baseboard_fab2_lib.baseboard_fab2(sch_1):vr_pvccio_cpu1_ph1_phase';
NODE_NAME     C4E18 2
 '@BASEBOARD_FAB2_LIB.BASEBOARD_FAB2(SCH_1):PAGE214_I78@MSTR_DISCRETE.CAP(CHIPS)':
 'B': CDS_PINID='B';
NODE_NAME     EU4E2 32
 '@BASEBOARD_FAB2_LIB.BASEBOARD_FAB2(SCH_1):PAGE214_I126@MSTR_DISCRETE.IR354XX(CHIPS)':
 'PHASE': CDS_PINID='PHASE';
NET_NAME
'VR_PVCCIO_CPU1_PH1_SW'
 '@BASEBOARD_FAB2_LIB.BASEBOARD_FAB2(SCH_1):VR_PVCCIO_CPU1_PH1_SW':
 C_SIGNAL='@baseboard_fab2_lib.baseboard_fab2(sch_1):vr_pvccio_cpu1_ph1_sw';
NODE_NAME     EU4E2 10
 '@BASEBOARD_FAB2_LIB.BASEBOARD_FAB2(SCH_1):PAGE214_I126@MSTR_DISCRETE.IR354XX(CHIPS)':
 'SW': CDS_PINID='SW';
NODE_NAME     CT62 1
 '@BASEBOARD_FAB2_LIB.BASEBOARD_FAB2(SCH_1):PAGE214_I143@MSTR_DISCRETE.CAP(CHIPS)':
 'A': CDS_PINID='A';
NODE_NAME     L4E2 1
 '@BASEBOARD_FAB2_LIB.BASEBOARD_FAB2(SCH_1):PAGE214_I174@W_HDL.IND-150NH-56-GP(CHIPS)':
 'S': CDS_PINID='S';
NET_NAME
'VR_PVCCIO_CPU1_PH1_SW_RC'
 '@BASEBOARD_FAB2_LIB.BASEBOARD_FAB2(SCH_1):VR_PVCCIO_CPU1_PH1_SW_RC':
 C_SIGNAL='@baseboard_fab2_lib.baseboard_fab2(sch_1):vr_pvccio_cpu1_ph1_sw_rc';
NODE_NAME     CT62 2
 '@BASEBOARD_FAB2_LIB.BASEBOARD_FAB2(SCH_1):PAGE214_I143@MSTR_DISCRETE.CAP(CHIPS)':
 'B': CDS_PINID='B';
NODE_NAME     RT42 1
 '@BASEBOARD_FAB2_LIB.BASEBOARD_FAB2(SCH_1):PAGE214_I176@W_HDL.1R3F-GP(CHIPS)':
 '1': CDS_PINID='\1\';
NET_NAME
'VR_PVCCIO_CPU1_PH1_VCIN'
 '@BASEBOARD_FAB2_LIB.BASEBOARD_FAB2(SCH_1):VR_PVCCIO_CPU1_PH1_VCIN':
 C_SIGNAL='@baseboard_fab2_lib.baseboard_fab2(sch_1):vr_pvccio_cpu1_ph1_vcin';
NODE_NAME     C4E22 1
 '@BASEBOARD_FAB2_LIB.BASEBOARD_FAB2(SCH_1):PAGE214_I76@MSTR_DISCRETE.CAP(CHIPS)':
 'A': CDS_PINID='A';
NODE_NAME     EU4E2 3
 '@BASEBOARD_FAB2_LIB.BASEBOARD_FAB2(SCH_1):PAGE214_I126@MSTR_DISCRETE.IR354XX(CHIPS)':
 'VCC': CDS_PINID='VCC';
NODE_NAME     R6R5 1
 '@BASEBOARD_FAB2_LIB.BASEBOARD_FAB2(SCH_1):PAGE214_I173@MSTR_DISCRETE.RES(CHIPS)':
 'A': CDS_PINID='A';
NET_NAME
'VR_PVCCIO_CPU1_PWM1'
 '@BASEBOARD_FAB2_LIB.BASEBOARD_FAB2(SCH_1):VR_PVCCIO_CPU1_PWM1':
 C_SIGNAL='@baseboard_fab2_lib.baseboard_fab2(sch_1):vr_pvccio_cpu1_pwm1';
NODE_NAME     EU4D5 5
 '@BASEBOARD_FAB2_LIB.BASEBOARD_FAB2(SCH_1):PAGE213_I96@MSTR_CONTROLLER.PXE1110B(CHIPS)':
 'APWM1': CDS_PINID='APWM1';
NODE_NAME     EU4E2 34
 '@BASEBOARD_FAB2_LIB.BASEBOARD_FAB2(SCH_1):PAGE214_I126@MSTR_DISCRETE.IR354XX(CHIPS)':
 'PWM': CDS_PINID='PWM';
NET_NAME
'VR_PVCCIO_CPU1_VD12'
 '@BASEBOARD_FAB2_LIB.BASEBOARD_FAB2(SCH_1):VR_PVCCIO_CPU1_VD12':
 C_SIGNAL='@baseboard_fab2_lib.baseboard_fab2(sch_1):vr_pvccio_cpu1_vd12';
NODE_NAME     C4D31 1
 '@BASEBOARD_FAB2_LIB.BASEBOARD_FAB2(SCH_1):PAGE213_I9@DEV_DISCRETE.CAP_A(CHIPS)':
 'A': CDS_PINID='A';
NODE_NAME     C4D32 1
 '@BASEBOARD_FAB2_LIB.BASEBOARD_FAB2(SCH_1):PAGE213_I11@DEV_DISCRETE.CAP_A(CHIPS)':
 'A': CDS_PINID='A';
NODE_NAME     EU4D5 40
 '@BASEBOARD_FAB2_LIB.BASEBOARD_FAB2(SCH_1):PAGE213_I96@MSTR_CONTROLLER.PXE1110B(CHIPS)':
 'VD12': CDS_PINID='VD12';
NET_NAME
'VR_PVCCIO_CPU1_VDD'
 '@BASEBOARD_FAB2_LIB.BASEBOARD_FAB2(SCH_1):VR_PVCCIO_CPU1_VDD':
 C_SIGNAL='@baseboard_fab2_lib.baseboard_fab2(sch_1):vr_pvccio_cpu1_vdd';
NODE_NAME     C4D36 1
 '@BASEBOARD_FAB2_LIB.BASEBOARD_FAB2(SCH_1):PAGE213_I17@DEV_DISCRETE.CAP_A(CHIPS)':
 'A': CDS_PINID='A';
NODE_NAME     R4D47 2
 '@BASEBOARD_FAB2_LIB.BASEBOARD_FAB2(SCH_1):PAGE213_I25@MSTR_DISCRETE.RES(CHIPS)':
 'B': CDS_PINID='B';
NODE_NAME     C4D38 1
 '@BASEBOARD_FAB2_LIB.BASEBOARD_FAB2(SCH_1):PAGE213_I35@DEV_DISCRETE.CAP_A(CHIPS)':
 'A': CDS_PINID='A';
NODE_NAME     EU4D5 39
 '@BASEBOARD_FAB2_LIB.BASEBOARD_FAB2(SCH_1):PAGE213_I96@MSTR_CONTROLLER.PXE1110B(CHIPS)':
 'VDD': CDS_PINID='VDD';
NET_NAME
'VR_PVCCIO_CPU1_VINSEN'
 '@BASEBOARD_FAB2_LIB.BASEBOARD_FAB2(SCH_1):VR_PVCCIO_CPU1_VINSEN':
 C_SIGNAL='@baseboard_fab2_lib.baseboard_fab2(sch_1):vr_pvccio_cpu1_vinsen';
NODE_NAME     R4D60 2
 '@BASEBOARD_FAB2_LIB.BASEBOARD_FAB2(SCH_1):PAGE213_I31@MSTR_DISCRETE.RES(CHIPS)':
 'B': CDS_PINID='B';
NODE_NAME     R4D57 1
 '@BASEBOARD_FAB2_LIB.BASEBOARD_FAB2(SCH_1):PAGE213_I32@MSTR_DISCRETE.RES(CHIPS)':
 'A': CDS_PINID='A';
NODE_NAME     EU4D5 37
 '@BASEBOARD_FAB2_LIB.BASEBOARD_FAB2(SCH_1):PAGE213_I96@MSTR_CONTROLLER.PXE1110B(CHIPS)':
 'VINSEN': CDS_PINID='VINSEN';
NODE_NAME     C4D40 1
 '@BASEBOARD_FAB2_LIB.BASEBOARD_FAB2(SCH_1):PAGE213_I105@DEV_DISCRETE.CAP_A(CHIPS)':
 'A': CDS_PINID='A';
NET_NAME
'VR_PVCCIO_CPU1_XADDR1'
 '@BASEBOARD_FAB2_LIB.BASEBOARD_FAB2(SCH_1):VR_PVCCIO_CPU1_XADDR1':
 C_SIGNAL='@baseboard_fab2_lib.baseboard_fab2(sch_1):vr_pvccio_cpu1_xaddr1';
NODE_NAME     EU4D5 36
 '@BASEBOARD_FAB2_LIB.BASEBOARD_FAB2(SCH_1):PAGE213_I96@MSTR_CONTROLLER.PXE1110B(CHIPS)':
 'XADDR1': CDS_PINID='XADDR1';
NODE_NAME     R4D64 1
 '@BASEBOARD_FAB2_LIB.BASEBOARD_FAB2(SCH_1):PAGE213_I104@MSTR_DISCRETE.RES(CHIPS)':
 'A': CDS_PINID='A';
NET_NAME
'VR_PVCCIO_CPU1_XADDR2'
 '@BASEBOARD_FAB2_LIB.BASEBOARD_FAB2(SCH_1):VR_PVCCIO_CPU1_XADDR2':
 C_SIGNAL='@baseboard_fab2_lib.baseboard_fab2(sch_1):vr_pvccio_cpu1_xaddr2';
NODE_NAME     EU4D5 33
 '@BASEBOARD_FAB2_LIB.BASEBOARD_FAB2(SCH_1):PAGE213_I96@MSTR_CONTROLLER.PXE1110B(CHIPS)':
 'XADDR2': CDS_PINID='XADDR2';
NODE_NAME     R4E2 1
 '@BASEBOARD_FAB2_LIB.BASEBOARD_FAB2(SCH_1):PAGE213_I103@MSTR_DISCRETE.RES(CHIPS)':
 'A': CDS_PINID='A';
NET_NAME
'VR_PVCCMCP_CPU0_XADDR2'
 '@BASEBOARD_FAB2_LIB.BASEBOARD_FAB2(SCH_1):VR_PVCCMCP_CPU0_XADDR2':
 C_SIGNAL='@baseboard_fab2_lib.baseboard_fab2(sch_1):vr_pvccmcp_cpu0_xaddr2';
NODE_NAME     J6B1 F10
 '@BASEBOARD_FAB2_LIB.BASEBOARD_FAB2(SCH_1):PAGE194_I56@MSTR_SCONN.SCONN120_H61426002(CHIPS)':
 'IOF10': CDS_PINID='IOF10';
NODE_NAME     R7C24 1
 '@BASEBOARD_FAB2_LIB.BASEBOARD_FAB2(SCH_1):PAGE194_I155@MSTR_DISCRETE.RES(CHIPS)':
 'A': CDS_PINID='A';
NET_NAME
'VR_PVCCMCP_CPU1_XADDR2'
 '@BASEBOARD_FAB2_LIB.BASEBOARD_FAB2(SCH_1):VR_PVCCMCP_CPU1_XADDR2':
 C_SIGNAL='@baseboard_fab2_lib.baseboard_fab2(sch_1):vr_pvccmcp_cpu1_xaddr2';
NODE_NAME     J4B2 F10
 '@BASEBOARD_FAB2_LIB.BASEBOARD_FAB2(SCH_1):PAGE193_I46@MSTR_SCONN.SCONN120_H61426002(CHIPS)':
 'IOF10': CDS_PINID='IOF10';
NODE_NAME     R4C11 1
 '@BASEBOARD_FAB2_LIB.BASEBOARD_FAB2(SCH_1):PAGE193_I170@MSTR_DISCRETE.RES(CHIPS)':
 'A': CDS_PINID='A';
NET_NAME
'VR_PVDDQ_ABC_AIINSEN'
 '@BASEBOARD_FAB2_LIB.BASEBOARD_FAB2(SCH_1):VR_PVDDQ_ABC_AIINSEN':
 C_SIGNAL='@baseboard_fab2_lib.baseboard_fab2(sch_1):vr_pvddq_abc_aiinsen';
NODE_NAME     EU7G1 38
 '@BASEBOARD_FAB2_LIB.BASEBOARD_FAB2(SCH_1):PAGE215_I69@MSTR_CONTROLLER.PXM1310B(CHIPS)':
 'IINSEN': CDS_PINID='IINSEN';
NODE_NAME     C12W1 1
 '@BASEBOARD_FAB2_LIB.BASEBOARD_FAB2(SCH_1):PAGE197_I8@MSTR_DISCRETE.CAP(CHIPS)':
 'A': CDS_PINID='A';
NODE_NAME     R12W1 2
 '@BASEBOARD_FAB2_LIB.BASEBOARD_FAB2(SCH_1):PAGE197_I101@W_HDL.665KR5B-1-GP(CHIPS)':
 '2': CDS_PINID='\2\';
NODE_NAME     R12W5 1
 '@BASEBOARD_FAB2_LIB.BASEBOARD_FAB2(SCH_1):PAGE197_I111@W_HDL.665KR2B-GP(CHIPS)':
 '1': CDS_PINID='\1\';
NET_NAME
'VR_PVDDQ_ABC_AIREF1'
 '@BASEBOARD_FAB2_LIB.BASEBOARD_FAB2(SCH_1):VR_PVDDQ_ABC_AIREF1':
 C_SIGNAL='@baseboard_fab2_lib.baseboard_fab2(sch_1):vr_pvddq_abc_airef1';
NODE_NAME     EU7G2 39
 '@BASEBOARD_FAB2_LIB.BASEBOARD_FAB2(SCH_1):PAGE216_I102@MSTR_DISCRETE.IR354XX(CHIPS)':
 'REFIN': CDS_PINID='REFIN';
NODE_NAME     CT51 1
 '@BASEBOARD_FAB2_LIB.BASEBOARD_FAB2(SCH_1):PAGE216_I108@DEV_DISCRETE.CAP_A(CHIPS)':
 'A': CDS_PINID='A';
NODE_NAME     RF15 1
 '@BASEBOARD_FAB2_LIB.BASEBOARD_FAB2(SCH_1):PAGE215_I15@MSTR_DISCRETE.RES(CHIPS)':
 'A': CDS_PINID='A';
NODE_NAME     CF15 1
 '@BASEBOARD_FAB2_LIB.BASEBOARD_FAB2(SCH_1):PAGE215_I16@W_HDL.SC22P50V2JN-4GP(CHIPS)':
 '1': CDS_PINID='\1\';
NODE_NAME     EU7G1 21
 '@BASEBOARD_FAB2_LIB.BASEBOARD_FAB2(SCH_1):PAGE215_I69@MSTR_CONTROLLER.PXM1310B(CHIPS)':
 'AIREF1': CDS_PINID='AIREF1';
NET_NAME
'VR_PVDDQ_ABC_AIREF2'
 '@BASEBOARD_FAB2_LIB.BASEBOARD_FAB2(SCH_1):VR_PVDDQ_ABC_AIREF2':
 C_SIGNAL='@baseboard_fab2_lib.baseboard_fab2(sch_1):vr_pvddq_abc_airef2';
NODE_NAME     EU7G3 39
 '@BASEBOARD_FAB2_LIB.BASEBOARD_FAB2(SCH_1):PAGE216_I103@MSTR_DISCRETE.IR354XX(CHIPS)':
 'REFIN': CDS_PINID='REFIN';
NODE_NAME     CT52 1
 '@BASEBOARD_FAB2_LIB.BASEBOARD_FAB2(SCH_1):PAGE216_I111@DEV_DISCRETE.CAP_A(CHIPS)':
 'A': CDS_PINID='A';
NODE_NAME     CF16 1
 '@BASEBOARD_FAB2_LIB.BASEBOARD_FAB2(SCH_1):PAGE215_I26@W_HDL.SC22P50V2JN-4GP(CHIPS)':
 '1': CDS_PINID='\1\';
NODE_NAME     RF16 1
 '@BASEBOARD_FAB2_LIB.BASEBOARD_FAB2(SCH_1):PAGE215_I27@MSTR_DISCRETE.RES(CHIPS)':
 'A': CDS_PINID='A';
NODE_NAME     EU7G1 23
 '@BASEBOARD_FAB2_LIB.BASEBOARD_FAB2(SCH_1):PAGE215_I69@MSTR_CONTROLLER.PXM1310B(CHIPS)':
 'AIREF2': CDS_PINID='AIREF2';
NET_NAME
'VR_PVDDQ_ABC_AVSP'
 '@BASEBOARD_FAB2_LIB.BASEBOARD_FAB2(SCH_1):VR_PVDDQ_ABC_AVSP':
 C_SIGNAL='@baseboard_fab2_lib.baseboard_fab2(sch_1):vr_pvddq_abc_avsp';
NODE_NAME     R7G9 2
 '@BASEBOARD_FAB2_LIB.BASEBOARD_FAB2(SCH_1):PAGE215_I12@MSTR_DISCRETE.RES(CHIPS)':
 'B': CDS_PINID='B';
NODE_NAME     C7G4 1
 '@BASEBOARD_FAB2_LIB.BASEBOARD_FAB2(SCH_1):PAGE215_I14@MSTR_DISCRETE.CAP(CHIPS)':
 'A': CDS_PINID='A';
NODE_NAME     EU7G1 19
 '@BASEBOARD_FAB2_LIB.BASEBOARD_FAB2(SCH_1):PAGE215_I69@MSTR_CONTROLLER.PXM1310B(CHIPS)':
 'AVSEN': CDS_PINID='AVSEN';
NET_NAME
'VR_PVDDQ_ABC_PH1_BOOT'
 '@BASEBOARD_FAB2_LIB.BASEBOARD_FAB2(SCH_1):VR_PVDDQ_ABC_PH1_BOOT':
 C_SIGNAL='@baseboard_fab2_lib.baseboard_fab2(sch_1):vr_pvddq_abc_ph1_boot';
NODE_NAME     C7G31 1
 '@BASEBOARD_FAB2_LIB.BASEBOARD_FAB2(SCH_1):PAGE216_I44@MSTR_DISCRETE.CAP(CHIPS)':
 'A': CDS_PINID='A';
NODE_NAME     RT33 1
 '@BASEBOARD_FAB2_LIB.BASEBOARD_FAB2(SCH_1):PAGE216_I139@MSTR_DISCRETE.RES(CHIPS)':
 'A': CDS_PINID='A';
NET_NAME
'VR_PVDDQ_ABC_PH1_BOOT_R'
 '@BASEBOARD_FAB2_LIB.BASEBOARD_FAB2(SCH_1):VR_PVDDQ_ABC_PH1_BOOT_R':
 C_SIGNAL='@baseboard_fab2_lib.baseboard_fab2(sch_1):vr_pvddq_abc_ph1_boot_r';
NODE_NAME     EU7G2 33
 '@BASEBOARD_FAB2_LIB.BASEBOARD_FAB2(SCH_1):PAGE216_I102@MSTR_DISCRETE.IR354XX(CHIPS)':
 'BOOST': CDS_PINID='BOOST';
NODE_NAME     RT33 2
 '@BASEBOARD_FAB2_LIB.BASEBOARD_FAB2(SCH_1):PAGE216_I139@MSTR_DISCRETE.RES(CHIPS)':
 'B': CDS_PINID='B';
NET_NAME
'VR_PVDDQ_ABC_PH1_OCSET'
 '@BASEBOARD_FAB2_LIB.BASEBOARD_FAB2(SCH_1):VR_PVDDQ_ABC_PH1_OCSET':
 C_SIGNAL='@baseboard_fab2_lib.baseboard_fab2(sch_1):vr_pvddq_abc_ph1_ocset';
NODE_NAME     EU7G2 37
 '@BASEBOARD_FAB2_LIB.BASEBOARD_FAB2(SCH_1):PAGE216_I102@MSTR_DISCRETE.IR354XX(CHIPS)':
 'OCSET': CDS_PINID='OCSET';
NODE_NAME     R7G25 1
 '@BASEBOARD_FAB2_LIB.BASEBOARD_FAB2(SCH_1):PAGE216_I104@MSTR_DISCRETE.RES(CHIPS)':
 'A': CDS_PINID='A';
NET_NAME
'VR_PVDDQ_ABC_PH1_PHASE'
 '@BASEBOARD_FAB2_LIB.BASEBOARD_FAB2(SCH_1):VR_PVDDQ_ABC_PH1_PHASE':
 C_SIGNAL='@baseboard_fab2_lib.baseboard_fab2(sch_1):vr_pvddq_abc_ph1_phase';
NODE_NAME     C7G31 2
 '@BASEBOARD_FAB2_LIB.BASEBOARD_FAB2(SCH_1):PAGE216_I44@MSTR_DISCRETE.CAP(CHIPS)':
 'B': CDS_PINID='B';
NODE_NAME     EU7G2 32
 '@BASEBOARD_FAB2_LIB.BASEBOARD_FAB2(SCH_1):PAGE216_I102@MSTR_DISCRETE.IR354XX(CHIPS)':
 'PHASE': CDS_PINID='PHASE';
NET_NAME
'VR_PVDDQ_ABC_PH1_SW'
 '@BASEBOARD_FAB2_LIB.BASEBOARD_FAB2(SCH_1):VR_PVDDQ_ABC_PH1_SW':
 C_SIGNAL='@baseboard_fab2_lib.baseboard_fab2(sch_1):vr_pvddq_abc_ph1_sw';
NODE_NAME     EU7G2 10
 '@BASEBOARD_FAB2_LIB.BASEBOARD_FAB2(SCH_1):PAGE216_I102@MSTR_DISCRETE.IR354XX(CHIPS)':
 'SW': CDS_PINID='SW';
NODE_NAME     CT50 1
 '@BASEBOARD_FAB2_LIB.BASEBOARD_FAB2(SCH_1):PAGE216_I135@MSTR_DISCRETE.CAP(CHIPS)':
 'A': CDS_PINID='A';
NODE_NAME     L7G1 1
 '@BASEBOARD_FAB2_LIB.BASEBOARD_FAB2(SCH_1):PAGE216_I153@W_HDL.IND-120NH-30-GP(CHIPS)':
 'S': CDS_PINID='S';
NET_NAME
'VR_PVDDQ_ABC_PH1_SW_RC'
 '@BASEBOARD_FAB2_LIB.BASEBOARD_FAB2(SCH_1):VR_PVDDQ_ABC_PH1_SW_RC':
 C_SIGNAL='@baseboard_fab2_lib.baseboard_fab2(sch_1):vr_pvddq_abc_ph1_sw_rc';
NODE_NAME     CT50 2
 '@BASEBOARD_FAB2_LIB.BASEBOARD_FAB2(SCH_1):PAGE216_I135@MSTR_DISCRETE.CAP(CHIPS)':
 'B': CDS_PINID='B';
NODE_NAME     RT34 1
 '@BASEBOARD_FAB2_LIB.BASEBOARD_FAB2(SCH_1):PAGE216_I151@W_HDL.1R3F-GP(CHIPS)':
 '1': CDS_PINID='\1\';
NET_NAME
'VR_PVDDQ_ABC_PH1_VCIN'
 '@BASEBOARD_FAB2_LIB.BASEBOARD_FAB2(SCH_1):VR_PVDDQ_ABC_PH1_VCIN':
 C_SIGNAL='@baseboard_fab2_lib.baseboard_fab2(sch_1):vr_pvddq_abc_ph1_vcin';
NODE_NAME     C7G33 1
 '@BASEBOARD_FAB2_LIB.BASEBOARD_FAB2(SCH_1):PAGE216_I50@MSTR_DISCRETE.CAP(CHIPS)':
 'A': CDS_PINID='A';
NODE_NAME     EU7G2 3
 '@BASEBOARD_FAB2_LIB.BASEBOARD_FAB2(SCH_1):PAGE216_I102@MSTR_DISCRETE.IR354XX(CHIPS)':
 'VCC': CDS_PINID='VCC';
NODE_NAME     R3U6 1
 '@BASEBOARD_FAB2_LIB.BASEBOARD_FAB2(SCH_1):PAGE216_I145@MSTR_DISCRETE.RES(CHIPS)':
 'A': CDS_PINID='A';
NET_NAME
'VR_PVDDQ_ABC_PH2_BOOT'
 '@BASEBOARD_FAB2_LIB.BASEBOARD_FAB2(SCH_1):VR_PVDDQ_ABC_PH2_BOOT':
 C_SIGNAL='@baseboard_fab2_lib.baseboard_fab2(sch_1):vr_pvddq_abc_ph2_boot';
NODE_NAME     C7G38 1
 '@BASEBOARD_FAB2_LIB.BASEBOARD_FAB2(SCH_1):PAGE216_I128@MSTR_DISCRETE.CAP(CHIPS)':
 'A': CDS_PINID='A';
NODE_NAME     RT36 1
 '@BASEBOARD_FAB2_LIB.BASEBOARD_FAB2(SCH_1):PAGE216_I140@MSTR_DISCRETE.RES(CHIPS)':
 'A': CDS_PINID='A';
NET_NAME
'VR_PVDDQ_ABC_PH2_BOOT_R'
 '@BASEBOARD_FAB2_LIB.BASEBOARD_FAB2(SCH_1):VR_PVDDQ_ABC_PH2_BOOT_R':
 C_SIGNAL='@baseboard_fab2_lib.baseboard_fab2(sch_1):vr_pvddq_abc_ph2_boot_r';
NODE_NAME     EU7G3 33
 '@BASEBOARD_FAB2_LIB.BASEBOARD_FAB2(SCH_1):PAGE216_I103@MSTR_DISCRETE.IR354XX(CHIPS)':
 'BOOST': CDS_PINID='BOOST';
NODE_NAME     RT36 2
 '@BASEBOARD_FAB2_LIB.BASEBOARD_FAB2(SCH_1):PAGE216_I140@MSTR_DISCRETE.RES(CHIPS)':
 'B': CDS_PINID='B';
NET_NAME
'VR_PVDDQ_ABC_PH2_OCSET'
 '@BASEBOARD_FAB2_LIB.BASEBOARD_FAB2(SCH_1):VR_PVDDQ_ABC_PH2_OCSET':
 C_SIGNAL='@baseboard_fab2_lib.baseboard_fab2(sch_1):vr_pvddq_abc_ph2_ocset';
NODE_NAME     EU7G3 37
 '@BASEBOARD_FAB2_LIB.BASEBOARD_FAB2(SCH_1):PAGE216_I103@MSTR_DISCRETE.IR354XX(CHIPS)':
 'OCSET': CDS_PINID='OCSET';
NODE_NAME     R7G30 1
 '@BASEBOARD_FAB2_LIB.BASEBOARD_FAB2(SCH_1):PAGE216_I106@MSTR_DISCRETE.RES(CHIPS)':
 'A': CDS_PINID='A';
NET_NAME
'VR_PVDDQ_ABC_PH2_PHASE'
 '@BASEBOARD_FAB2_LIB.BASEBOARD_FAB2(SCH_1):VR_PVDDQ_ABC_PH2_PHASE':
 C_SIGNAL='@baseboard_fab2_lib.baseboard_fab2(sch_1):vr_pvddq_abc_ph2_phase';
NODE_NAME     EU7G3 32
 '@BASEBOARD_FAB2_LIB.BASEBOARD_FAB2(SCH_1):PAGE216_I103@MSTR_DISCRETE.IR354XX(CHIPS)':
 'PHASE': CDS_PINID='PHASE';
NODE_NAME     C7G38 2
 '@BASEBOARD_FAB2_LIB.BASEBOARD_FAB2(SCH_1):PAGE216_I128@MSTR_DISCRETE.CAP(CHIPS)':
 'B': CDS_PINID='B';
NET_NAME
'VR_PVDDQ_ABC_PH2_SW'
 '@BASEBOARD_FAB2_LIB.BASEBOARD_FAB2(SCH_1):VR_PVDDQ_ABC_PH2_SW':
 C_SIGNAL='@baseboard_fab2_lib.baseboard_fab2(sch_1):vr_pvddq_abc_ph2_sw';
NODE_NAME     EU7G3 10
 '@BASEBOARD_FAB2_LIB.BASEBOARD_FAB2(SCH_1):PAGE216_I103@MSTR_DISCRETE.IR354XX(CHIPS)':
 'SW': CDS_PINID='SW';
NODE_NAME     CT53 1
 '@BASEBOARD_FAB2_LIB.BASEBOARD_FAB2(SCH_1):PAGE216_I136@MSTR_DISCRETE.CAP(CHIPS)':
 'A': CDS_PINID='A';
NODE_NAME     L7G2 1
 '@BASEBOARD_FAB2_LIB.BASEBOARD_FAB2(SCH_1):PAGE216_I155@W_HDL.IND-120NH-30-GP(CHIPS)':
 'S': CDS_PINID='S';
NET_NAME
'VR_PVDDQ_ABC_PH2_SW_RC'
 '@BASEBOARD_FAB2_LIB.BASEBOARD_FAB2(SCH_1):VR_PVDDQ_ABC_PH2_SW_RC':
 C_SIGNAL='@baseboard_fab2_lib.baseboard_fab2(sch_1):vr_pvddq_abc_ph2_sw_rc';
NODE_NAME     CT53 2
 '@BASEBOARD_FAB2_LIB.BASEBOARD_FAB2(SCH_1):PAGE216_I136@MSTR_DISCRETE.CAP(CHIPS)':
 'B': CDS_PINID='B';
NODE_NAME     RT35 1
 '@BASEBOARD_FAB2_LIB.BASEBOARD_FAB2(SCH_1):PAGE216_I152@W_HDL.1R3F-GP(CHIPS)':
 '1': CDS_PINID='\1\';
NET_NAME
'VR_PVDDQ_ABC_PH2_VCIN'
 '@BASEBOARD_FAB2_LIB.BASEBOARD_FAB2(SCH_1):VR_PVDDQ_ABC_PH2_VCIN':
 C_SIGNAL='@baseboard_fab2_lib.baseboard_fab2(sch_1):vr_pvddq_abc_ph2_vcin';
NODE_NAME     C7G40 1
 '@BASEBOARD_FAB2_LIB.BASEBOARD_FAB2(SCH_1):PAGE216_I77@MSTR_DISCRETE.CAP(CHIPS)':
 'A': CDS_PINID='A';
NODE_NAME     EU7G3 3
 '@BASEBOARD_FAB2_LIB.BASEBOARD_FAB2(SCH_1):PAGE216_I103@MSTR_DISCRETE.IR354XX(CHIPS)':
 'VCC': CDS_PINID='VCC';
NODE_NAME     R3U9 1
 '@BASEBOARD_FAB2_LIB.BASEBOARD_FAB2(SCH_1):PAGE216_I146@MSTR_DISCRETE.RES(CHIPS)':
 'A': CDS_PINID='A';
NET_NAME
'VR_PVDDQ_ABC_PWM1'
 '@BASEBOARD_FAB2_LIB.BASEBOARD_FAB2(SCH_1):VR_PVDDQ_ABC_PWM1':
 C_SIGNAL='@baseboard_fab2_lib.baseboard_fab2(sch_1):vr_pvddq_abc_pwm1';
NODE_NAME     EU7G2 34
 '@BASEBOARD_FAB2_LIB.BASEBOARD_FAB2(SCH_1):PAGE216_I102@MSTR_DISCRETE.IR354XX(CHIPS)':
 'PWM': CDS_PINID='PWM';
NODE_NAME     EU7G1 5
 '@BASEBOARD_FAB2_LIB.BASEBOARD_FAB2(SCH_1):PAGE215_I69@MSTR_CONTROLLER.PXM1310B(CHIPS)':
 'APWM1': CDS_PINID='APWM1';
NET_NAME
'VR_PVDDQ_ABC_PWM2'
 '@BASEBOARD_FAB2_LIB.BASEBOARD_FAB2(SCH_1):VR_PVDDQ_ABC_PWM2':
 C_SIGNAL='@baseboard_fab2_lib.baseboard_fab2(sch_1):vr_pvddq_abc_pwm2';
NODE_NAME     EU7G3 34
 '@BASEBOARD_FAB2_LIB.BASEBOARD_FAB2(SCH_1):PAGE216_I103@MSTR_DISCRETE.IR354XX(CHIPS)':
 'PWM': CDS_PINID='PWM';
NODE_NAME     EU7G1 4
 '@BASEBOARD_FAB2_LIB.BASEBOARD_FAB2(SCH_1):PAGE215_I69@MSTR_CONTROLLER.PXM1310B(CHIPS)':
 'APWM2': CDS_PINID='APWM2';
NET_NAME
'VR_PVDDQ_ABC_VD12'
 '@BASEBOARD_FAB2_LIB.BASEBOARD_FAB2(SCH_1):VR_PVDDQ_ABC_VD12':
 C_SIGNAL='@baseboard_fab2_lib.baseboard_fab2(sch_1):vr_pvddq_abc_vd12';
NODE_NAME     C7F15 1
 '@BASEBOARD_FAB2_LIB.BASEBOARD_FAB2(SCH_1):PAGE215_I38@DEV_DISCRETE.CAP_A(CHIPS)':
 'A': CDS_PINID='A';
NODE_NAME     C7F16 1
 '@BASEBOARD_FAB2_LIB.BASEBOARD_FAB2(SCH_1):PAGE215_I40@DEV_DISCRETE.CAP_A(CHIPS)':
 'A': CDS_PINID='A';
NODE_NAME     EU7G1 40
 '@BASEBOARD_FAB2_LIB.BASEBOARD_FAB2(SCH_1):PAGE215_I69@MSTR_CONTROLLER.PXM1310B(CHIPS)':
 'VD12': CDS_PINID='VD12';
NET_NAME
'VR_PVDDQ_ABC_VDD'
 '@BASEBOARD_FAB2_LIB.BASEBOARD_FAB2(SCH_1):VR_PVDDQ_ABC_VDD':
 C_SIGNAL='@baseboard_fab2_lib.baseboard_fab2(sch_1):vr_pvddq_abc_vdd';
NODE_NAME     R3T13 2
 '@BASEBOARD_FAB2_LIB.BASEBOARD_FAB2(SCH_1):PAGE215_I33@MSTR_DISCRETE.RES(CHIPS)':
 'B': CDS_PINID='B';
NODE_NAME     C7F17 1
 '@BASEBOARD_FAB2_LIB.BASEBOARD_FAB2(SCH_1):PAGE215_I34@DEV_DISCRETE.CAP_A(CHIPS)':
 'A': CDS_PINID='A';
NODE_NAME     C7F18 1
 '@BASEBOARD_FAB2_LIB.BASEBOARD_FAB2(SCH_1):PAGE215_I35@DEV_DISCRETE.CAP_A(CHIPS)':
 'A': CDS_PINID='A';
NODE_NAME     EU7G1 39
 '@BASEBOARD_FAB2_LIB.BASEBOARD_FAB2(SCH_1):PAGE215_I69@MSTR_CONTROLLER.PXM1310B(CHIPS)':
 'VDD': CDS_PINID='VDD';
NET_NAME
'VR_PVDDQ_ABC_VINSEN'
 '@BASEBOARD_FAB2_LIB.BASEBOARD_FAB2(SCH_1):VR_PVDDQ_ABC_VINSEN':
 C_SIGNAL='@baseboard_fab2_lib.baseboard_fab2(sch_1):vr_pvddq_abc_vinsen';
NODE_NAME     EU7G1 37
 '@BASEBOARD_FAB2_LIB.BASEBOARD_FAB2(SCH_1):PAGE215_I69@MSTR_CONTROLLER.PXM1310B(CHIPS)':
 'VINSEN': CDS_PINID='VINSEN';
NODE_NAME     C12W1 2
 '@BASEBOARD_FAB2_LIB.BASEBOARD_FAB2(SCH_1):PAGE197_I8@MSTR_DISCRETE.CAP(CHIPS)':
 'B': CDS_PINID='B';
NODE_NAME     R12W5 2
 '@BASEBOARD_FAB2_LIB.BASEBOARD_FAB2(SCH_1):PAGE197_I111@W_HDL.665KR2B-GP(CHIPS)':
 '2': CDS_PINID='\2\';
NODE_NAME     R12W2 2
 '@BASEBOARD_FAB2_LIB.BASEBOARD_FAB2(SCH_1):PAGE197_I117@W_HDL.665KR5B-1-GP(CHIPS)':
 '2': CDS_PINID='\2\';
NET_NAME
'VR_PVDDQ_ABC_VREN'
 '@BASEBOARD_FAB2_LIB.BASEBOARD_FAB2(SCH_1):VR_PVDDQ_ABC_VREN':
 C_SIGNAL='@baseboard_fab2_lib.baseboard_fab2(sch_1):vr_pvddq_abc_vren';
NODE_NAME     R7F21 2
 '@BASEBOARD_FAB2_LIB.BASEBOARD_FAB2(SCH_1):PAGE215_I13@MSTR_DISCRETE.RES(CHIPS)':
 'B': CDS_PINID='B';
NODE_NAME     R7F20 2
 '@BASEBOARD_FAB2_LIB.BASEBOARD_FAB2(SCH_1):PAGE215_I29@MSTR_DISCRETE.RES(CHIPS)':
 'B': CDS_PINID='B';
NODE_NAME     EU7G1 10
 '@BASEBOARD_FAB2_LIB.BASEBOARD_FAB2(SCH_1):PAGE215_I69@MSTR_CONTROLLER.PXM1310B(CHIPS)':
 'AVREN': CDS_PINID='AVREN';
NET_NAME
'VR_PVDDQ_ABC_XADDR1'
 '@BASEBOARD_FAB2_LIB.BASEBOARD_FAB2(SCH_1):VR_PVDDQ_ABC_XADDR1':
 C_SIGNAL='@baseboard_fab2_lib.baseboard_fab2(sch_1):vr_pvddq_abc_xaddr1';
NODE_NAME     EU7G1 36
 '@BASEBOARD_FAB2_LIB.BASEBOARD_FAB2(SCH_1):PAGE215_I69@MSTR_CONTROLLER.PXM1310B(CHIPS)':
 'XADDR1': CDS_PINID='XADDR1';
NODE_NAME     R7G8 1
 '@BASEBOARD_FAB2_LIB.BASEBOARD_FAB2(SCH_1):PAGE215_I72@MSTR_DISCRETE.RES(CHIPS)':
 'A': CDS_PINID='A';
NET_NAME
'VR_PVDDQ_ABC_XADDR2'
 '@BASEBOARD_FAB2_LIB.BASEBOARD_FAB2(SCH_1):VR_PVDDQ_ABC_XADDR2':
 C_SIGNAL='@baseboard_fab2_lib.baseboard_fab2(sch_1):vr_pvddq_abc_xaddr2';
NODE_NAME     EU7G1 33
 '@BASEBOARD_FAB2_LIB.BASEBOARD_FAB2(SCH_1):PAGE215_I69@MSTR_CONTROLLER.PXM1310B(CHIPS)':
 'XADDR2': CDS_PINID='XADDR2';
NODE_NAME     R7G10 1
 '@BASEBOARD_FAB2_LIB.BASEBOARD_FAB2(SCH_1):PAGE215_I73@MSTR_DISCRETE.RES(CHIPS)':
 'A': CDS_PINID='A';
NET_NAME
'VR_PVDDQ_DEF_AIINSEN'
 '@BASEBOARD_FAB2_LIB.BASEBOARD_FAB2(SCH_1):VR_PVDDQ_DEF_AIINSEN':
 C_SIGNAL='@baseboard_fab2_lib.baseboard_fab2(sch_1):vr_pvddq_def_aiinsen';
NODE_NAME     EU7A5 38
 '@BASEBOARD_FAB2_LIB.BASEBOARD_FAB2(SCH_1):PAGE218_I69@MSTR_CONTROLLER.PXM1310B(CHIPS)':
 'IINSEN': CDS_PINID='IINSEN';
NODE_NAME     C12W2 1
 '@BASEBOARD_FAB2_LIB.BASEBOARD_FAB2(SCH_1):PAGE197_I1@MSTR_DISCRETE.CAP(CHIPS)':
 'A': CDS_PINID='A';
NODE_NAME     R12W10 1
 '@BASEBOARD_FAB2_LIB.BASEBOARD_FAB2(SCH_1):PAGE197_I109@W_HDL.665KR2B-GP(CHIPS)':
 '1': CDS_PINID='\1\';
NODE_NAME     R12W6 2
 '@BASEBOARD_FAB2_LIB.BASEBOARD_FAB2(SCH_1):PAGE197_I120@W_HDL.665KR5B-1-GP(CHIPS)':
 '2': CDS_PINID='\2\';
NET_NAME
'VR_PVDDQ_DEF_AIREF1'
 '@BASEBOARD_FAB2_LIB.BASEBOARD_FAB2(SCH_1):VR_PVDDQ_DEF_AIREF1':
 C_SIGNAL='@baseboard_fab2_lib.baseboard_fab2(sch_1):vr_pvddq_def_airef1';
NODE_NAME     EU7A1 39
 '@BASEBOARD_FAB2_LIB.BASEBOARD_FAB2(SCH_1):PAGE219_I106@MSTR_DISCRETE.IR354XX(CHIPS)':
 'REFIN': CDS_PINID='REFIN';
NODE_NAME     CT45 1
 '@BASEBOARD_FAB2_LIB.BASEBOARD_FAB2(SCH_1):PAGE219_I116@DEV_DISCRETE.CAP_A(CHIPS)':
 'A': CDS_PINID='A';
NODE_NAME     RF17 1
 '@BASEBOARD_FAB2_LIB.BASEBOARD_FAB2(SCH_1):PAGE218_I18@MSTR_DISCRETE.RES(CHIPS)':
 'A': CDS_PINID='A';
NODE_NAME     EU7A5 21
 '@BASEBOARD_FAB2_LIB.BASEBOARD_FAB2(SCH_1):PAGE218_I69@MSTR_CONTROLLER.PXM1310B(CHIPS)':
 'AIREF1': CDS_PINID='AIREF1';
NODE_NAME     CF17 1
 '@BASEBOARD_FAB2_LIB.BASEBOARD_FAB2(SCH_1):PAGE218_I17@W_HDL.SC22P50V2JN-4GP(CHIPS)':
 '1': CDS_PINID='\1\';
NET_NAME
'VR_PVDDQ_DEF_AIREF2'
 '@BASEBOARD_FAB2_LIB.BASEBOARD_FAB2(SCH_1):VR_PVDDQ_DEF_AIREF2':
 C_SIGNAL='@baseboard_fab2_lib.baseboard_fab2(sch_1):vr_pvddq_def_airef2';
NODE_NAME     EU7A4 39
 '@BASEBOARD_FAB2_LIB.BASEBOARD_FAB2(SCH_1):PAGE219_I107@MSTR_DISCRETE.IR354XX(CHIPS)':
 'REFIN': CDS_PINID='REFIN';
NODE_NAME     CT46 1
 '@BASEBOARD_FAB2_LIB.BASEBOARD_FAB2(SCH_1):PAGE219_I113@DEV_DISCRETE.CAP_A(CHIPS)':
 'A': CDS_PINID='A';
NODE_NAME     RF18 1
 '@BASEBOARD_FAB2_LIB.BASEBOARD_FAB2(SCH_1):PAGE218_I19@MSTR_DISCRETE.RES(CHIPS)':
 'A': CDS_PINID='A';
NODE_NAME     CF18 1
 '@BASEBOARD_FAB2_LIB.BASEBOARD_FAB2(SCH_1):PAGE218_I20@W_HDL.SC22P50V2JN-4GP(CHIPS)':
 '1': CDS_PINID='\1\';
NODE_NAME     EU7A5 23
 '@BASEBOARD_FAB2_LIB.BASEBOARD_FAB2(SCH_1):PAGE218_I69@MSTR_CONTROLLER.PXM1310B(CHIPS)':
 'AIREF2': CDS_PINID='AIREF2';
NET_NAME
'VR_PVDDQ_DEF_AVSP'
 '@BASEBOARD_FAB2_LIB.BASEBOARD_FAB2(SCH_1):VR_PVDDQ_DEF_AVSP':
 C_SIGNAL='@baseboard_fab2_lib.baseboard_fab2(sch_1):vr_pvddq_def_avsp';
NODE_NAME     R7A7 2
 '@BASEBOARD_FAB2_LIB.BASEBOARD_FAB2(SCH_1):PAGE218_I13@MSTR_DISCRETE.RES(CHIPS)':
 'B': CDS_PINID='B';
NODE_NAME     EU7A5 19
 '@BASEBOARD_FAB2_LIB.BASEBOARD_FAB2(SCH_1):PAGE218_I69@MSTR_CONTROLLER.PXM1310B(CHIPS)':
 'AVSEN': CDS_PINID='AVSEN';
NODE_NAME     C7A28 1
 '@BASEBOARD_FAB2_LIB.BASEBOARD_FAB2(SCH_1):PAGE218_I14@MSTR_DISCRETE.CAP(CHIPS)':
 'A': CDS_PINID='A';
NET_NAME
'VR_PVDDQ_DEF_PH1_BOOT'
 '@BASEBOARD_FAB2_LIB.BASEBOARD_FAB2(SCH_1):VR_PVDDQ_DEF_PH1_BOOT':
 C_SIGNAL='@baseboard_fab2_lib.baseboard_fab2(sch_1):vr_pvddq_def_ph1_boot';
NODE_NAME     C7A12 1
 '@BASEBOARD_FAB2_LIB.BASEBOARD_FAB2(SCH_1):PAGE219_I44@MSTR_DISCRETE.CAP(CHIPS)':
 'A': CDS_PINID='A';
NODE_NAME     RT30 1
 '@BASEBOARD_FAB2_LIB.BASEBOARD_FAB2(SCH_1):PAGE219_I141@MSTR_DISCRETE.RES(CHIPS)':
 'A': CDS_PINID='A';
NET_NAME
'VR_PVDDQ_DEF_PH1_BOOT_R'
 '@BASEBOARD_FAB2_LIB.BASEBOARD_FAB2(SCH_1):VR_PVDDQ_DEF_PH1_BOOT_R':
 C_SIGNAL='@baseboard_fab2_lib.baseboard_fab2(sch_1):vr_pvddq_def_ph1_boot_r';
NODE_NAME     EU7A1 33
 '@BASEBOARD_FAB2_LIB.BASEBOARD_FAB2(SCH_1):PAGE219_I106@MSTR_DISCRETE.IR354XX(CHIPS)':
 'BOOST': CDS_PINID='BOOST';
NODE_NAME     RT30 2
 '@BASEBOARD_FAB2_LIB.BASEBOARD_FAB2(SCH_1):PAGE219_I141@MSTR_DISCRETE.RES(CHIPS)':
 'B': CDS_PINID='B';
NET_NAME
'VR_PVDDQ_DEF_PH1_OCSET'
 '@BASEBOARD_FAB2_LIB.BASEBOARD_FAB2(SCH_1):VR_PVDDQ_DEF_PH1_OCSET':
 C_SIGNAL='@baseboard_fab2_lib.baseboard_fab2(sch_1):vr_pvddq_def_ph1_ocset';
NODE_NAME     EU7A1 37
 '@BASEBOARD_FAB2_LIB.BASEBOARD_FAB2(SCH_1):PAGE219_I106@MSTR_DISCRETE.IR354XX(CHIPS)':
 'OCSET': CDS_PINID='OCSET';
NODE_NAME     R7A20 1
 '@BASEBOARD_FAB2_LIB.BASEBOARD_FAB2(SCH_1):PAGE219_I108@MSTR_DISCRETE.RES(CHIPS)':
 'A': CDS_PINID='A';
NET_NAME
'VR_PVDDQ_DEF_PH1_PHASE'
 '@BASEBOARD_FAB2_LIB.BASEBOARD_FAB2(SCH_1):VR_PVDDQ_DEF_PH1_PHASE':
 C_SIGNAL='@baseboard_fab2_lib.baseboard_fab2(sch_1):vr_pvddq_def_ph1_phase';
NODE_NAME     C7A12 2
 '@BASEBOARD_FAB2_LIB.BASEBOARD_FAB2(SCH_1):PAGE219_I44@MSTR_DISCRETE.CAP(CHIPS)':
 'B': CDS_PINID='B';
NODE_NAME     EU7A1 32
 '@BASEBOARD_FAB2_LIB.BASEBOARD_FAB2(SCH_1):PAGE219_I106@MSTR_DISCRETE.IR354XX(CHIPS)':
 'PHASE': CDS_PINID='PHASE';
NET_NAME
'VR_PVDDQ_DEF_PH1_SW'
 '@BASEBOARD_FAB2_LIB.BASEBOARD_FAB2(SCH_1):VR_PVDDQ_DEF_PH1_SW':
 C_SIGNAL='@baseboard_fab2_lib.baseboard_fab2(sch_1):vr_pvddq_def_ph1_sw';
NODE_NAME     EU7A1 10
 '@BASEBOARD_FAB2_LIB.BASEBOARD_FAB2(SCH_1):PAGE219_I106@MSTR_DISCRETE.IR354XX(CHIPS)':
 'SW': CDS_PINID='SW';
NODE_NAME     CT44 1
 '@BASEBOARD_FAB2_LIB.BASEBOARD_FAB2(SCH_1):PAGE219_I137@MSTR_DISCRETE.CAP(CHIPS)':
 'A': CDS_PINID='A';
NODE_NAME     L7A1 1
 '@BASEBOARD_FAB2_LIB.BASEBOARD_FAB2(SCH_1):PAGE219_I157@W_HDL.IND-120NH-30-GP(CHIPS)':
 'S': CDS_PINID='S';
NET_NAME
'VR_PVDDQ_DEF_PH1_SW_RC'
 '@BASEBOARD_FAB2_LIB.BASEBOARD_FAB2(SCH_1):VR_PVDDQ_DEF_PH1_SW_RC':
 C_SIGNAL='@baseboard_fab2_lib.baseboard_fab2(sch_1):vr_pvddq_def_ph1_sw_rc';
NODE_NAME     CT44 2
 '@BASEBOARD_FAB2_LIB.BASEBOARD_FAB2(SCH_1):PAGE219_I137@MSTR_DISCRETE.CAP(CHIPS)':
 'B': CDS_PINID='B';
NODE_NAME     RT29 1
 '@BASEBOARD_FAB2_LIB.BASEBOARD_FAB2(SCH_1):PAGE219_I153@W_HDL.1R3F-GP(CHIPS)':
 '1': CDS_PINID='\1\';
NET_NAME
'VR_PVDDQ_DEF_PH1_VCIN'
 '@BASEBOARD_FAB2_LIB.BASEBOARD_FAB2(SCH_1):VR_PVDDQ_DEF_PH1_VCIN':
 C_SIGNAL='@baseboard_fab2_lib.baseboard_fab2(sch_1):vr_pvddq_def_ph1_vcin';
NODE_NAME     C7A16 1
 '@BASEBOARD_FAB2_LIB.BASEBOARD_FAB2(SCH_1):PAGE219_I50@MSTR_DISCRETE.CAP(CHIPS)':
 'A': CDS_PINID='A';
NODE_NAME     EU7A1 3
 '@BASEBOARD_FAB2_LIB.BASEBOARD_FAB2(SCH_1):PAGE219_I106@MSTR_DISCRETE.IR354XX(CHIPS)':
 'VCC': CDS_PINID='VCC';
NODE_NAME     R3L6 1
 '@BASEBOARD_FAB2_LIB.BASEBOARD_FAB2(SCH_1):PAGE219_I147@MSTR_DISCRETE.RES(CHIPS)':
 'A': CDS_PINID='A';
NET_NAME
'VR_PVDDQ_DEF_PH2_BOOT'
 '@BASEBOARD_FAB2_LIB.BASEBOARD_FAB2(SCH_1):VR_PVDDQ_DEF_PH2_BOOT':
 C_SIGNAL='@baseboard_fab2_lib.baseboard_fab2(sch_1):vr_pvddq_def_ph2_boot';
NODE_NAME     C7A22 1
 '@BASEBOARD_FAB2_LIB.BASEBOARD_FAB2(SCH_1):PAGE219_I75@MSTR_DISCRETE.CAP(CHIPS)':
 'A': CDS_PINID='A';
NODE_NAME     RT31 1
 '@BASEBOARD_FAB2_LIB.BASEBOARD_FAB2(SCH_1):PAGE219_I142@MSTR_DISCRETE.RES(CHIPS)':
 'A': CDS_PINID='A';
NET_NAME
'VR_PVDDQ_DEF_PH2_BOOT_R'
 '@BASEBOARD_FAB2_LIB.BASEBOARD_FAB2(SCH_1):VR_PVDDQ_DEF_PH2_BOOT_R':
 C_SIGNAL='@baseboard_fab2_lib.baseboard_fab2(sch_1):vr_pvddq_def_ph2_boot_r';
NODE_NAME     EU7A4 33
 '@BASEBOARD_FAB2_LIB.BASEBOARD_FAB2(SCH_1):PAGE219_I107@MSTR_DISCRETE.IR354XX(CHIPS)':
 'BOOST': CDS_PINID='BOOST';
NODE_NAME     RT31 2
 '@BASEBOARD_FAB2_LIB.BASEBOARD_FAB2(SCH_1):PAGE219_I142@MSTR_DISCRETE.RES(CHIPS)':
 'B': CDS_PINID='B';
NET_NAME
'VR_PVDDQ_DEF_PH2_OCSET'
 '@BASEBOARD_FAB2_LIB.BASEBOARD_FAB2(SCH_1):VR_PVDDQ_DEF_PH2_OCSET':
 C_SIGNAL='@baseboard_fab2_lib.baseboard_fab2(sch_1):vr_pvddq_def_ph2_ocset';
NODE_NAME     EU7A4 37
 '@BASEBOARD_FAB2_LIB.BASEBOARD_FAB2(SCH_1):PAGE219_I107@MSTR_DISCRETE.IR354XX(CHIPS)':
 'OCSET': CDS_PINID='OCSET';
NODE_NAME     R7A21 1
 '@BASEBOARD_FAB2_LIB.BASEBOARD_FAB2(SCH_1):PAGE219_I110@MSTR_DISCRETE.RES(CHIPS)':
 'A': CDS_PINID='A';
NET_NAME
'VR_PVDDQ_DEF_PH2_PHASE'
 '@BASEBOARD_FAB2_LIB.BASEBOARD_FAB2(SCH_1):VR_PVDDQ_DEF_PH2_PHASE':
 C_SIGNAL='@baseboard_fab2_lib.baseboard_fab2(sch_1):vr_pvddq_def_ph2_phase';
NODE_NAME     C7A22 2
 '@BASEBOARD_FAB2_LIB.BASEBOARD_FAB2(SCH_1):PAGE219_I75@MSTR_DISCRETE.CAP(CHIPS)':
 'B': CDS_PINID='B';
NODE_NAME     EU7A4 32
 '@BASEBOARD_FAB2_LIB.BASEBOARD_FAB2(SCH_1):PAGE219_I107@MSTR_DISCRETE.IR354XX(CHIPS)':
 'PHASE': CDS_PINID='PHASE';
NET_NAME
'VR_PVDDQ_DEF_PH2_SW'
 '@BASEBOARD_FAB2_LIB.BASEBOARD_FAB2(SCH_1):VR_PVDDQ_DEF_PH2_SW':
 C_SIGNAL='@baseboard_fab2_lib.baseboard_fab2(sch_1):vr_pvddq_def_ph2_sw';
NODE_NAME     EU7A4 10
 '@BASEBOARD_FAB2_LIB.BASEBOARD_FAB2(SCH_1):PAGE219_I107@MSTR_DISCRETE.IR354XX(CHIPS)':
 'SW': CDS_PINID='SW';
NODE_NAME     CT47 1
 '@BASEBOARD_FAB2_LIB.BASEBOARD_FAB2(SCH_1):PAGE219_I138@MSTR_DISCRETE.CAP(CHIPS)':
 'A': CDS_PINID='A';
NODE_NAME     L7A3 1
 '@BASEBOARD_FAB2_LIB.BASEBOARD_FAB2(SCH_1):PAGE219_I158@W_HDL.IND-120NH-30-GP(CHIPS)':
 'S': CDS_PINID='S';
NET_NAME
'VR_PVDDQ_DEF_PH2_SW_RC'
 '@BASEBOARD_FAB2_LIB.BASEBOARD_FAB2(SCH_1):VR_PVDDQ_DEF_PH2_SW_RC':
 C_SIGNAL='@baseboard_fab2_lib.baseboard_fab2(sch_1):vr_pvddq_def_ph2_sw_rc';
NODE_NAME     CT47 2
 '@BASEBOARD_FAB2_LIB.BASEBOARD_FAB2(SCH_1):PAGE219_I138@MSTR_DISCRETE.CAP(CHIPS)':
 'B': CDS_PINID='B';
NODE_NAME     RT32 1
 '@BASEBOARD_FAB2_LIB.BASEBOARD_FAB2(SCH_1):PAGE219_I154@W_HDL.1R3F-GP(CHIPS)':
 '1': CDS_PINID='\1\';
NET_NAME
'VR_PVDDQ_DEF_PH2_VCIN'
 '@BASEBOARD_FAB2_LIB.BASEBOARD_FAB2(SCH_1):VR_PVDDQ_DEF_PH2_VCIN':
 C_SIGNAL='@baseboard_fab2_lib.baseboard_fab2(sch_1):vr_pvddq_def_ph2_vcin';
NODE_NAME     C7A24 1
 '@BASEBOARD_FAB2_LIB.BASEBOARD_FAB2(SCH_1):PAGE219_I77@MSTR_DISCRETE.CAP(CHIPS)':
 'A': CDS_PINID='A';
NODE_NAME     EU7A4 3
 '@BASEBOARD_FAB2_LIB.BASEBOARD_FAB2(SCH_1):PAGE219_I107@MSTR_DISCRETE.IR354XX(CHIPS)':
 'VCC': CDS_PINID='VCC';
NODE_NAME     R3L8 1
 '@BASEBOARD_FAB2_LIB.BASEBOARD_FAB2(SCH_1):PAGE219_I148@MSTR_DISCRETE.RES(CHIPS)':
 'A': CDS_PINID='A';
NET_NAME
'VR_PVDDQ_DEF_PWM1'
 '@BASEBOARD_FAB2_LIB.BASEBOARD_FAB2(SCH_1):VR_PVDDQ_DEF_PWM1':
 C_SIGNAL='@baseboard_fab2_lib.baseboard_fab2(sch_1):vr_pvddq_def_pwm1';
NODE_NAME     EU7A1 34
 '@BASEBOARD_FAB2_LIB.BASEBOARD_FAB2(SCH_1):PAGE219_I106@MSTR_DISCRETE.IR354XX(CHIPS)':
 'PWM': CDS_PINID='PWM';
NODE_NAME     EU7A5 5
 '@BASEBOARD_FAB2_LIB.BASEBOARD_FAB2(SCH_1):PAGE218_I69@MSTR_CONTROLLER.PXM1310B(CHIPS)':
 'APWM1': CDS_PINID='APWM1';
NET_NAME
'VR_PVDDQ_DEF_PWM2'
 '@BASEBOARD_FAB2_LIB.BASEBOARD_FAB2(SCH_1):VR_PVDDQ_DEF_PWM2':
 C_SIGNAL='@baseboard_fab2_lib.baseboard_fab2(sch_1):vr_pvddq_def_pwm2';
NODE_NAME     EU7A4 34
 '@BASEBOARD_FAB2_LIB.BASEBOARD_FAB2(SCH_1):PAGE219_I107@MSTR_DISCRETE.IR354XX(CHIPS)':
 'PWM': CDS_PINID='PWM';
NODE_NAME     EU7A5 4
 '@BASEBOARD_FAB2_LIB.BASEBOARD_FAB2(SCH_1):PAGE218_I69@MSTR_CONTROLLER.PXM1310B(CHIPS)':
 'APWM2': CDS_PINID='APWM2';
NET_NAME
'VR_PVDDQ_DEF_VD12'
 '@BASEBOARD_FAB2_LIB.BASEBOARD_FAB2(SCH_1):VR_PVDDQ_DEF_VD12':
 C_SIGNAL='@baseboard_fab2_lib.baseboard_fab2(sch_1):vr_pvddq_def_vd12';
NODE_NAME     C7B2 1
 '@BASEBOARD_FAB2_LIB.BASEBOARD_FAB2(SCH_1):PAGE218_I28@DEV_DISCRETE.CAP_A(CHIPS)':
 'A': CDS_PINID='A';
NODE_NAME     C7B1 1
 '@BASEBOARD_FAB2_LIB.BASEBOARD_FAB2(SCH_1):PAGE218_I30@DEV_DISCRETE.CAP_A(CHIPS)':
 'A': CDS_PINID='A';
NODE_NAME     EU7A5 40
 '@BASEBOARD_FAB2_LIB.BASEBOARD_FAB2(SCH_1):PAGE218_I69@MSTR_CONTROLLER.PXM1310B(CHIPS)':
 'VD12': CDS_PINID='VD12';
NET_NAME
'VR_PVDDQ_DEF_VDD'
 '@BASEBOARD_FAB2_LIB.BASEBOARD_FAB2(SCH_1):VR_PVDDQ_DEF_VDD':
 C_SIGNAL='@baseboard_fab2_lib.baseboard_fab2(sch_1):vr_pvddq_def_vdd';
NODE_NAME     R3M1 2
 '@BASEBOARD_FAB2_LIB.BASEBOARD_FAB2(SCH_1):PAGE218_I35@MSTR_DISCRETE.RES(CHIPS)':
 'B': CDS_PINID='B';
NODE_NAME     C7A38 1
 '@BASEBOARD_FAB2_LIB.BASEBOARD_FAB2(SCH_1):PAGE218_I38@DEV_DISCRETE.CAP_A(CHIPS)':
 'A': CDS_PINID='A';
NODE_NAME     EU7A5 39
 '@BASEBOARD_FAB2_LIB.BASEBOARD_FAB2(SCH_1):PAGE218_I69@MSTR_CONTROLLER.PXM1310B(CHIPS)':
 'VDD': CDS_PINID='VDD';
NODE_NAME     C7A37 1
 '@BASEBOARD_FAB2_LIB.BASEBOARD_FAB2(SCH_1):PAGE218_I40@DEV_DISCRETE.CAP_A(CHIPS)':
 'A': CDS_PINID='A';
NET_NAME
'VR_PVDDQ_DEF_VINSEN'
 '@BASEBOARD_FAB2_LIB.BASEBOARD_FAB2(SCH_1):VR_PVDDQ_DEF_VINSEN':
 C_SIGNAL='@baseboard_fab2_lib.baseboard_fab2(sch_1):vr_pvddq_def_vinsen';
NODE_NAME     EU7A5 37
 '@BASEBOARD_FAB2_LIB.BASEBOARD_FAB2(SCH_1):PAGE218_I69@MSTR_CONTROLLER.PXM1310B(CHIPS)':
 'VINSEN': CDS_PINID='VINSEN';
NODE_NAME     C12W2 2
 '@BASEBOARD_FAB2_LIB.BASEBOARD_FAB2(SCH_1):PAGE197_I1@MSTR_DISCRETE.CAP(CHIPS)':
 'B': CDS_PINID='B';
NODE_NAME     R12W10 2
 '@BASEBOARD_FAB2_LIB.BASEBOARD_FAB2(SCH_1):PAGE197_I109@W_HDL.665KR2B-GP(CHIPS)':
 '2': CDS_PINID='\2\';
NODE_NAME     R12W7 2
 '@BASEBOARD_FAB2_LIB.BASEBOARD_FAB2(SCH_1):PAGE197_I121@W_HDL.665KR5B-1-GP(CHIPS)':
 '2': CDS_PINID='\2\';
NET_NAME
'VR_PVDDQ_DEF_VREN'
 '@BASEBOARD_FAB2_LIB.BASEBOARD_FAB2(SCH_1):VR_PVDDQ_DEF_VREN':
 C_SIGNAL='@baseboard_fab2_lib.baseboard_fab2(sch_1):vr_pvddq_def_vren';
NODE_NAME     R3M6 2
 '@BASEBOARD_FAB2_LIB.BASEBOARD_FAB2(SCH_1):PAGE218_I15@MSTR_DISCRETE.RES(CHIPS)':
 'B': CDS_PINID='B';
NODE_NAME     R3M5 2
 '@BASEBOARD_FAB2_LIB.BASEBOARD_FAB2(SCH_1):PAGE218_I34@MSTR_DISCRETE.RES(CHIPS)':
 'B': CDS_PINID='B';
NODE_NAME     EU7A5 10
 '@BASEBOARD_FAB2_LIB.BASEBOARD_FAB2(SCH_1):PAGE218_I69@MSTR_CONTROLLER.PXM1310B(CHIPS)':
 'AVREN': CDS_PINID='AVREN';
NET_NAME
'VR_PVDDQ_DEF_XADDR1'
 '@BASEBOARD_FAB2_LIB.BASEBOARD_FAB2(SCH_1):VR_PVDDQ_DEF_XADDR1':
 C_SIGNAL='@baseboard_fab2_lib.baseboard_fab2(sch_1):vr_pvddq_def_xaddr1';
NODE_NAME     EU7A5 36
 '@BASEBOARD_FAB2_LIB.BASEBOARD_FAB2(SCH_1):PAGE218_I69@MSTR_CONTROLLER.PXM1310B(CHIPS)':
 'XADDR1': CDS_PINID='XADDR1';
NODE_NAME     R7A10 1
 '@BASEBOARD_FAB2_LIB.BASEBOARD_FAB2(SCH_1):PAGE218_I73@MSTR_DISCRETE.RES(CHIPS)':
 'A': CDS_PINID='A';
NET_NAME
'VR_PVDDQ_DEF_XADDR2'
 '@BASEBOARD_FAB2_LIB.BASEBOARD_FAB2(SCH_1):VR_PVDDQ_DEF_XADDR2':
 C_SIGNAL='@baseboard_fab2_lib.baseboard_fab2(sch_1):vr_pvddq_def_xaddr2';
NODE_NAME     EU7A5 33
 '@BASEBOARD_FAB2_LIB.BASEBOARD_FAB2(SCH_1):PAGE218_I69@MSTR_CONTROLLER.PXM1310B(CHIPS)':
 'XADDR2': CDS_PINID='XADDR2';
NODE_NAME     R7A8 1
 '@BASEBOARD_FAB2_LIB.BASEBOARD_FAB2(SCH_1):PAGE218_I74@MSTR_DISCRETE.RES(CHIPS)':
 'A': CDS_PINID='A';
NET_NAME
'VR_PVDDQ_GHJ_AIINSEN'
 '@BASEBOARD_FAB2_LIB.BASEBOARD_FAB2(SCH_1):VR_PVDDQ_GHJ_AIINSEN':
 C_SIGNAL='@baseboard_fab2_lib.baseboard_fab2(sch_1):vr_pvddq_ghj_aiinsen';
NODE_NAME     EU1G2 38
 '@BASEBOARD_FAB2_LIB.BASEBOARD_FAB2(SCH_1):PAGE223_I69@MSTR_CONTROLLER.PXM1310B(CHIPS)':
 'IINSEN': CDS_PINID='IINSEN';
NODE_NAME     C12W3 1
 '@BASEBOARD_FAB2_LIB.BASEBOARD_FAB2(SCH_1):PAGE197_I42@MSTR_DISCRETE.CAP(CHIPS)':
 'A': CDS_PINID='A';
NODE_NAME     R12W15 1
 '@BASEBOARD_FAB2_LIB.BASEBOARD_FAB2(SCH_1):PAGE197_I112@W_HDL.665KR2B-GP(CHIPS)':
 '1': CDS_PINID='\1\';
NODE_NAME     R12W11 2
 '@BASEBOARD_FAB2_LIB.BASEBOARD_FAB2(SCH_1):PAGE197_I118@W_HDL.665KR5B-1-GP(CHIPS)':
 '2': CDS_PINID='\2\';
NET_NAME
'VR_PVDDQ_GHJ_AIREF1'
 '@BASEBOARD_FAB2_LIB.BASEBOARD_FAB2(SCH_1):VR_PVDDQ_GHJ_AIREF1':
 C_SIGNAL='@baseboard_fab2_lib.baseboard_fab2(sch_1):vr_pvddq_ghj_airef1';
NODE_NAME     RF19 1
 '@BASEBOARD_FAB2_LIB.BASEBOARD_FAB2(SCH_1):PAGE223_I16@MSTR_DISCRETE.RES(CHIPS)':
 'A': CDS_PINID='A';
NODE_NAME     EU1G1 39
 '@BASEBOARD_FAB2_LIB.BASEBOARD_FAB2(SCH_1):PAGE224_I110@MSTR_DISCRETE.IR354XX(CHIPS)':
 'REFIN': CDS_PINID='REFIN';
NODE_NAME     CT30 1
 '@BASEBOARD_FAB2_LIB.BASEBOARD_FAB2(SCH_1):PAGE224_I117@DEV_DISCRETE.CAP_A(CHIPS)':
 'A': CDS_PINID='A';
NODE_NAME     CF19 1
 '@BASEBOARD_FAB2_LIB.BASEBOARD_FAB2(SCH_1):PAGE223_I15@W_HDL.SC22P50V2JN-4GP(CHIPS)':
 '1': CDS_PINID='\1\';
NODE_NAME     EU1G2 21
 '@BASEBOARD_FAB2_LIB.BASEBOARD_FAB2(SCH_1):PAGE223_I69@MSTR_CONTROLLER.PXM1310B(CHIPS)':
 'AIREF1': CDS_PINID='AIREF1';
NET_NAME
'VR_PVDDQ_GHJ_AIREF2'
 '@BASEBOARD_FAB2_LIB.BASEBOARD_FAB2(SCH_1):VR_PVDDQ_GHJ_AIREF2':
 C_SIGNAL='@baseboard_fab2_lib.baseboard_fab2(sch_1):vr_pvddq_ghj_airef2';
NODE_NAME     EU1F1 39
 '@BASEBOARD_FAB2_LIB.BASEBOARD_FAB2(SCH_1):PAGE224_I111@MSTR_DISCRETE.IR354XX(CHIPS)':
 'REFIN': CDS_PINID='REFIN';
NODE_NAME     CT31 1
 '@BASEBOARD_FAB2_LIB.BASEBOARD_FAB2(SCH_1):PAGE224_I124@DEV_DISCRETE.CAP_A(CHIPS)':
 'A': CDS_PINID='A';
NODE_NAME     RF20 1
 '@BASEBOARD_FAB2_LIB.BASEBOARD_FAB2(SCH_1):PAGE223_I19@MSTR_DISCRETE.RES(CHIPS)':
 'A': CDS_PINID='A';
NODE_NAME     EU1G2 23
 '@BASEBOARD_FAB2_LIB.BASEBOARD_FAB2(SCH_1):PAGE223_I69@MSTR_CONTROLLER.PXM1310B(CHIPS)':
 'AIREF2': CDS_PINID='AIREF2';
NODE_NAME     CF20 1
 '@BASEBOARD_FAB2_LIB.BASEBOARD_FAB2(SCH_1):PAGE223_I17@W_HDL.SC22P50V2JN-4GP(CHIPS)':
 '1': CDS_PINID='\1\';
NET_NAME
'VR_PVDDQ_GHJ_AVSP'
 '@BASEBOARD_FAB2_LIB.BASEBOARD_FAB2(SCH_1):VR_PVDDQ_GHJ_AVSP':
 C_SIGNAL='@baseboard_fab2_lib.baseboard_fab2(sch_1):vr_pvddq_ghj_avsp';
NODE_NAME     C1G16 1
 '@BASEBOARD_FAB2_LIB.BASEBOARD_FAB2(SCH_1):PAGE223_I12@MSTR_DISCRETE.CAP(CHIPS)':
 'A': CDS_PINID='A';
NODE_NAME     EU1G2 19
 '@BASEBOARD_FAB2_LIB.BASEBOARD_FAB2(SCH_1):PAGE223_I69@MSTR_CONTROLLER.PXM1310B(CHIPS)':
 'AVSEN': CDS_PINID='AVSEN';
NODE_NAME     R1G5 2
 '@BASEBOARD_FAB2_LIB.BASEBOARD_FAB2(SCH_1):PAGE223_I13@MSTR_DISCRETE.RES(CHIPS)':
 'B': CDS_PINID='B';
NET_NAME
'VR_PVDDQ_GHJ_PH1_BOOT'
 '@BASEBOARD_FAB2_LIB.BASEBOARD_FAB2(SCH_1):VR_PVDDQ_GHJ_PH1_BOOT':
 C_SIGNAL='@baseboard_fab2_lib.baseboard_fab2(sch_1):vr_pvddq_ghj_ph1_boot';
NODE_NAME     C1G11 1
 '@BASEBOARD_FAB2_LIB.BASEBOARD_FAB2(SCH_1):PAGE224_I44@MSTR_DISCRETE.CAP(CHIPS)':
 'A': CDS_PINID='A';
NODE_NAME     RT19 1
 '@BASEBOARD_FAB2_LIB.BASEBOARD_FAB2(SCH_1):PAGE224_I144@MSTR_DISCRETE.RES(CHIPS)':
 'A': CDS_PINID='A';
NET_NAME
'VR_PVDDQ_GHJ_PH1_BOOT_R'
 '@BASEBOARD_FAB2_LIB.BASEBOARD_FAB2(SCH_1):VR_PVDDQ_GHJ_PH1_BOOT_R':
 C_SIGNAL='@baseboard_fab2_lib.baseboard_fab2(sch_1):vr_pvddq_ghj_ph1_boot_r';
NODE_NAME     EU1G1 33
 '@BASEBOARD_FAB2_LIB.BASEBOARD_FAB2(SCH_1):PAGE224_I110@MSTR_DISCRETE.IR354XX(CHIPS)':
 'BOOST': CDS_PINID='BOOST';
NODE_NAME     RT19 2
 '@BASEBOARD_FAB2_LIB.BASEBOARD_FAB2(SCH_1):PAGE224_I144@MSTR_DISCRETE.RES(CHIPS)':
 'B': CDS_PINID='B';
NET_NAME
'VR_PVDDQ_GHJ_PH1_OCSET'
 '@BASEBOARD_FAB2_LIB.BASEBOARD_FAB2(SCH_1):VR_PVDDQ_GHJ_PH1_OCSET':
 C_SIGNAL='@baseboard_fab2_lib.baseboard_fab2(sch_1):vr_pvddq_ghj_ph1_ocset';
NODE_NAME     EU1G1 37
 '@BASEBOARD_FAB2_LIB.BASEBOARD_FAB2(SCH_1):PAGE224_I110@MSTR_DISCRETE.IR354XX(CHIPS)':
 'OCSET': CDS_PINID='OCSET';
NODE_NAME     R1G26 1
 '@BASEBOARD_FAB2_LIB.BASEBOARD_FAB2(SCH_1):PAGE224_I112@MSTR_DISCRETE.RES(CHIPS)':
 'A': CDS_PINID='A';
NET_NAME
'VR_PVDDQ_GHJ_PH1_PHASE'
 '@BASEBOARD_FAB2_LIB.BASEBOARD_FAB2(SCH_1):VR_PVDDQ_GHJ_PH1_PHASE':
 C_SIGNAL='@baseboard_fab2_lib.baseboard_fab2(sch_1):vr_pvddq_ghj_ph1_phase';
NODE_NAME     C1G11 2
 '@BASEBOARD_FAB2_LIB.BASEBOARD_FAB2(SCH_1):PAGE224_I44@MSTR_DISCRETE.CAP(CHIPS)':
 'B': CDS_PINID='B';
NODE_NAME     EU1G1 32
 '@BASEBOARD_FAB2_LIB.BASEBOARD_FAB2(SCH_1):PAGE224_I110@MSTR_DISCRETE.IR354XX(CHIPS)':
 'PHASE': CDS_PINID='PHASE';
NET_NAME
'VR_PVDDQ_GHJ_PH1_SW'
 '@BASEBOARD_FAB2_LIB.BASEBOARD_FAB2(SCH_1):VR_PVDDQ_GHJ_PH1_SW':
 C_SIGNAL='@baseboard_fab2_lib.baseboard_fab2(sch_1):vr_pvddq_ghj_ph1_sw';
NODE_NAME     EU1G1 10
 '@BASEBOARD_FAB2_LIB.BASEBOARD_FAB2(SCH_1):PAGE224_I110@MSTR_DISCRETE.IR354XX(CHIPS)':
 'SW': CDS_PINID='SW';
NODE_NAME     CT29 1
 '@BASEBOARD_FAB2_LIB.BASEBOARD_FAB2(SCH_1):PAGE224_I140@MSTR_DISCRETE.CAP(CHIPS)':
 'A': CDS_PINID='A';
NODE_NAME     L1G1 1
 '@BASEBOARD_FAB2_LIB.BASEBOARD_FAB2(SCH_1):PAGE224_I160@W_HDL.IND-120NH-30-GP(CHIPS)':
 'S': CDS_PINID='S';
NET_NAME
'VR_PVDDQ_GHJ_PH1_SW_RC'
 '@BASEBOARD_FAB2_LIB.BASEBOARD_FAB2(SCH_1):VR_PVDDQ_GHJ_PH1_SW_RC':
 C_SIGNAL='@baseboard_fab2_lib.baseboard_fab2(sch_1):vr_pvddq_ghj_ph1_sw_rc';
NODE_NAME     CT29 2
 '@BASEBOARD_FAB2_LIB.BASEBOARD_FAB2(SCH_1):PAGE224_I140@MSTR_DISCRETE.CAP(CHIPS)':
 'B': CDS_PINID='B';
NODE_NAME     RT20 1
 '@BASEBOARD_FAB2_LIB.BASEBOARD_FAB2(SCH_1):PAGE224_I156@W_HDL.1R3F-GP(CHIPS)':
 '1': CDS_PINID='\1\';
NET_NAME
'VR_PVDDQ_GHJ_PH1_VCIN'
 '@BASEBOARD_FAB2_LIB.BASEBOARD_FAB2(SCH_1):VR_PVDDQ_GHJ_PH1_VCIN':
 C_SIGNAL='@baseboard_fab2_lib.baseboard_fab2(sch_1):vr_pvddq_ghj_ph1_vcin';
NODE_NAME     C1G6 1
 '@BASEBOARD_FAB2_LIB.BASEBOARD_FAB2(SCH_1):PAGE224_I50@MSTR_DISCRETE.CAP(CHIPS)':
 'A': CDS_PINID='A';
NODE_NAME     EU1G1 3
 '@BASEBOARD_FAB2_LIB.BASEBOARD_FAB2(SCH_1):PAGE224_I110@MSTR_DISCRETE.IR354XX(CHIPS)':
 'VCC': CDS_PINID='VCC';
NODE_NAME     R9U1 1
 '@BASEBOARD_FAB2_LIB.BASEBOARD_FAB2(SCH_1):PAGE224_I150@MSTR_DISCRETE.RES(CHIPS)':
 'A': CDS_PINID='A';
NET_NAME
'VR_PVDDQ_GHJ_PH2_BOOT'
 '@BASEBOARD_FAB2_LIB.BASEBOARD_FAB2(SCH_1):VR_PVDDQ_GHJ_PH2_BOOT':
 C_SIGNAL='@baseboard_fab2_lib.baseboard_fab2(sch_1):vr_pvddq_ghj_ph2_boot';
NODE_NAME     C1F26 1
 '@BASEBOARD_FAB2_LIB.BASEBOARD_FAB2(SCH_1):PAGE224_I75@MSTR_DISCRETE.CAP(CHIPS)':
 'A': CDS_PINID='A';
NODE_NAME     RT21 1
 '@BASEBOARD_FAB2_LIB.BASEBOARD_FAB2(SCH_1):PAGE224_I145@MSTR_DISCRETE.RES(CHIPS)':
 'A': CDS_PINID='A';
NET_NAME
'VR_PVDDQ_GHJ_PH2_BOOT_R'
 '@BASEBOARD_FAB2_LIB.BASEBOARD_FAB2(SCH_1):VR_PVDDQ_GHJ_PH2_BOOT_R':
 C_SIGNAL='@baseboard_fab2_lib.baseboard_fab2(sch_1):vr_pvddq_ghj_ph2_boot_r';
NODE_NAME     EU1F1 33
 '@BASEBOARD_FAB2_LIB.BASEBOARD_FAB2(SCH_1):PAGE224_I111@MSTR_DISCRETE.IR354XX(CHIPS)':
 'BOOST': CDS_PINID='BOOST';
NODE_NAME     RT21 2
 '@BASEBOARD_FAB2_LIB.BASEBOARD_FAB2(SCH_1):PAGE224_I145@MSTR_DISCRETE.RES(CHIPS)':
 'B': CDS_PINID='B';
NET_NAME
'VR_PVDDQ_GHJ_PH2_OCSET'
 '@BASEBOARD_FAB2_LIB.BASEBOARD_FAB2(SCH_1):VR_PVDDQ_GHJ_PH2_OCSET':
 C_SIGNAL='@baseboard_fab2_lib.baseboard_fab2(sch_1):vr_pvddq_ghj_ph2_ocset';
NODE_NAME     EU1F1 37
 '@BASEBOARD_FAB2_LIB.BASEBOARD_FAB2(SCH_1):PAGE224_I111@MSTR_DISCRETE.IR354XX(CHIPS)':
 'OCSET': CDS_PINID='OCSET';
NODE_NAME     R1G25 1
 '@BASEBOARD_FAB2_LIB.BASEBOARD_FAB2(SCH_1):PAGE224_I114@MSTR_DISCRETE.RES(CHIPS)':
 'A': CDS_PINID='A';
NET_NAME
'VR_PVDDQ_GHJ_PH2_PHASE'
 '@BASEBOARD_FAB2_LIB.BASEBOARD_FAB2(SCH_1):VR_PVDDQ_GHJ_PH2_PHASE':
 C_SIGNAL='@baseboard_fab2_lib.baseboard_fab2(sch_1):vr_pvddq_ghj_ph2_phase';
NODE_NAME     C1F26 2
 '@BASEBOARD_FAB2_LIB.BASEBOARD_FAB2(SCH_1):PAGE224_I75@MSTR_DISCRETE.CAP(CHIPS)':
 'B': CDS_PINID='B';
NODE_NAME     EU1F1 32
 '@BASEBOARD_FAB2_LIB.BASEBOARD_FAB2(SCH_1):PAGE224_I111@MSTR_DISCRETE.IR354XX(CHIPS)':
 'PHASE': CDS_PINID='PHASE';
NET_NAME
'VR_PVDDQ_GHJ_PH2_SW'
 '@BASEBOARD_FAB2_LIB.BASEBOARD_FAB2(SCH_1):VR_PVDDQ_GHJ_PH2_SW':
 C_SIGNAL='@baseboard_fab2_lib.baseboard_fab2(sch_1):vr_pvddq_ghj_ph2_sw';
NODE_NAME     EU1F1 10
 '@BASEBOARD_FAB2_LIB.BASEBOARD_FAB2(SCH_1):PAGE224_I111@MSTR_DISCRETE.IR354XX(CHIPS)':
 'SW': CDS_PINID='SW';
NODE_NAME     CT33 1
 '@BASEBOARD_FAB2_LIB.BASEBOARD_FAB2(SCH_1):PAGE224_I141@MSTR_DISCRETE.CAP(CHIPS)':
 'A': CDS_PINID='A';
NODE_NAME     L1F2 1
 '@BASEBOARD_FAB2_LIB.BASEBOARD_FAB2(SCH_1):PAGE224_I161@W_HDL.IND-120NH-30-GP(CHIPS)':
 'S': CDS_PINID='S';
NET_NAME
'VR_PVDDQ_GHJ_PH2_SW_RC'
 '@BASEBOARD_FAB2_LIB.BASEBOARD_FAB2(SCH_1):VR_PVDDQ_GHJ_PH2_SW_RC':
 C_SIGNAL='@baseboard_fab2_lib.baseboard_fab2(sch_1):vr_pvddq_ghj_ph2_sw_rc';
NODE_NAME     CT33 2
 '@BASEBOARD_FAB2_LIB.BASEBOARD_FAB2(SCH_1):PAGE224_I141@MSTR_DISCRETE.CAP(CHIPS)':
 'B': CDS_PINID='B';
NODE_NAME     RT22 1
 '@BASEBOARD_FAB2_LIB.BASEBOARD_FAB2(SCH_1):PAGE224_I157@W_HDL.1R3F-GP(CHIPS)':
 '1': CDS_PINID='\1\';
NET_NAME
'VR_PVDDQ_GHJ_PH2_VCIN'
 '@BASEBOARD_FAB2_LIB.BASEBOARD_FAB2(SCH_1):VR_PVDDQ_GHJ_PH2_VCIN':
 C_SIGNAL='@baseboard_fab2_lib.baseboard_fab2(sch_1):vr_pvddq_ghj_ph2_vcin';
NODE_NAME     C1G28 1
 '@BASEBOARD_FAB2_LIB.BASEBOARD_FAB2(SCH_1):PAGE224_I77@MSTR_DISCRETE.CAP(CHIPS)':
 'A': CDS_PINID='A';
NODE_NAME     EU1F1 3
 '@BASEBOARD_FAB2_LIB.BASEBOARD_FAB2(SCH_1):PAGE224_I111@MSTR_DISCRETE.IR354XX(CHIPS)':
 'VCC': CDS_PINID='VCC';
NODE_NAME     R9U12 1
 '@BASEBOARD_FAB2_LIB.BASEBOARD_FAB2(SCH_1):PAGE224_I151@MSTR_DISCRETE.RES(CHIPS)':
 'A': CDS_PINID='A';
NET_NAME
'VR_PVDDQ_GHJ_PWM1'
 '@BASEBOARD_FAB2_LIB.BASEBOARD_FAB2(SCH_1):VR_PVDDQ_GHJ_PWM1':
 C_SIGNAL='@baseboard_fab2_lib.baseboard_fab2(sch_1):vr_pvddq_ghj_pwm1';
NODE_NAME     EU1G1 34
 '@BASEBOARD_FAB2_LIB.BASEBOARD_FAB2(SCH_1):PAGE224_I110@MSTR_DISCRETE.IR354XX(CHIPS)':
 'PWM': CDS_PINID='PWM';
NODE_NAME     EU1G2 5
 '@BASEBOARD_FAB2_LIB.BASEBOARD_FAB2(SCH_1):PAGE223_I69@MSTR_CONTROLLER.PXM1310B(CHIPS)':
 'APWM1': CDS_PINID='APWM1';
NET_NAME
'VR_PVDDQ_GHJ_PWM2'
 '@BASEBOARD_FAB2_LIB.BASEBOARD_FAB2(SCH_1):VR_PVDDQ_GHJ_PWM2':
 C_SIGNAL='@baseboard_fab2_lib.baseboard_fab2(sch_1):vr_pvddq_ghj_pwm2';
NODE_NAME     EU1F1 34
 '@BASEBOARD_FAB2_LIB.BASEBOARD_FAB2(SCH_1):PAGE224_I111@MSTR_DISCRETE.IR354XX(CHIPS)':
 'PWM': CDS_PINID='PWM';
NODE_NAME     EU1G2 4
 '@BASEBOARD_FAB2_LIB.BASEBOARD_FAB2(SCH_1):PAGE223_I69@MSTR_CONTROLLER.PXM1310B(CHIPS)':
 'APWM2': CDS_PINID='APWM2';
NET_NAME
'VR_PVDDQ_GHJ_VD12'
 '@BASEBOARD_FAB2_LIB.BASEBOARD_FAB2(SCH_1):VR_PVDDQ_GHJ_VD12':
 C_SIGNAL='@baseboard_fab2_lib.baseboard_fab2(sch_1):vr_pvddq_ghj_vd12';
NODE_NAME     C1G23 1
 '@BASEBOARD_FAB2_LIB.BASEBOARD_FAB2(SCH_1):PAGE223_I44@DEV_DISCRETE.CAP_A(CHIPS)':
 'A': CDS_PINID='A';
NODE_NAME     C1G22 1
 '@BASEBOARD_FAB2_LIB.BASEBOARD_FAB2(SCH_1):PAGE223_I43@DEV_DISCRETE.CAP_A(CHIPS)':
 'A': CDS_PINID='A';
NODE_NAME     EU1G2 40
 '@BASEBOARD_FAB2_LIB.BASEBOARD_FAB2(SCH_1):PAGE223_I69@MSTR_CONTROLLER.PXM1310B(CHIPS)':
 'VD12': CDS_PINID='VD12';
NET_NAME
'VR_PVDDQ_GHJ_VDD'
 '@BASEBOARD_FAB2_LIB.BASEBOARD_FAB2(SCH_1):VR_PVDDQ_GHJ_VDD':
 C_SIGNAL='@baseboard_fab2_lib.baseboard_fab2(sch_1):vr_pvddq_ghj_vdd';
NODE_NAME     C1G25 1
 '@BASEBOARD_FAB2_LIB.BASEBOARD_FAB2(SCH_1):PAGE223_I35@DEV_DISCRETE.CAP_A(CHIPS)':
 'A': CDS_PINID='A';
NODE_NAME     EU1G2 39
 '@BASEBOARD_FAB2_LIB.BASEBOARD_FAB2(SCH_1):PAGE223_I69@MSTR_CONTROLLER.PXM1310B(CHIPS)':
 'VDD': CDS_PINID='VDD';
NODE_NAME     R9U10 2
 '@BASEBOARD_FAB2_LIB.BASEBOARD_FAB2(SCH_1):PAGE223_I32@MSTR_DISCRETE.RES(CHIPS)':
 'B': CDS_PINID='B';
NODE_NAME     C1G27 1
 '@BASEBOARD_FAB2_LIB.BASEBOARD_FAB2(SCH_1):PAGE223_I36@DEV_DISCRETE.CAP_A(CHIPS)':
 'A': CDS_PINID='A';
NET_NAME
'VR_PVDDQ_GHJ_VINSEN'
 '@BASEBOARD_FAB2_LIB.BASEBOARD_FAB2(SCH_1):VR_PVDDQ_GHJ_VINSEN':
 C_SIGNAL='@baseboard_fab2_lib.baseboard_fab2(sch_1):vr_pvddq_ghj_vinsen';
NODE_NAME     EU1G2 37
 '@BASEBOARD_FAB2_LIB.BASEBOARD_FAB2(SCH_1):PAGE223_I69@MSTR_CONTROLLER.PXM1310B(CHIPS)':
 'VINSEN': CDS_PINID='VINSEN';
NODE_NAME     C12W3 2
 '@BASEBOARD_FAB2_LIB.BASEBOARD_FAB2(SCH_1):PAGE197_I42@MSTR_DISCRETE.CAP(CHIPS)':
 'B': CDS_PINID='B';
NODE_NAME     R12W15 2
 '@BASEBOARD_FAB2_LIB.BASEBOARD_FAB2(SCH_1):PAGE197_I112@W_HDL.665KR2B-GP(CHIPS)':
 '2': CDS_PINID='\2\';
NODE_NAME     R12W12 2
 '@BASEBOARD_FAB2_LIB.BASEBOARD_FAB2(SCH_1):PAGE197_I119@W_HDL.665KR5B-1-GP(CHIPS)':
 '2': CDS_PINID='\2\';
NET_NAME
'VR_PVDDQ_GHJ_VREN'
 '@BASEBOARD_FAB2_LIB.BASEBOARD_FAB2(SCH_1):VR_PVDDQ_GHJ_VREN':
 C_SIGNAL='@baseboard_fab2_lib.baseboard_fab2(sch_1):vr_pvddq_ghj_vren';
NODE_NAME     R9U7 2
 '@BASEBOARD_FAB2_LIB.BASEBOARD_FAB2(SCH_1):PAGE223_I14@MSTR_DISCRETE.RES(CHIPS)':
 'B': CDS_PINID='B';
NODE_NAME     R9U8 2
 '@BASEBOARD_FAB2_LIB.BASEBOARD_FAB2(SCH_1):PAGE223_I31@MSTR_DISCRETE.RES(CHIPS)':
 'B': CDS_PINID='B';
NODE_NAME     EU1G2 10
 '@BASEBOARD_FAB2_LIB.BASEBOARD_FAB2(SCH_1):PAGE223_I69@MSTR_CONTROLLER.PXM1310B(CHIPS)':
 'AVREN': CDS_PINID='AVREN';
NET_NAME
'VR_PVDDQ_GHJ_XADDR1'
 '@BASEBOARD_FAB2_LIB.BASEBOARD_FAB2(SCH_1):VR_PVDDQ_GHJ_XADDR1':
 C_SIGNAL='@baseboard_fab2_lib.baseboard_fab2(sch_1):vr_pvddq_ghj_xaddr1';
NODE_NAME     EU1G2 36
 '@BASEBOARD_FAB2_LIB.BASEBOARD_FAB2(SCH_1):PAGE223_I69@MSTR_CONTROLLER.PXM1310B(CHIPS)':
 'XADDR1': CDS_PINID='XADDR1';
NODE_NAME     R1G23 1
 '@BASEBOARD_FAB2_LIB.BASEBOARD_FAB2(SCH_1):PAGE223_I73@MSTR_DISCRETE.RES(CHIPS)':
 'A': CDS_PINID='A';
NET_NAME
'VR_PVDDQ_GHJ_XADDR2'
 '@BASEBOARD_FAB2_LIB.BASEBOARD_FAB2(SCH_1):VR_PVDDQ_GHJ_XADDR2':
 C_SIGNAL='@baseboard_fab2_lib.baseboard_fab2(sch_1):vr_pvddq_ghj_xaddr2';
NODE_NAME     EU1G2 33
 '@BASEBOARD_FAB2_LIB.BASEBOARD_FAB2(SCH_1):PAGE223_I69@MSTR_CONTROLLER.PXM1310B(CHIPS)':
 'XADDR2': CDS_PINID='XADDR2';
NODE_NAME     R1G22 1
 '@BASEBOARD_FAB2_LIB.BASEBOARD_FAB2(SCH_1):PAGE223_I74@MSTR_DISCRETE.RES(CHIPS)':
 'A': CDS_PINID='A';
NET_NAME
'VR_PVDDQ_KLM_AIINSEN'
 '@BASEBOARD_FAB2_LIB.BASEBOARD_FAB2(SCH_1):VR_PVDDQ_KLM_AIINSEN':
 C_SIGNAL='@baseboard_fab2_lib.baseboard_fab2(sch_1):vr_pvddq_klm_aiinsen';
NODE_NAME     EU1B1 38
 '@BASEBOARD_FAB2_LIB.BASEBOARD_FAB2(SCH_1):PAGE226_I69@MSTR_CONTROLLER.PXM1310B(CHIPS)':
 'IINSEN': CDS_PINID='IINSEN';
NODE_NAME     C12W4 1
 '@BASEBOARD_FAB2_LIB.BASEBOARD_FAB2(SCH_1):PAGE197_I18@MSTR_DISCRETE.CAP(CHIPS)':
 'A': CDS_PINID='A';
NODE_NAME     R12W20 1
 '@BASEBOARD_FAB2_LIB.BASEBOARD_FAB2(SCH_1):PAGE197_I110@W_HDL.665KR2B-GP(CHIPS)':
 '1': CDS_PINID='\1\';
NODE_NAME     R12W16 2
 '@BASEBOARD_FAB2_LIB.BASEBOARD_FAB2(SCH_1):PAGE197_I122@W_HDL.665KR5B-1-GP(CHIPS)':
 '2': CDS_PINID='\2\';
NET_NAME
'VR_PVDDQ_KLM_AIREF1'
 '@BASEBOARD_FAB2_LIB.BASEBOARD_FAB2(SCH_1):VR_PVDDQ_KLM_AIREF1':
 C_SIGNAL='@baseboard_fab2_lib.baseboard_fab2(sch_1):vr_pvddq_klm_airef1';
NODE_NAME     RF21 1
 '@BASEBOARD_FAB2_LIB.BASEBOARD_FAB2(SCH_1):PAGE226_I16@MSTR_DISCRETE.RES(CHIPS)':
 'A': CDS_PINID='A';
NODE_NAME     EU1A2 39
 '@BASEBOARD_FAB2_LIB.BASEBOARD_FAB2(SCH_1):PAGE227_I101@MSTR_DISCRETE.IR354XX(CHIPS)':
 'REFIN': CDS_PINID='REFIN';
NODE_NAME     CT7 1
 '@BASEBOARD_FAB2_LIB.BASEBOARD_FAB2(SCH_1):PAGE227_I109@DEV_DISCRETE.CAP_A(CHIPS)':
 'A': CDS_PINID='A';
NODE_NAME     CF21 1
 '@BASEBOARD_FAB2_LIB.BASEBOARD_FAB2(SCH_1):PAGE226_I15@W_HDL.SC22P50V2JN-4GP(CHIPS)':
 '1': CDS_PINID='\1\';
NODE_NAME     EU1B1 21
 '@BASEBOARD_FAB2_LIB.BASEBOARD_FAB2(SCH_1):PAGE226_I69@MSTR_CONTROLLER.PXM1310B(CHIPS)':
 'AIREF1': CDS_PINID='AIREF1';
NET_NAME
'VR_PVDDQ_KLM_AIREF2'
 '@BASEBOARD_FAB2_LIB.BASEBOARD_FAB2(SCH_1):VR_PVDDQ_KLM_AIREF2':
 C_SIGNAL='@baseboard_fab2_lib.baseboard_fab2(sch_1):vr_pvddq_klm_airef2';
NODE_NAME     EU1A1 39
 '@BASEBOARD_FAB2_LIB.BASEBOARD_FAB2(SCH_1):PAGE227_I102@MSTR_DISCRETE.IR354XX(CHIPS)':
 'REFIN': CDS_PINID='REFIN';
NODE_NAME     CT12 1
 '@BASEBOARD_FAB2_LIB.BASEBOARD_FAB2(SCH_1):PAGE227_I122@DEV_DISCRETE.CAP_A(CHIPS)':
 'A': CDS_PINID='A';
NODE_NAME     RF22 1
 '@BASEBOARD_FAB2_LIB.BASEBOARD_FAB2(SCH_1):PAGE226_I18@MSTR_DISCRETE.RES(CHIPS)':
 'A': CDS_PINID='A';
NODE_NAME     EU1B1 23
 '@BASEBOARD_FAB2_LIB.BASEBOARD_FAB2(SCH_1):PAGE226_I69@MSTR_CONTROLLER.PXM1310B(CHIPS)':
 'AIREF2': CDS_PINID='AIREF2';
NODE_NAME     CF22 1
 '@BASEBOARD_FAB2_LIB.BASEBOARD_FAB2(SCH_1):PAGE226_I17@W_HDL.SC22P50V2JN-4GP(CHIPS)':
 '1': CDS_PINID='\1\';
NET_NAME
'VR_PVDDQ_KLM_AVSP'
 '@BASEBOARD_FAB2_LIB.BASEBOARD_FAB2(SCH_1):VR_PVDDQ_KLM_AVSP':
 C_SIGNAL='@baseboard_fab2_lib.baseboard_fab2(sch_1):vr_pvddq_klm_avsp';
NODE_NAME     C1B12 1
 '@BASEBOARD_FAB2_LIB.BASEBOARD_FAB2(SCH_1):PAGE226_I12@MSTR_DISCRETE.CAP(CHIPS)':
 'A': CDS_PINID='A';
NODE_NAME     EU1B1 19
 '@BASEBOARD_FAB2_LIB.BASEBOARD_FAB2(SCH_1):PAGE226_I69@MSTR_CONTROLLER.PXM1310B(CHIPS)':
 'AVSEN': CDS_PINID='AVSEN';
NODE_NAME     R1B16 2
 '@BASEBOARD_FAB2_LIB.BASEBOARD_FAB2(SCH_1):PAGE226_I13@MSTR_DISCRETE.RES(CHIPS)':
 'B': CDS_PINID='B';
NET_NAME
'VR_PVDDQ_KLM_PH1_BOOT'
 '@BASEBOARD_FAB2_LIB.BASEBOARD_FAB2(SCH_1):VR_PVDDQ_KLM_PH1_BOOT':
 C_SIGNAL='@baseboard_fab2_lib.baseboard_fab2(sch_1):vr_pvddq_klm_ph1_boot';
NODE_NAME     C1A18 1
 '@BASEBOARD_FAB2_LIB.BASEBOARD_FAB2(SCH_1):PAGE227_I44@MSTR_DISCRETE.CAP(CHIPS)':
 'A': CDS_PINID='A';
NODE_NAME     RT5 1
 '@BASEBOARD_FAB2_LIB.BASEBOARD_FAB2(SCH_1):PAGE227_I138@MSTR_DISCRETE.RES(CHIPS)':
 'A': CDS_PINID='A';
NET_NAME
'VR_PVDDQ_KLM_PH1_BOOT_R'
 '@BASEBOARD_FAB2_LIB.BASEBOARD_FAB2(SCH_1):VR_PVDDQ_KLM_PH1_BOOT_R':
 C_SIGNAL='@baseboard_fab2_lib.baseboard_fab2(sch_1):vr_pvddq_klm_ph1_boot_r';
NODE_NAME     EU1A2 33
 '@BASEBOARD_FAB2_LIB.BASEBOARD_FAB2(SCH_1):PAGE227_I101@MSTR_DISCRETE.IR354XX(CHIPS)':
 'BOOST': CDS_PINID='BOOST';
NODE_NAME     RT5 2
 '@BASEBOARD_FAB2_LIB.BASEBOARD_FAB2(SCH_1):PAGE227_I138@MSTR_DISCRETE.RES(CHIPS)':
 'B': CDS_PINID='B';
NET_NAME
'VR_PVDDQ_KLM_PH1_OCSET'
 '@BASEBOARD_FAB2_LIB.BASEBOARD_FAB2(SCH_1):VR_PVDDQ_KLM_PH1_OCSET':
 C_SIGNAL='@baseboard_fab2_lib.baseboard_fab2(sch_1):vr_pvddq_klm_ph1_ocset';
NODE_NAME     EU1A2 37
 '@BASEBOARD_FAB2_LIB.BASEBOARD_FAB2(SCH_1):PAGE227_I101@MSTR_DISCRETE.IR354XX(CHIPS)':
 'OCSET': CDS_PINID='OCSET';
NODE_NAME     R1A3 1
 '@BASEBOARD_FAB2_LIB.BASEBOARD_FAB2(SCH_1):PAGE227_I103@MSTR_DISCRETE.RES(CHIPS)':
 'A': CDS_PINID='A';
NET_NAME
'VR_PVDDQ_KLM_PH1_PHASE'
 '@BASEBOARD_FAB2_LIB.BASEBOARD_FAB2(SCH_1):VR_PVDDQ_KLM_PH1_PHASE':
 C_SIGNAL='@baseboard_fab2_lib.baseboard_fab2(sch_1):vr_pvddq_klm_ph1_phase';
NODE_NAME     C1A18 2
 '@BASEBOARD_FAB2_LIB.BASEBOARD_FAB2(SCH_1):PAGE227_I44@MSTR_DISCRETE.CAP(CHIPS)':
 'B': CDS_PINID='B';
NODE_NAME     EU1A2 32
 '@BASEBOARD_FAB2_LIB.BASEBOARD_FAB2(SCH_1):PAGE227_I101@MSTR_DISCRETE.IR354XX(CHIPS)':
 'PHASE': CDS_PINID='PHASE';
NET_NAME
'VR_PVDDQ_KLM_PH1_RC'
 '@BASEBOARD_FAB2_LIB.BASEBOARD_FAB2(SCH_1):VR_PVDDQ_KLM_PH1_RC':
 C_SIGNAL='@baseboard_fab2_lib.baseboard_fab2(sch_1):vr_pvddq_klm_ph1_rc';
NODE_NAME     CT9 2
 '@BASEBOARD_FAB2_LIB.BASEBOARD_FAB2(SCH_1):PAGE227_I134@MSTR_DISCRETE.CAP(CHIPS)':
 'B': CDS_PINID='B';
NODE_NAME     RT6 1
 '@BASEBOARD_FAB2_LIB.BASEBOARD_FAB2(SCH_1):PAGE227_I149@W_HDL.1R3F-GP(CHIPS)':
 '1': CDS_PINID='\1\';
NET_NAME
'VR_PVDDQ_KLM_PH1_SW'
 '@BASEBOARD_FAB2_LIB.BASEBOARD_FAB2(SCH_1):VR_PVDDQ_KLM_PH1_SW':
 C_SIGNAL='@baseboard_fab2_lib.baseboard_fab2(sch_1):vr_pvddq_klm_ph1_sw';
NODE_NAME     EU1A2 10
 '@BASEBOARD_FAB2_LIB.BASEBOARD_FAB2(SCH_1):PAGE227_I101@MSTR_DISCRETE.IR354XX(CHIPS)':
 'SW': CDS_PINID='SW';
NODE_NAME     CT9 1
 '@BASEBOARD_FAB2_LIB.BASEBOARD_FAB2(SCH_1):PAGE227_I134@MSTR_DISCRETE.CAP(CHIPS)':
 'A': CDS_PINID='A';
NODE_NAME     L1A2 1
 '@BASEBOARD_FAB2_LIB.BASEBOARD_FAB2(SCH_1):PAGE227_I152@W_HDL.IND-120NH-30-GP(CHIPS)':
 'S': CDS_PINID='S';
NET_NAME
'VR_PVDDQ_KLM_PH1_VCIN'
 '@BASEBOARD_FAB2_LIB.BASEBOARD_FAB2(SCH_1):VR_PVDDQ_KLM_PH1_VCIN':
 C_SIGNAL='@baseboard_fab2_lib.baseboard_fab2(sch_1):vr_pvddq_klm_ph1_vcin';
NODE_NAME     C1B20 1
 '@BASEBOARD_FAB2_LIB.BASEBOARD_FAB2(SCH_1):PAGE227_I50@MSTR_DISCRETE.CAP(CHIPS)':
 'A': CDS_PINID='A';
NODE_NAME     EU1A2 3
 '@BASEBOARD_FAB2_LIB.BASEBOARD_FAB2(SCH_1):PAGE227_I101@MSTR_DISCRETE.IR354XX(CHIPS)':
 'VCC': CDS_PINID='VCC';
NODE_NAME     R9L9 1
 '@BASEBOARD_FAB2_LIB.BASEBOARD_FAB2(SCH_1):PAGE227_I154@MSTR_DISCRETE.RES(CHIPS)':
 'A': CDS_PINID='A';
NET_NAME
'VR_PVDDQ_KLM_PH2_BOOT'
 '@BASEBOARD_FAB2_LIB.BASEBOARD_FAB2(SCH_1):VR_PVDDQ_KLM_PH2_BOOT':
 C_SIGNAL='@baseboard_fab2_lib.baseboard_fab2(sch_1):vr_pvddq_klm_ph2_boot';
NODE_NAME     C1A8 1
 '@BASEBOARD_FAB2_LIB.BASEBOARD_FAB2(SCH_1):PAGE227_I75@MSTR_DISCRETE.CAP(CHIPS)':
 'A': CDS_PINID='A';
NODE_NAME     RT8 1
 '@BASEBOARD_FAB2_LIB.BASEBOARD_FAB2(SCH_1):PAGE227_I139@MSTR_DISCRETE.RES(CHIPS)':
 'A': CDS_PINID='A';
NET_NAME
'VR_PVDDQ_KLM_PH2_BOOT_R'
 '@BASEBOARD_FAB2_LIB.BASEBOARD_FAB2(SCH_1):VR_PVDDQ_KLM_PH2_BOOT_R':
 C_SIGNAL='@baseboard_fab2_lib.baseboard_fab2(sch_1):vr_pvddq_klm_ph2_boot_r';
NODE_NAME     EU1A1 33
 '@BASEBOARD_FAB2_LIB.BASEBOARD_FAB2(SCH_1):PAGE227_I102@MSTR_DISCRETE.IR354XX(CHIPS)':
 'BOOST': CDS_PINID='BOOST';
NODE_NAME     RT8 2
 '@BASEBOARD_FAB2_LIB.BASEBOARD_FAB2(SCH_1):PAGE227_I139@MSTR_DISCRETE.RES(CHIPS)':
 'B': CDS_PINID='B';
NET_NAME
'VR_PVDDQ_KLM_PH2_OCSET'
 '@BASEBOARD_FAB2_LIB.BASEBOARD_FAB2(SCH_1):VR_PVDDQ_KLM_PH2_OCSET':
 C_SIGNAL='@baseboard_fab2_lib.baseboard_fab2(sch_1):vr_pvddq_klm_ph2_ocset';
NODE_NAME     EU1A1 37
 '@BASEBOARD_FAB2_LIB.BASEBOARD_FAB2(SCH_1):PAGE227_I102@MSTR_DISCRETE.IR354XX(CHIPS)':
 'OCSET': CDS_PINID='OCSET';
NODE_NAME     R1A2 1
 '@BASEBOARD_FAB2_LIB.BASEBOARD_FAB2(SCH_1):PAGE227_I105@MSTR_DISCRETE.RES(CHIPS)':
 'A': CDS_PINID='A';
NET_NAME
'VR_PVDDQ_KLM_PH2_PHASE'
 '@BASEBOARD_FAB2_LIB.BASEBOARD_FAB2(SCH_1):VR_PVDDQ_KLM_PH2_PHASE':
 C_SIGNAL='@baseboard_fab2_lib.baseboard_fab2(sch_1):vr_pvddq_klm_ph2_phase';
NODE_NAME     C1A8 2
 '@BASEBOARD_FAB2_LIB.BASEBOARD_FAB2(SCH_1):PAGE227_I75@MSTR_DISCRETE.CAP(CHIPS)':
 'B': CDS_PINID='B';
NODE_NAME     EU1A1 32
 '@BASEBOARD_FAB2_LIB.BASEBOARD_FAB2(SCH_1):PAGE227_I102@MSTR_DISCRETE.IR354XX(CHIPS)':
 'PHASE': CDS_PINID='PHASE';
NET_NAME
'VR_PVDDQ_KLM_PH2_RC'
 '@BASEBOARD_FAB2_LIB.BASEBOARD_FAB2(SCH_1):VR_PVDDQ_KLM_PH2_RC':
 C_SIGNAL='@baseboard_fab2_lib.baseboard_fab2(sch_1):vr_pvddq_klm_ph2_rc';
NODE_NAME     CT11 2
 '@BASEBOARD_FAB2_LIB.BASEBOARD_FAB2(SCH_1):PAGE227_I135@MSTR_DISCRETE.CAP(CHIPS)':
 'B': CDS_PINID='B';
NODE_NAME     RT7 1
 '@BASEBOARD_FAB2_LIB.BASEBOARD_FAB2(SCH_1):PAGE227_I150@W_HDL.1R3F-GP(CHIPS)':
 '1': CDS_PINID='\1\';
NET_NAME
'VR_PVDDQ_KLM_PH2_SW'
 '@BASEBOARD_FAB2_LIB.BASEBOARD_FAB2(SCH_1):VR_PVDDQ_KLM_PH2_SW':
 C_SIGNAL='@baseboard_fab2_lib.baseboard_fab2(sch_1):vr_pvddq_klm_ph2_sw';
NODE_NAME     EU1A1 10
 '@BASEBOARD_FAB2_LIB.BASEBOARD_FAB2(SCH_1):PAGE227_I102@MSTR_DISCRETE.IR354XX(CHIPS)':
 'SW': CDS_PINID='SW';
NODE_NAME     CT11 1
 '@BASEBOARD_FAB2_LIB.BASEBOARD_FAB2(SCH_1):PAGE227_I135@MSTR_DISCRETE.CAP(CHIPS)':
 'A': CDS_PINID='A';
NODE_NAME     L1A1 1
 '@BASEBOARD_FAB2_LIB.BASEBOARD_FAB2(SCH_1):PAGE227_I153@W_HDL.IND-120NH-30-GP(CHIPS)':
 'S': CDS_PINID='S';
NET_NAME
'VR_PVDDQ_KLM_PH2_VCIN'
 '@BASEBOARD_FAB2_LIB.BASEBOARD_FAB2(SCH_1):VR_PVDDQ_KLM_PH2_VCIN':
 C_SIGNAL='@baseboard_fab2_lib.baseboard_fab2(sch_1):vr_pvddq_klm_ph2_vcin';
NODE_NAME     C1A6 1
 '@BASEBOARD_FAB2_LIB.BASEBOARD_FAB2(SCH_1):PAGE227_I77@MSTR_DISCRETE.CAP(CHIPS)':
 'A': CDS_PINID='A';
NODE_NAME     EU1A1 3
 '@BASEBOARD_FAB2_LIB.BASEBOARD_FAB2(SCH_1):PAGE227_I102@MSTR_DISCRETE.IR354XX(CHIPS)':
 'VCC': CDS_PINID='VCC';
NODE_NAME     R9L4 1
 '@BASEBOARD_FAB2_LIB.BASEBOARD_FAB2(SCH_1):PAGE227_I155@MSTR_DISCRETE.RES(CHIPS)':
 'A': CDS_PINID='A';
NET_NAME
'VR_PVDDQ_KLM_PWM1'
 '@BASEBOARD_FAB2_LIB.BASEBOARD_FAB2(SCH_1):VR_PVDDQ_KLM_PWM1':
 C_SIGNAL='@baseboard_fab2_lib.baseboard_fab2(sch_1):vr_pvddq_klm_pwm1';
NODE_NAME     EU1A2 34
 '@BASEBOARD_FAB2_LIB.BASEBOARD_FAB2(SCH_1):PAGE227_I101@MSTR_DISCRETE.IR354XX(CHIPS)':
 'PWM': CDS_PINID='PWM';
NODE_NAME     EU1B1 5
 '@BASEBOARD_FAB2_LIB.BASEBOARD_FAB2(SCH_1):PAGE226_I69@MSTR_CONTROLLER.PXM1310B(CHIPS)':
 'APWM1': CDS_PINID='APWM1';
NET_NAME
'VR_PVDDQ_KLM_PWM2'
 '@BASEBOARD_FAB2_LIB.BASEBOARD_FAB2(SCH_1):VR_PVDDQ_KLM_PWM2':
 C_SIGNAL='@baseboard_fab2_lib.baseboard_fab2(sch_1):vr_pvddq_klm_pwm2';
NODE_NAME     EU1A1 34
 '@BASEBOARD_FAB2_LIB.BASEBOARD_FAB2(SCH_1):PAGE227_I102@MSTR_DISCRETE.IR354XX(CHIPS)':
 'PWM': CDS_PINID='PWM';
NODE_NAME     EU1B1 4
 '@BASEBOARD_FAB2_LIB.BASEBOARD_FAB2(SCH_1):PAGE226_I69@MSTR_CONTROLLER.PXM1310B(CHIPS)':
 'APWM2': CDS_PINID='APWM2';
NET_NAME
'VR_PVDDQ_KLM_VD12'
 '@BASEBOARD_FAB2_LIB.BASEBOARD_FAB2(SCH_1):VR_PVDDQ_KLM_VD12':
 C_SIGNAL='@baseboard_fab2_lib.baseboard_fab2(sch_1):vr_pvddq_klm_vd12';
NODE_NAME     C1B2 1
 '@BASEBOARD_FAB2_LIB.BASEBOARD_FAB2(SCH_1):PAGE226_I44@DEV_DISCRETE.CAP_A(CHIPS)':
 'A': CDS_PINID='A';
NODE_NAME     C1B3 1
 '@BASEBOARD_FAB2_LIB.BASEBOARD_FAB2(SCH_1):PAGE226_I45@DEV_DISCRETE.CAP_A(CHIPS)':
 'A': CDS_PINID='A';
NODE_NAME     EU1B1 40
 '@BASEBOARD_FAB2_LIB.BASEBOARD_FAB2(SCH_1):PAGE226_I69@MSTR_CONTROLLER.PXM1310B(CHIPS)':
 'VD12': CDS_PINID='VD12';
NET_NAME
'VR_PVDDQ_KLM_VDD'
 '@BASEBOARD_FAB2_LIB.BASEBOARD_FAB2(SCH_1):VR_PVDDQ_KLM_VDD':
 C_SIGNAL='@baseboard_fab2_lib.baseboard_fab2(sch_1):vr_pvddq_klm_vdd';
NODE_NAME     C1B6 1
 '@BASEBOARD_FAB2_LIB.BASEBOARD_FAB2(SCH_1):PAGE226_I38@DEV_DISCRETE.CAP_A(CHIPS)':
 'A': CDS_PINID='A';
NODE_NAME     EU1B1 39
 '@BASEBOARD_FAB2_LIB.BASEBOARD_FAB2(SCH_1):PAGE226_I69@MSTR_CONTROLLER.PXM1310B(CHIPS)':
 'VDD': CDS_PINID='VDD';
NODE_NAME     C1B5 1
 '@BASEBOARD_FAB2_LIB.BASEBOARD_FAB2(SCH_1):PAGE226_I32@DEV_DISCRETE.CAP_A(CHIPS)':
 'A': CDS_PINID='A';
NODE_NAME     R9M3 2
 '@BASEBOARD_FAB2_LIB.BASEBOARD_FAB2(SCH_1):PAGE226_I36@MSTR_DISCRETE.RES(CHIPS)':
 'B': CDS_PINID='B';
NET_NAME
'VR_PVDDQ_KLM_VINSEN'
 '@BASEBOARD_FAB2_LIB.BASEBOARD_FAB2(SCH_1):VR_PVDDQ_KLM_VINSEN':
 C_SIGNAL='@baseboard_fab2_lib.baseboard_fab2(sch_1):vr_pvddq_klm_vinsen';
NODE_NAME     EU1B1 37
 '@BASEBOARD_FAB2_LIB.BASEBOARD_FAB2(SCH_1):PAGE226_I69@MSTR_CONTROLLER.PXM1310B(CHIPS)':
 'VINSEN': CDS_PINID='VINSEN';
NODE_NAME     C12W4 2
 '@BASEBOARD_FAB2_LIB.BASEBOARD_FAB2(SCH_1):PAGE197_I18@MSTR_DISCRETE.CAP(CHIPS)':
 'B': CDS_PINID='B';
NODE_NAME     R12W20 2
 '@BASEBOARD_FAB2_LIB.BASEBOARD_FAB2(SCH_1):PAGE197_I110@W_HDL.665KR2B-GP(CHIPS)':
 '2': CDS_PINID='\2\';
NODE_NAME     R12W17 2
 '@BASEBOARD_FAB2_LIB.BASEBOARD_FAB2(SCH_1):PAGE197_I123@W_HDL.665KR5B-1-GP(CHIPS)':
 '2': CDS_PINID='\2\';
NET_NAME
'VR_PVDDQ_KLM_VREN'
 '@BASEBOARD_FAB2_LIB.BASEBOARD_FAB2(SCH_1):VR_PVDDQ_KLM_VREN':
 C_SIGNAL='@baseboard_fab2_lib.baseboard_fab2(sch_1):vr_pvddq_klm_vren';
NODE_NAME     R9M9 2
 '@BASEBOARD_FAB2_LIB.BASEBOARD_FAB2(SCH_1):PAGE226_I14@MSTR_DISCRETE.RES(CHIPS)':
 'B': CDS_PINID='B';
NODE_NAME     R9M5 2
 '@BASEBOARD_FAB2_LIB.BASEBOARD_FAB2(SCH_1):PAGE226_I34@MSTR_DISCRETE.RES(CHIPS)':
 'B': CDS_PINID='B';
NODE_NAME     EU1B1 10
 '@BASEBOARD_FAB2_LIB.BASEBOARD_FAB2(SCH_1):PAGE226_I69@MSTR_CONTROLLER.PXM1310B(CHIPS)':
 'AVREN': CDS_PINID='AVREN';
NET_NAME
'VR_PVDDQ_KLM_XADDR1'
 '@BASEBOARD_FAB2_LIB.BASEBOARD_FAB2(SCH_1):VR_PVDDQ_KLM_XADDR1':
 C_SIGNAL='@baseboard_fab2_lib.baseboard_fab2(sch_1):vr_pvddq_klm_xaddr1';
NODE_NAME     EU1B1 36
 '@BASEBOARD_FAB2_LIB.BASEBOARD_FAB2(SCH_1):PAGE226_I69@MSTR_CONTROLLER.PXM1310B(CHIPS)':
 'XADDR1': CDS_PINID='XADDR1';
NODE_NAME     R1B12 1
 '@BASEBOARD_FAB2_LIB.BASEBOARD_FAB2(SCH_1):PAGE226_I72@MSTR_DISCRETE.RES(CHIPS)':
 'A': CDS_PINID='A';
NET_NAME
'VR_PVDDQ_KLM_XADDR2'
 '@BASEBOARD_FAB2_LIB.BASEBOARD_FAB2(SCH_1):VR_PVDDQ_KLM_XADDR2':
 C_SIGNAL='@baseboard_fab2_lib.baseboard_fab2(sch_1):vr_pvddq_klm_xaddr2';
NODE_NAME     EU1B1 33
 '@BASEBOARD_FAB2_LIB.BASEBOARD_FAB2(SCH_1):PAGE226_I69@MSTR_CONTROLLER.PXM1310B(CHIPS)':
 'XADDR2': CDS_PINID='XADDR2';
NODE_NAME     R1B15 1
 '@BASEBOARD_FAB2_LIB.BASEBOARD_FAB2(SCH_1):PAGE226_I73@MSTR_DISCRETE.RES(CHIPS)':
 'A': CDS_PINID='A';
NET_NAME
'VR_PVNN_P1V05_PCH_VD12'
 '@BASEBOARD_FAB2_LIB.BASEBOARD_FAB2(SCH_1):VR_PVNN_P1V05_PCH_VD12':
 C_SIGNAL='@baseboard_fab2_lib.baseboard_fab2(sch_1):vr_pvnn_p1v05_pch_vd12';
NODE_NAME     C8A7 1
 '@BASEBOARD_FAB2_LIB.BASEBOARD_FAB2(SCH_1):PAGE235_I143@DEV_DISCRETE.CAP_A(CHIPS)':
 'A': CDS_PINID='A';
NODE_NAME     C8A8 1
 '@BASEBOARD_FAB2_LIB.BASEBOARD_FAB2(SCH_1):PAGE235_I145@DEV_DISCRETE.CAP_A(CHIPS)':
 'A': CDS_PINID='A';
NODE_NAME     EU8A1 40
 '@BASEBOARD_FAB2_LIB.BASEBOARD_FAB2(SCH_1):PAGE235_I229@MSTR_CONTROLLER.PXE1110B(CHIPS)':
 'VD12': CDS_PINID='VD12';
NODE_NAME     R8W2 2
 '@BASEBOARD_FAB2_LIB.BASEBOARD_FAB2(SCH_1):PAGE235_I247@MSTR_DISCRETE.RES(CHIPS)':
 'B': CDS_PINID='B';
NODE_NAME     R8W3 1
 '@BASEBOARD_FAB2_LIB.BASEBOARD_FAB2(SCH_1):PAGE235_I248@MSTR_DISCRETE.RES(CHIPS)':
 'A': CDS_PINID='A';
NET_NAME
'VR_PVNN_PCH_AIREF1'
 '@BASEBOARD_FAB2_LIB.BASEBOARD_FAB2(SCH_1):VR_PVNN_PCH_AIREF1':
 C_SIGNAL='@baseboard_fab2_lib.baseboard_fab2(sch_1):vr_pvnn_pch_airef1';
NODE_NAME     EU8A1 21
 '@BASEBOARD_FAB2_LIB.BASEBOARD_FAB2(SCH_1):PAGE235_I229@MSTR_CONTROLLER.PXE1110B(CHIPS)':
 'AIREF1': CDS_PINID='AIREF1';
NODE_NAME     EU7A3 39
 '@BASEBOARD_FAB2_LIB.BASEBOARD_FAB2(SCH_1):PAGE236_I116@MSTR_DISCRETE.IR354XX(CHIPS)':
 'REFIN': CDS_PINID='REFIN';
NODE_NAME     CT66 1
 '@BASEBOARD_FAB2_LIB.BASEBOARD_FAB2(SCH_1):PAGE236_I127@DEV_DISCRETE.CAP_A(CHIPS)':
 'A': CDS_PINID='A';
NODE_NAME     CF23 1
 '@BASEBOARD_FAB2_LIB.BASEBOARD_FAB2(SCH_1):PAGE235_I239@W_HDL.SC22P50V2JN-4GP(CHIPS)':
 '1': CDS_PINID='\1\';
NODE_NAME     RF23 1
 '@BASEBOARD_FAB2_LIB.BASEBOARD_FAB2(SCH_1):PAGE235_I241@MSTR_DISCRETE.RES(CHIPS)':
 'A': CDS_PINID='A';
NET_NAME
'VR_PVNN_PCH_AVSP'
 '@BASEBOARD_FAB2_LIB.BASEBOARD_FAB2(SCH_1):VR_PVNN_PCH_AVSP':
 C_SIGNAL='@baseboard_fab2_lib.baseboard_fab2(sch_1):vr_pvnn_pch_avsp';
NODE_NAME     C8A2 1
 '@BASEBOARD_FAB2_LIB.BASEBOARD_FAB2(SCH_1):PAGE235_I209@MSTR_DISCRETE.CAP(CHIPS)':
 'A': CDS_PINID='A';
NODE_NAME     R8A1 2
 '@BASEBOARD_FAB2_LIB.BASEBOARD_FAB2(SCH_1):PAGE235_I210@MSTR_DISCRETE.RES(CHIPS)':
 'B': CDS_PINID='B';
NODE_NAME     EU8A1 19
 '@BASEBOARD_FAB2_LIB.BASEBOARD_FAB2(SCH_1):PAGE235_I229@MSTR_CONTROLLER.PXE1110B(CHIPS)':
 'AVSEN': CDS_PINID='AVSEN';
NET_NAME
'VR_PVNN_PCH_PH1_BOOT'
 '@BASEBOARD_FAB2_LIB.BASEBOARD_FAB2(SCH_1):VR_PVNN_PCH_PH1_BOOT':
 C_SIGNAL='@baseboard_fab2_lib.baseboard_fab2(sch_1):vr_pvnn_pch_ph1_boot';
NODE_NAME     C7A43 1
 '@BASEBOARD_FAB2_LIB.BASEBOARD_FAB2(SCH_1):PAGE236_I21@MSTR_DISCRETE.CAP(CHIPS)':
 'A': CDS_PINID='A';
NODE_NAME     RT44 1
 '@BASEBOARD_FAB2_LIB.BASEBOARD_FAB2(SCH_1):PAGE236_I153@MSTR_DISCRETE.RES(CHIPS)':
 'A': CDS_PINID='A';
NET_NAME
'VR_PVNN_PCH_PH1_BOOT_R'
 '@BASEBOARD_FAB2_LIB.BASEBOARD_FAB2(SCH_1):VR_PVNN_PCH_PH1_BOOT_R':
 C_SIGNAL='@baseboard_fab2_lib.baseboard_fab2(sch_1):vr_pvnn_pch_ph1_boot_r';
NODE_NAME     EU7A3 33
 '@BASEBOARD_FAB2_LIB.BASEBOARD_FAB2(SCH_1):PAGE236_I116@MSTR_DISCRETE.IR354XX(CHIPS)':
 'BOOST': CDS_PINID='BOOST';
NODE_NAME     RT44 2
 '@BASEBOARD_FAB2_LIB.BASEBOARD_FAB2(SCH_1):PAGE236_I153@MSTR_DISCRETE.RES(CHIPS)':
 'B': CDS_PINID='B';
NET_NAME
'VR_PVNN_PCH_PH1_PHASE'
 '@BASEBOARD_FAB2_LIB.BASEBOARD_FAB2(SCH_1):VR_PVNN_PCH_PH1_PHASE':
 C_SIGNAL='@baseboard_fab2_lib.baseboard_fab2(sch_1):vr_pvnn_pch_ph1_phase';
NODE_NAME     C7A43 2
 '@BASEBOARD_FAB2_LIB.BASEBOARD_FAB2(SCH_1):PAGE236_I21@MSTR_DISCRETE.CAP(CHIPS)':
 'B': CDS_PINID='B';
NODE_NAME     EU7A3 32
 '@BASEBOARD_FAB2_LIB.BASEBOARD_FAB2(SCH_1):PAGE236_I116@MSTR_DISCRETE.IR354XX(CHIPS)':
 'PHASE': CDS_PINID='PHASE';
NET_NAME
'VR_PVNN_PCH_PH1_PHASE_SW'
 '@BASEBOARD_FAB2_LIB.BASEBOARD_FAB2(SCH_1):VR_PVNN_PCH_PH1_PHASE_SW':
 C_SIGNAL='@baseboard_fab2_lib.baseboard_fab2(sch_1):vr_pvnn_pch_ph1_phase_sw';
NODE_NAME     EU7A3 10
 '@BASEBOARD_FAB2_LIB.BASEBOARD_FAB2(SCH_1):PAGE236_I116@MSTR_DISCRETE.IR354XX(CHIPS)':
 'SW': CDS_PINID='SW';
NODE_NAME     CT65 1
 '@BASEBOARD_FAB2_LIB.BASEBOARD_FAB2(SCH_1):PAGE236_I149@MSTR_DISCRETE.CAP(CHIPS)':
 'A': CDS_PINID='A';
NODE_NAME     L7A2 1
 '@BASEBOARD_FAB2_LIB.BASEBOARD_FAB2(SCH_1):PAGE236_I178@W_HDL.IND-300NH-20-GP(CHIPS)':
 'S': CDS_PINID='S';
NET_NAME
'VR_PVNN_PCH_PH1_PHASE_SW_RC'
 '@BASEBOARD_FAB2_LIB.BASEBOARD_FAB2(SCH_1):VR_PVNN_PCH_PH1_PHASE_SW_RC':
 C_SIGNAL='@baseboard_fab2_lib.baseboard_fab2(sch_1):vr_pvnn_pch_ph1_phase_sw_rc~
';
NODE_NAME     CT65 2
 '@BASEBOARD_FAB2_LIB.BASEBOARD_FAB2(SCH_1):PAGE236_I149@MSTR_DISCRETE.CAP(CHIPS)':
 'B': CDS_PINID='B';
NODE_NAME     RT43 1
 '@BASEBOARD_FAB2_LIB.BASEBOARD_FAB2(SCH_1):PAGE236_I182@W_HDL.1R3F-GP(CHIPS)':
 '1': CDS_PINID='\1\';
NET_NAME
'VR_PVNN_PCH_PH1_VCIN'
 '@BASEBOARD_FAB2_LIB.BASEBOARD_FAB2(SCH_1):VR_PVNN_PCH_PH1_VCIN':
 C_SIGNAL='@baseboard_fab2_lib.baseboard_fab2(sch_1):vr_pvnn_pch_ph1_vcin';
NODE_NAME     C7A6 1
 '@BASEBOARD_FAB2_LIB.BASEBOARD_FAB2(SCH_1):PAGE236_I19@MSTR_DISCRETE.CAP(CHIPS)':
 'A': CDS_PINID='A';
NODE_NAME     EU7A3 3
 '@BASEBOARD_FAB2_LIB.BASEBOARD_FAB2(SCH_1):PAGE236_I116@MSTR_DISCRETE.IR354XX(CHIPS)':
 'VCC': CDS_PINID='VCC';
NODE_NAME     R3L1 1
 '@BASEBOARD_FAB2_LIB.BASEBOARD_FAB2(SCH_1):PAGE236_I175@MSTR_DISCRETE.RES(CHIPS)':
 'A': CDS_PINID='A';
NET_NAME
'VR_PVNN_PCH_PWM1'
 '@BASEBOARD_FAB2_LIB.BASEBOARD_FAB2(SCH_1):VR_PVNN_PCH_PWM1':
 C_SIGNAL='@baseboard_fab2_lib.baseboard_fab2(sch_1):vr_pvnn_pch_pwm1';
NODE_NAME     EU8A1 5
 '@BASEBOARD_FAB2_LIB.BASEBOARD_FAB2(SCH_1):PAGE235_I229@MSTR_CONTROLLER.PXE1110B(CHIPS)':
 'APWM1': CDS_PINID='APWM1';
NODE_NAME     EU7A3 34
 '@BASEBOARD_FAB2_LIB.BASEBOARD_FAB2(SCH_1):PAGE236_I116@MSTR_DISCRETE.IR354XX(CHIPS)':
 'PWM': CDS_PINID='PWM';
NET_NAME
'VR_PVNN_PCH_STBY_OCSET'
 '@BASEBOARD_FAB2_LIB.BASEBOARD_FAB2(SCH_1):VR_PVNN_PCH_STBY_OCSET':
 C_SIGNAL='@baseboard_fab2_lib.baseboard_fab2(sch_1):vr_pvnn_pch_stby_ocset';
NODE_NAME     EU7A3 37
 '@BASEBOARD_FAB2_LIB.BASEBOARD_FAB2(SCH_1):PAGE236_I116@MSTR_DISCRETE.IR354XX(CHIPS)':
 'OCSET': CDS_PINID='OCSET';
NODE_NAME     R3L15 1
 '@BASEBOARD_FAB2_LIB.BASEBOARD_FAB2(SCH_1):PAGE236_I118@MSTR_DISCRETE.RES(CHIPS)':
 'A': CDS_PINID='A';
NET_NAME
'VR_PVNN_PCH_VDD'
 '@BASEBOARD_FAB2_LIB.BASEBOARD_FAB2(SCH_1):VR_PVNN_PCH_VDD':
 C_SIGNAL='@baseboard_fab2_lib.baseboard_fab2(sch_1):vr_pvnn_pch_vdd';
NODE_NAME     C2L8 1
 '@BASEBOARD_FAB2_LIB.BASEBOARD_FAB2(SCH_1):PAGE235_I151@DEV_DISCRETE.CAP_A(CHIPS)':
 'A': CDS_PINID='A';
NODE_NAME     R2L14 2
 '@BASEBOARD_FAB2_LIB.BASEBOARD_FAB2(SCH_1):PAGE235_I159@MSTR_DISCRETE.RES(CHIPS)':
 'B': CDS_PINID='B';
NODE_NAME     C2L11 1
 '@BASEBOARD_FAB2_LIB.BASEBOARD_FAB2(SCH_1):PAGE235_I169@DEV_DISCRETE.CAP_A(CHIPS)':
 'A': CDS_PINID='A';
NODE_NAME     EU8A1 39
 '@BASEBOARD_FAB2_LIB.BASEBOARD_FAB2(SCH_1):PAGE235_I229@MSTR_CONTROLLER.PXE1110B(CHIPS)':
 'VDD': CDS_PINID='VDD';
NET_NAME
'VR_PVNN_PCH_VINSEN'
 '@BASEBOARD_FAB2_LIB.BASEBOARD_FAB2(SCH_1):VR_PVNN_PCH_VINSEN':
 C_SIGNAL='@baseboard_fab2_lib.baseboard_fab2(sch_1):vr_pvnn_pch_vinsen';
NODE_NAME     R8A4 2
 '@BASEBOARD_FAB2_LIB.BASEBOARD_FAB2(SCH_1):PAGE235_I165@MSTR_DISCRETE.RES(CHIPS)':
 'B': CDS_PINID='B';
NODE_NAME     R2L10 1
 '@BASEBOARD_FAB2_LIB.BASEBOARD_FAB2(SCH_1):PAGE235_I166@MSTR_DISCRETE.RES(CHIPS)':
 'A': CDS_PINID='A';
NODE_NAME     EU8A1 37
 '@BASEBOARD_FAB2_LIB.BASEBOARD_FAB2(SCH_1):PAGE235_I229@MSTR_CONTROLLER.PXE1110B(CHIPS)':
 'VINSEN': CDS_PINID='VINSEN';
NODE_NAME     C8A3 1
 '@BASEBOARD_FAB2_LIB.BASEBOARD_FAB2(SCH_1):PAGE235_I255@DEV_DISCRETE.CAP_A(CHIPS)':
 'A': CDS_PINID='A';
NET_NAME
'VR_PVNN_PCH_VREN'
 '@BASEBOARD_FAB2_LIB.BASEBOARD_FAB2(SCH_1):VR_PVNN_PCH_VREN':
 C_SIGNAL='@baseboard_fab2_lib.baseboard_fab2(sch_1):vr_pvnn_pch_vren';
NODE_NAME     R2L17 2
 '@BASEBOARD_FAB2_LIB.BASEBOARD_FAB2(SCH_1):PAGE235_I221@MSTR_DISCRETE.RES(CHIPS)':
 'B': CDS_PINID='B';
NODE_NAME     R8A7 2
 '@BASEBOARD_FAB2_LIB.BASEBOARD_FAB2(SCH_1):PAGE235_I222@MSTR_DISCRETE.RES(CHIPS)':
 'B': CDS_PINID='B';
NODE_NAME     EU8A1 10
 '@BASEBOARD_FAB2_LIB.BASEBOARD_FAB2(SCH_1):PAGE235_I229@MSTR_CONTROLLER.PXE1110B(CHIPS)':
 'AVREN': CDS_PINID='AVREN';
NET_NAME
'VR_PVNN_PCH_XADDR1'
 '@BASEBOARD_FAB2_LIB.BASEBOARD_FAB2(SCH_1):VR_PVNN_PCH_XADDR1':
 C_SIGNAL='@baseboard_fab2_lib.baseboard_fab2(sch_1):vr_pvnn_pch_xaddr1';
NODE_NAME     EU8A1 36
 '@BASEBOARD_FAB2_LIB.BASEBOARD_FAB2(SCH_1):PAGE235_I229@MSTR_CONTROLLER.PXE1110B(CHIPS)':
 'XADDR1': CDS_PINID='XADDR1';
NODE_NAME     R2L9 1
 '@BASEBOARD_FAB2_LIB.BASEBOARD_FAB2(SCH_1):PAGE235_I254@MSTR_DISCRETE.RES(CHIPS)':
 'A': CDS_PINID='A';
NET_NAME
'VR_PVNN_PCH_XADDR2'
 '@BASEBOARD_FAB2_LIB.BASEBOARD_FAB2(SCH_1):VR_PVNN_PCH_XADDR2':
 C_SIGNAL='@baseboard_fab2_lib.baseboard_fab2(sch_1):vr_pvnn_pch_xaddr2';
NODE_NAME     R8A2 1
 '@BASEBOARD_FAB2_LIB.BASEBOARD_FAB2(SCH_1):PAGE235_I217@MSTR_DISCRETE.RES(CHIPS)':
 'A': CDS_PINID='A';
NODE_NAME     EU8A1 33
 '@BASEBOARD_FAB2_LIB.BASEBOARD_FAB2(SCH_1):PAGE235_I229@MSTR_CONTROLLER.PXE1110B(CHIPS)':
 'XADDR2': CDS_PINID='XADDR2';
NET_NAME
'VR_PVPP_ABC_BOOT'
 '@BASEBOARD_FAB2_LIB.BASEBOARD_FAB2(SCH_1):VR_PVPP_ABC_BOOT':
 C_SIGNAL='@baseboard_fab2_lib.baseboard_fab2(sch_1):vr_pvpp_abc_boot';
NODE_NAME     EU7F1 36
 '@BASEBOARD_FAB2_LIB.BASEBOARD_FAB2(SCH_1):PAGE231_I193@MSTR_VREG.NCP3232L(CHIPS)':
 'BST': CDS_PINID='BST';
NODE_NAME     R7F8 1
 '@BASEBOARD_FAB2_LIB.BASEBOARD_FAB2(SCH_1):PAGE231_I229@MSTR_DISCRETE.RES(CHIPS)':
 'A': CDS_PINID='A';
NET_NAME
'VR_PVPP_ABC_BOOT_R'
 '@BASEBOARD_FAB2_LIB.BASEBOARD_FAB2(SCH_1):VR_PVPP_ABC_BOOT_R':
 C_SIGNAL='@baseboard_fab2_lib.baseboard_fab2(sch_1):vr_pvpp_abc_boot_r';
NODE_NAME     C7F4 2
 '@BASEBOARD_FAB2_LIB.BASEBOARD_FAB2(SCH_1):PAGE231_I159@MSTR_DISCRETE.CAP(CHIPS)':
 'B': CDS_PINID='B';
NODE_NAME     R7F8 2
 '@BASEBOARD_FAB2_LIB.BASEBOARD_FAB2(SCH_1):PAGE231_I229@MSTR_DISCRETE.RES(CHIPS)':
 'B': CDS_PINID='B';
NET_NAME
'VR_PVPP_ABC_ISET'
 '@BASEBOARD_FAB2_LIB.BASEBOARD_FAB2(SCH_1):VR_PVPP_ABC_ISET':
 C_SIGNAL='@baseboard_fab2_lib.baseboard_fab2(sch_1):vr_pvpp_abc_iset';
NODE_NAME     R7F15 1
 '@BASEBOARD_FAB2_LIB.BASEBOARD_FAB2(SCH_1):PAGE231_I134@MSTR_DISCRETE.RES(CHIPS)':
 'A': CDS_PINID='A';
NODE_NAME     EU7F1 4
 '@BASEBOARD_FAB2_LIB.BASEBOARD_FAB2(SCH_1):PAGE231_I193@MSTR_VREG.NCP3232L(CHIPS)':
 'ISET': CDS_PINID='ISET';
NET_NAME
'VR_PVPP_ABC_PHASE'
 '@BASEBOARD_FAB2_LIB.BASEBOARD_FAB2(SCH_1):VR_PVPP_ABC_PHASE':
 C_SIGNAL='@baseboard_fab2_lib.baseboard_fab2(sch_1):vr_pvpp_abc_phase';
NODE_NAME     C7F4 1
 '@BASEBOARD_FAB2_LIB.BASEBOARD_FAB2(SCH_1):PAGE231_I159@MSTR_DISCRETE.CAP(CHIPS)':
 'A': CDS_PINID='A';
NODE_NAME     C7F3 1
 '@BASEBOARD_FAB2_LIB.BASEBOARD_FAB2(SCH_1):PAGE231_I175@MSTR_DISCRETE.CAP(CHIPS)':
 'A': CDS_PINID='A';
NODE_NAME     L7F1 1
 '@BASEBOARD_FAB2_LIB.BASEBOARD_FAB2(SCH_1):PAGE231_I178@MSTR_DISCRETE.INDUCTOR(CHIPS)':
 'INA': CDS_PINID='INA';
NODE_NAME     EU7F1 35
 '@BASEBOARD_FAB2_LIB.BASEBOARD_FAB2(SCH_1):PAGE231_I193@MSTR_VREG.NCP3232L(CHIPS)':
 'VSW': CDS_PINID='VSW';
NODE_NAME     EU7F1 15
 '@BASEBOARD_FAB2_LIB.BASEBOARD_FAB2(SCH_1):PAGE231_I193@MSTR_VREG.NCP3232L(CHIPS)':
 'VSWH'<0>: CDS_PINID='VSWH(0)';
NODE_NAME     EU7F1 29
 '@BASEBOARD_FAB2_LIB.BASEBOARD_FAB2(SCH_1):PAGE231_I193@MSTR_VREG.NCP3232L(CHIPS)':
 'VSWH'<1>: CDS_PINID='VSWH(1)';
NODE_NAME     EU7F1 30
 '@BASEBOARD_FAB2_LIB.BASEBOARD_FAB2(SCH_1):PAGE231_I193@MSTR_VREG.NCP3232L(CHIPS)':
 'VSWH'<2>: CDS_PINID='VSWH(2)';
NODE_NAME     EU7F1 31
 '@BASEBOARD_FAB2_LIB.BASEBOARD_FAB2(SCH_1):PAGE231_I193@MSTR_VREG.NCP3232L(CHIPS)':
 'VSWH'<3>: CDS_PINID='VSWH(3)';
NODE_NAME     EU7F1 32
 '@BASEBOARD_FAB2_LIB.BASEBOARD_FAB2(SCH_1):PAGE231_I193@MSTR_VREG.NCP3232L(CHIPS)':
 'VSWH'<4>: CDS_PINID='VSWH(4)';
NODE_NAME     EU7F1 33
 '@BASEBOARD_FAB2_LIB.BASEBOARD_FAB2(SCH_1):PAGE231_I193@MSTR_VREG.NCP3232L(CHIPS)':
 'VSWH'<5>: CDS_PINID='VSWH(5)';
NODE_NAME     EU7F1 34
 '@BASEBOARD_FAB2_LIB.BASEBOARD_FAB2(SCH_1):PAGE231_I193@MSTR_VREG.NCP3232L(CHIPS)':
 'VSWH'<6>: CDS_PINID='VSWH(6)';
NODE_NAME     EU7F1 43
 '@BASEBOARD_FAB2_LIB.BASEBOARD_FAB2(SCH_1):PAGE231_I193@MSTR_VREG.NCP3232L(CHIPS)':
 'VSWH'<7>: CDS_PINID='VSWH(7)';
NET_NAME
'VR_PVPP_ABC_SNUB'
 '@BASEBOARD_FAB2_LIB.BASEBOARD_FAB2(SCH_1):VR_PVPP_ABC_SNUB':
 C_SIGNAL='@baseboard_fab2_lib.baseboard_fab2(sch_1):vr_pvpp_abc_snub';
NODE_NAME     R7F7 1
 '@BASEBOARD_FAB2_LIB.BASEBOARD_FAB2(SCH_1):PAGE231_I174@MSTR_DISCRETE.RES(CHIPS)':
 'A': CDS_PINID='A';
NODE_NAME     C7F3 2
 '@BASEBOARD_FAB2_LIB.BASEBOARD_FAB2(SCH_1):PAGE231_I175@MSTR_DISCRETE.CAP(CHIPS)':
 'B': CDS_PINID='B';
NET_NAME
'VR_PVPP_ABC_SS'
 '@BASEBOARD_FAB2_LIB.BASEBOARD_FAB2(SCH_1):VR_PVPP_ABC_SS':
 C_SIGNAL='@baseboard_fab2_lib.baseboard_fab2(sch_1):vr_pvpp_abc_ss';
NODE_NAME     EU7F1 1
 '@BASEBOARD_FAB2_LIB.BASEBOARD_FAB2(SCH_1):PAGE231_I193@MSTR_VREG.NCP3232L(CHIPS)':
 'SS': CDS_PINID='SS';
NODE_NAME     C7F10 1
 '@BASEBOARD_FAB2_LIB.BASEBOARD_FAB2(SCH_1):PAGE231_I194@MSTR_DISCRETE.CAP(CHIPS)':
 'A': CDS_PINID='A';
NET_NAME
'VR_PVPP_DEF_BOOT'
 '@BASEBOARD_FAB2_LIB.BASEBOARD_FAB2(SCH_1):VR_PVPP_DEF_BOOT':
 C_SIGNAL='@baseboard_fab2_lib.baseboard_fab2(sch_1):vr_pvpp_def_boot';
NODE_NAME     EU7B1 36
 '@BASEBOARD_FAB2_LIB.BASEBOARD_FAB2(SCH_1):PAGE232_I214@MSTR_VREG.NCP3232L(CHIPS)':
 'BST': CDS_PINID='BST';
NODE_NAME     R7B19 1
 '@BASEBOARD_FAB2_LIB.BASEBOARD_FAB2(SCH_1):PAGE232_I313@MSTR_DISCRETE.RES(CHIPS)':
 'A': CDS_PINID='A';
NET_NAME
'VR_PVPP_DEF_BOOT_R'
 '@BASEBOARD_FAB2_LIB.BASEBOARD_FAB2(SCH_1):VR_PVPP_DEF_BOOT_R':
 C_SIGNAL='@baseboard_fab2_lib.baseboard_fab2(sch_1):vr_pvpp_def_boot_r';
NODE_NAME     C7B30 2
 '@BASEBOARD_FAB2_LIB.BASEBOARD_FAB2(SCH_1):PAGE232_I241@MSTR_DISCRETE.CAP(CHIPS)':
 'B': CDS_PINID='B';
NODE_NAME     R7B19 2
 '@BASEBOARD_FAB2_LIB.BASEBOARD_FAB2(SCH_1):PAGE232_I313@MSTR_DISCRETE.RES(CHIPS)':
 'B': CDS_PINID='B';
NET_NAME
'VR_PVPP_DEF_ISET'
 '@BASEBOARD_FAB2_LIB.BASEBOARD_FAB2(SCH_1):VR_PVPP_DEF_ISET':
 C_SIGNAL='@baseboard_fab2_lib.baseboard_fab2(sch_1):vr_pvpp_def_iset';
NODE_NAME     EU7B1 4
 '@BASEBOARD_FAB2_LIB.BASEBOARD_FAB2(SCH_1):PAGE232_I214@MSTR_VREG.NCP3232L(CHIPS)':
 'ISET': CDS_PINID='ISET';
NODE_NAME     R7B14 1
 '@BASEBOARD_FAB2_LIB.BASEBOARD_FAB2(SCH_1):PAGE232_I315@MSTR_DISCRETE.RES(CHIPS)':
 'A': CDS_PINID='A';
NET_NAME
'VR_PVPP_DEF_PHASE'
 '@BASEBOARD_FAB2_LIB.BASEBOARD_FAB2(SCH_1):VR_PVPP_DEF_PHASE':
 C_SIGNAL='@baseboard_fab2_lib.baseboard_fab2(sch_1):vr_pvpp_def_phase';
NODE_NAME     EU7B1 35
 '@BASEBOARD_FAB2_LIB.BASEBOARD_FAB2(SCH_1):PAGE232_I214@MSTR_VREG.NCP3232L(CHIPS)':
 'VSW': CDS_PINID='VSW';
NODE_NAME     EU7B1 15
 '@BASEBOARD_FAB2_LIB.BASEBOARD_FAB2(SCH_1):PAGE232_I214@MSTR_VREG.NCP3232L(CHIPS)':
 'VSWH'<0>: CDS_PINID='VSWH(0)';
NODE_NAME     EU7B1 29
 '@BASEBOARD_FAB2_LIB.BASEBOARD_FAB2(SCH_1):PAGE232_I214@MSTR_VREG.NCP3232L(CHIPS)':
 'VSWH'<1>: CDS_PINID='VSWH(1)';
NODE_NAME     EU7B1 30
 '@BASEBOARD_FAB2_LIB.BASEBOARD_FAB2(SCH_1):PAGE232_I214@MSTR_VREG.NCP3232L(CHIPS)':
 'VSWH'<2>: CDS_PINID='VSWH(2)';
NODE_NAME     EU7B1 31
 '@BASEBOARD_FAB2_LIB.BASEBOARD_FAB2(SCH_1):PAGE232_I214@MSTR_VREG.NCP3232L(CHIPS)':
 'VSWH'<3>: CDS_PINID='VSWH(3)';
NODE_NAME     EU7B1 32
 '@BASEBOARD_FAB2_LIB.BASEBOARD_FAB2(SCH_1):PAGE232_I214@MSTR_VREG.NCP3232L(CHIPS)':
 'VSWH'<4>: CDS_PINID='VSWH(4)';
NODE_NAME     EU7B1 33
 '@BASEBOARD_FAB2_LIB.BASEBOARD_FAB2(SCH_1):PAGE232_I214@MSTR_VREG.NCP3232L(CHIPS)':
 'VSWH'<5>: CDS_PINID='VSWH(5)';
NODE_NAME     EU7B1 34
 '@BASEBOARD_FAB2_LIB.BASEBOARD_FAB2(SCH_1):PAGE232_I214@MSTR_VREG.NCP3232L(CHIPS)':
 'VSWH'<6>: CDS_PINID='VSWH(6)';
NODE_NAME     EU7B1 43
 '@BASEBOARD_FAB2_LIB.BASEBOARD_FAB2(SCH_1):PAGE232_I214@MSTR_VREG.NCP3232L(CHIPS)':
 'VSWH'<7>: CDS_PINID='VSWH(7)';
NODE_NAME     C7A34 1
 '@BASEBOARD_FAB2_LIB.BASEBOARD_FAB2(SCH_1):PAGE232_I220@MSTR_DISCRETE.CAP(CHIPS)':
 'A': CDS_PINID='A';
NODE_NAME     L7B1 1
 '@BASEBOARD_FAB2_LIB.BASEBOARD_FAB2(SCH_1):PAGE232_I239@MSTR_DISCRETE.INDUCTOR(CHIPS)':
 'INA': CDS_PINID='INA';
NODE_NAME     C7B30 1
 '@BASEBOARD_FAB2_LIB.BASEBOARD_FAB2(SCH_1):PAGE232_I241@MSTR_DISCRETE.CAP(CHIPS)':
 'A': CDS_PINID='A';
NET_NAME
'VR_PVPP_DEF_SNUB'
 '@BASEBOARD_FAB2_LIB.BASEBOARD_FAB2(SCH_1):VR_PVPP_DEF_SNUB':
 C_SIGNAL='@baseboard_fab2_lib.baseboard_fab2(sch_1):vr_pvpp_def_snub';
NODE_NAME     R7A15 1
 '@BASEBOARD_FAB2_LIB.BASEBOARD_FAB2(SCH_1):PAGE232_I218@MSTR_DISCRETE.RES(CHIPS)':
 'A': CDS_PINID='A';
NODE_NAME     C7A34 2
 '@BASEBOARD_FAB2_LIB.BASEBOARD_FAB2(SCH_1):PAGE232_I220@MSTR_DISCRETE.CAP(CHIPS)':
 'B': CDS_PINID='B';
NET_NAME
'VR_PVPP_DEF_SS'
 '@BASEBOARD_FAB2_LIB.BASEBOARD_FAB2(SCH_1):VR_PVPP_DEF_SS':
 C_SIGNAL='@baseboard_fab2_lib.baseboard_fab2(sch_1):vr_pvpp_def_ss';
NODE_NAME     C7B11 1
 '@BASEBOARD_FAB2_LIB.BASEBOARD_FAB2(SCH_1):PAGE232_I197@MSTR_DISCRETE.CAP(CHIPS)':
 'A': CDS_PINID='A';
NODE_NAME     EU7B1 1
 '@BASEBOARD_FAB2_LIB.BASEBOARD_FAB2(SCH_1):PAGE232_I214@MSTR_VREG.NCP3232L(CHIPS)':
 'SS': CDS_PINID='SS';
NET_NAME
'VR_PVPP_GHJ_BOOT'
 '@BASEBOARD_FAB2_LIB.BASEBOARD_FAB2(SCH_1):VR_PVPP_GHJ_BOOT':
 C_SIGNAL='@baseboard_fab2_lib.baseboard_fab2(sch_1):vr_pvpp_ghj_boot';
NODE_NAME     EU4G1 36
 '@BASEBOARD_FAB2_LIB.BASEBOARD_FAB2(SCH_1):PAGE233_I225@MSTR_VREG.NCP3232L(CHIPS)':
 'BST': CDS_PINID='BST';
NODE_NAME     R4G24 1
 '@BASEBOARD_FAB2_LIB.BASEBOARD_FAB2(SCH_1):PAGE233_I282@MSTR_DISCRETE.RES(CHIPS)':
 'A': CDS_PINID='A';
NET_NAME
'VR_PVPP_GHJ_BOOT_R'
 '@BASEBOARD_FAB2_LIB.BASEBOARD_FAB2(SCH_1):VR_PVPP_GHJ_BOOT_R':
 C_SIGNAL='@baseboard_fab2_lib.baseboard_fab2(sch_1):vr_pvpp_ghj_boot_r';
NODE_NAME     C4G26 2
 '@BASEBOARD_FAB2_LIB.BASEBOARD_FAB2(SCH_1):PAGE233_I224@MSTR_DISCRETE.CAP(CHIPS)':
 'B': CDS_PINID='B';
NODE_NAME     R4G24 2
 '@BASEBOARD_FAB2_LIB.BASEBOARD_FAB2(SCH_1):PAGE233_I282@MSTR_DISCRETE.RES(CHIPS)':
 'B': CDS_PINID='B';
NET_NAME
'VR_PVPP_GHJ_ISET'
 '@BASEBOARD_FAB2_LIB.BASEBOARD_FAB2(SCH_1):VR_PVPP_GHJ_ISET':
 C_SIGNAL='@baseboard_fab2_lib.baseboard_fab2(sch_1):vr_pvpp_ghj_iset';
NODE_NAME     EU4G1 4
 '@BASEBOARD_FAB2_LIB.BASEBOARD_FAB2(SCH_1):PAGE233_I225@MSTR_VREG.NCP3232L(CHIPS)':
 'ISET': CDS_PINID='ISET';
NODE_NAME     R4G11 1
 '@BASEBOARD_FAB2_LIB.BASEBOARD_FAB2(SCH_1):PAGE233_I284@MSTR_DISCRETE.RES(CHIPS)':
 'A': CDS_PINID='A';
NET_NAME
'VR_PVPP_GHJ_PHASE'
 '@BASEBOARD_FAB2_LIB.BASEBOARD_FAB2(SCH_1):VR_PVPP_GHJ_PHASE':
 C_SIGNAL='@baseboard_fab2_lib.baseboard_fab2(sch_1):vr_pvpp_ghj_phase';
NODE_NAME     C4F12 1
 '@BASEBOARD_FAB2_LIB.BASEBOARD_FAB2(SCH_1):PAGE233_I209@MSTR_DISCRETE.CAP(CHIPS)':
 'A': CDS_PINID='A';
NODE_NAME     C4G26 1
 '@BASEBOARD_FAB2_LIB.BASEBOARD_FAB2(SCH_1):PAGE233_I224@MSTR_DISCRETE.CAP(CHIPS)':
 'A': CDS_PINID='A';
NODE_NAME     EU4G1 35
 '@BASEBOARD_FAB2_LIB.BASEBOARD_FAB2(SCH_1):PAGE233_I225@MSTR_VREG.NCP3232L(CHIPS)':
 'VSW': CDS_PINID='VSW';
NODE_NAME     EU4G1 15
 '@BASEBOARD_FAB2_LIB.BASEBOARD_FAB2(SCH_1):PAGE233_I225@MSTR_VREG.NCP3232L(CHIPS)':
 'VSWH'<0>: CDS_PINID='VSWH(0)';
NODE_NAME     EU4G1 29
 '@BASEBOARD_FAB2_LIB.BASEBOARD_FAB2(SCH_1):PAGE233_I225@MSTR_VREG.NCP3232L(CHIPS)':
 'VSWH'<1>: CDS_PINID='VSWH(1)';
NODE_NAME     EU4G1 30
 '@BASEBOARD_FAB2_LIB.BASEBOARD_FAB2(SCH_1):PAGE233_I225@MSTR_VREG.NCP3232L(CHIPS)':
 'VSWH'<2>: CDS_PINID='VSWH(2)';
NODE_NAME     EU4G1 31
 '@BASEBOARD_FAB2_LIB.BASEBOARD_FAB2(SCH_1):PAGE233_I225@MSTR_VREG.NCP3232L(CHIPS)':
 'VSWH'<3>: CDS_PINID='VSWH(3)';
NODE_NAME     EU4G1 32
 '@BASEBOARD_FAB2_LIB.BASEBOARD_FAB2(SCH_1):PAGE233_I225@MSTR_VREG.NCP3232L(CHIPS)':
 'VSWH'<4>: CDS_PINID='VSWH(4)';
NODE_NAME     EU4G1 33
 '@BASEBOARD_FAB2_LIB.BASEBOARD_FAB2(SCH_1):PAGE233_I225@MSTR_VREG.NCP3232L(CHIPS)':
 'VSWH'<5>: CDS_PINID='VSWH(5)';
NODE_NAME     EU4G1 34
 '@BASEBOARD_FAB2_LIB.BASEBOARD_FAB2(SCH_1):PAGE233_I225@MSTR_VREG.NCP3232L(CHIPS)':
 'VSWH'<6>: CDS_PINID='VSWH(6)';
NODE_NAME     EU4G1 43
 '@BASEBOARD_FAB2_LIB.BASEBOARD_FAB2(SCH_1):PAGE233_I225@MSTR_VREG.NCP3232L(CHIPS)':
 'VSWH'<7>: CDS_PINID='VSWH(7)';
NODE_NAME     L4G1 1
 '@BASEBOARD_FAB2_LIB.BASEBOARD_FAB2(SCH_1):PAGE233_I277@MSTR_DISCRETE.INDUCTOR(CHIPS)':
 'INA': CDS_PINID='INA';
NET_NAME
'VR_PVPP_GHJ_SNUB'
 '@BASEBOARD_FAB2_LIB.BASEBOARD_FAB2(SCH_1):VR_PVPP_GHJ_SNUB':
 C_SIGNAL='@baseboard_fab2_lib.baseboard_fab2(sch_1):vr_pvpp_ghj_snub';
NODE_NAME     R4F6 1
 '@BASEBOARD_FAB2_LIB.BASEBOARD_FAB2(SCH_1):PAGE233_I208@MSTR_DISCRETE.RES(CHIPS)':
 'A': CDS_PINID='A';
NODE_NAME     C4F12 2
 '@BASEBOARD_FAB2_LIB.BASEBOARD_FAB2(SCH_1):PAGE233_I209@MSTR_DISCRETE.CAP(CHIPS)':
 'B': CDS_PINID='B';
NET_NAME
'VR_PVPP_GHJ_SS'
 '@BASEBOARD_FAB2_LIB.BASEBOARD_FAB2(SCH_1):VR_PVPP_GHJ_SS':
 C_SIGNAL='@baseboard_fab2_lib.baseboard_fab2(sch_1):vr_pvpp_ghj_ss';
NODE_NAME     C4G8 1
 '@BASEBOARD_FAB2_LIB.BASEBOARD_FAB2(SCH_1):PAGE233_I194@MSTR_DISCRETE.CAP(CHIPS)':
 'A': CDS_PINID='A';
NODE_NAME     EU4G1 1
 '@BASEBOARD_FAB2_LIB.BASEBOARD_FAB2(SCH_1):PAGE233_I225@MSTR_VREG.NCP3232L(CHIPS)':
 'SS': CDS_PINID='SS';
NET_NAME
'VR_PVPP_KLM_BOOT'
 '@BASEBOARD_FAB2_LIB.BASEBOARD_FAB2(SCH_1):VR_PVPP_KLM_BOOT':
 C_SIGNAL='@baseboard_fab2_lib.baseboard_fab2(sch_1):vr_pvpp_klm_boot';
NODE_NAME     EU4A3 36
 '@BASEBOARD_FAB2_LIB.BASEBOARD_FAB2(SCH_1):PAGE234_I184@MSTR_VREG.NCP3232L(CHIPS)':
 'BST': CDS_PINID='BST';
NODE_NAME     R4B13 1
 '@BASEBOARD_FAB2_LIB.BASEBOARD_FAB2(SCH_1):PAGE234_I226@MSTR_DISCRETE.RES(CHIPS)':
 'A': CDS_PINID='A';
NET_NAME
'VR_PVPP_KLM_BOOT_R'
 '@BASEBOARD_FAB2_LIB.BASEBOARD_FAB2(SCH_1):VR_PVPP_KLM_BOOT_R':
 C_SIGNAL='@baseboard_fab2_lib.baseboard_fab2(sch_1):vr_pvpp_klm_boot_r';
NODE_NAME     C4B15 2
 '@BASEBOARD_FAB2_LIB.BASEBOARD_FAB2(SCH_1):PAGE234_I182@MSTR_DISCRETE.CAP(CHIPS)':
 'B': CDS_PINID='B';
NODE_NAME     R4B13 2
 '@BASEBOARD_FAB2_LIB.BASEBOARD_FAB2(SCH_1):PAGE234_I226@MSTR_DISCRETE.RES(CHIPS)':
 'B': CDS_PINID='B';
NET_NAME
'VR_PVPP_KLM_ISET'
 '@BASEBOARD_FAB2_LIB.BASEBOARD_FAB2(SCH_1):VR_PVPP_KLM_ISET':
 C_SIGNAL='@baseboard_fab2_lib.baseboard_fab2(sch_1):vr_pvpp_klm_iset';
NODE_NAME     EU4A3 4
 '@BASEBOARD_FAB2_LIB.BASEBOARD_FAB2(SCH_1):PAGE234_I184@MSTR_VREG.NCP3232L(CHIPS)':
 'ISET': CDS_PINID='ISET';
NODE_NAME     R4B6 1
 '@BASEBOARD_FAB2_LIB.BASEBOARD_FAB2(SCH_1):PAGE234_I228@MSTR_DISCRETE.RES(CHIPS)':
 'A': CDS_PINID='A';
NET_NAME
'VR_PVPP_KLM_PHASE'
 '@BASEBOARD_FAB2_LIB.BASEBOARD_FAB2(SCH_1):VR_PVPP_KLM_PHASE':
 C_SIGNAL='@baseboard_fab2_lib.baseboard_fab2(sch_1):vr_pvpp_klm_phase';
NODE_NAME     C4A16 1
 '@BASEBOARD_FAB2_LIB.BASEBOARD_FAB2(SCH_1):PAGE234_I163@MSTR_DISCRETE.CAP(CHIPS)':
 'A': CDS_PINID='A';
NODE_NAME     L4A1 1
 '@BASEBOARD_FAB2_LIB.BASEBOARD_FAB2(SCH_1):PAGE234_I164@MSTR_DISCRETE.INDUCTOR(CHIPS)':
 'INA': CDS_PINID='INA';
NODE_NAME     C4B15 1
 '@BASEBOARD_FAB2_LIB.BASEBOARD_FAB2(SCH_1):PAGE234_I182@MSTR_DISCRETE.CAP(CHIPS)':
 'A': CDS_PINID='A';
NODE_NAME     EU4A3 35
 '@BASEBOARD_FAB2_LIB.BASEBOARD_FAB2(SCH_1):PAGE234_I184@MSTR_VREG.NCP3232L(CHIPS)':
 'VSW': CDS_PINID='VSW';
NODE_NAME     EU4A3 15
 '@BASEBOARD_FAB2_LIB.BASEBOARD_FAB2(SCH_1):PAGE234_I184@MSTR_VREG.NCP3232L(CHIPS)':
 'VSWH'<0>: CDS_PINID='VSWH(0)';
NODE_NAME     EU4A3 29
 '@BASEBOARD_FAB2_LIB.BASEBOARD_FAB2(SCH_1):PAGE234_I184@MSTR_VREG.NCP3232L(CHIPS)':
 'VSWH'<1>: CDS_PINID='VSWH(1)';
NODE_NAME     EU4A3 30
 '@BASEBOARD_FAB2_LIB.BASEBOARD_FAB2(SCH_1):PAGE234_I184@MSTR_VREG.NCP3232L(CHIPS)':
 'VSWH'<2>: CDS_PINID='VSWH(2)';
NODE_NAME     EU4A3 31
 '@BASEBOARD_FAB2_LIB.BASEBOARD_FAB2(SCH_1):PAGE234_I184@MSTR_VREG.NCP3232L(CHIPS)':
 'VSWH'<3>: CDS_PINID='VSWH(3)';
NODE_NAME     EU4A3 32
 '@BASEBOARD_FAB2_LIB.BASEBOARD_FAB2(SCH_1):PAGE234_I184@MSTR_VREG.NCP3232L(CHIPS)':
 'VSWH'<4>: CDS_PINID='VSWH(4)';
NODE_NAME     EU4A3 33
 '@BASEBOARD_FAB2_LIB.BASEBOARD_FAB2(SCH_1):PAGE234_I184@MSTR_VREG.NCP3232L(CHIPS)':
 'VSWH'<5>: CDS_PINID='VSWH(5)';
NODE_NAME     EU4A3 34
 '@BASEBOARD_FAB2_LIB.BASEBOARD_FAB2(SCH_1):PAGE234_I184@MSTR_VREG.NCP3232L(CHIPS)':
 'VSWH'<6>: CDS_PINID='VSWH(6)';
NODE_NAME     EU4A3 43
 '@BASEBOARD_FAB2_LIB.BASEBOARD_FAB2(SCH_1):PAGE234_I184@MSTR_VREG.NCP3232L(CHIPS)':
 'VSWH'<7>: CDS_PINID='VSWH(7)';
NET_NAME
'VR_PVPP_KLM_SNUB'
 '@BASEBOARD_FAB2_LIB.BASEBOARD_FAB2(SCH_1):VR_PVPP_KLM_SNUB':
 C_SIGNAL='@baseboard_fab2_lib.baseboard_fab2(sch_1):vr_pvpp_klm_snub';
NODE_NAME     R4A7 1
 '@BASEBOARD_FAB2_LIB.BASEBOARD_FAB2(SCH_1):PAGE234_I162@MSTR_DISCRETE.RES(CHIPS)':
 'A': CDS_PINID='A';
NODE_NAME     C4A16 2
 '@BASEBOARD_FAB2_LIB.BASEBOARD_FAB2(SCH_1):PAGE234_I163@MSTR_DISCRETE.CAP(CHIPS)':
 'B': CDS_PINID='B';
NET_NAME
'VR_PVPP_KLM_SS'
 '@BASEBOARD_FAB2_LIB.BASEBOARD_FAB2(SCH_1):VR_PVPP_KLM_SS':
 C_SIGNAL='@baseboard_fab2_lib.baseboard_fab2(sch_1):vr_pvpp_klm_ss';
NODE_NAME     C4B6 1
 '@BASEBOARD_FAB2_LIB.BASEBOARD_FAB2(SCH_1):PAGE234_I146@MSTR_DISCRETE.CAP(CHIPS)':
 'A': CDS_PINID='A';
NODE_NAME     EU4A3 1
 '@BASEBOARD_FAB2_LIB.BASEBOARD_FAB2(SCH_1):PAGE234_I184@MSTR_VREG.NCP3232L(CHIPS)':
 'SS': CDS_PINID='SS';
NET_NAME
'VR_PVSA_CPU0_BIREF1'
 '@BASEBOARD_FAB2_LIB.BASEBOARD_FAB2(SCH_1):VR_PVSA_CPU0_BIREF1':
 C_SIGNAL='@baseboard_fab2_lib.baseboard_fab2(sch_1):vr_pvsa_cpu0_biref1';
NODE_NAME     EU4D4 37
 '@BASEBOARD_FAB2_LIB.BASEBOARD_FAB2(SCH_1):PAGE201_I155@MSTR_CONTROLLER.PXE1610B(CHIPS)':
 'BIREF1': CDS_PINID='BIREF1';
NODE_NAME     EU4C1 39
 '@BASEBOARD_FAB2_LIB.BASEBOARD_FAB2(SCH_1):PAGE205_I46@MSTR_DISCRETE.IR354XX(CHIPS)':
 'REFIN': CDS_PINID='REFIN';
NODE_NAME     CT60 1
 '@BASEBOARD_FAB2_LIB.BASEBOARD_FAB2(SCH_1):PAGE205_I69@DEV_DISCRETE.CAP_A(CHIPS)':
 'A': CDS_PINID='A';
NODE_NAME     CF6 1
 '@BASEBOARD_FAB2_LIB.BASEBOARD_FAB2(SCH_1):PAGE201_I173@W_HDL.SC22P50V2JN-4GP(CHIPS)':
 '1': CDS_PINID='\1\';
NODE_NAME     RF6 1
 '@BASEBOARD_FAB2_LIB.BASEBOARD_FAB2(SCH_1):PAGE201_I180@MSTR_DISCRETE.RES(CHIPS)':
 'A': CDS_PINID='A';
NET_NAME
'VR_PVSA_CPU0_BOOT'
 '@BASEBOARD_FAB2_LIB.BASEBOARD_FAB2(SCH_1):VR_PVSA_CPU0_BOOT':
 C_SIGNAL='@baseboard_fab2_lib.baseboard_fab2(sch_1):vr_pvsa_cpu0_boot';
NODE_NAME     C4C8 1
 '@BASEBOARD_FAB2_LIB.BASEBOARD_FAB2(SCH_1):PAGE205_I25@MSTR_DISCRETE.CAP(CHIPS)':
 'A': CDS_PINID='A';
NODE_NAME     RT40 1
 '@BASEBOARD_FAB2_LIB.BASEBOARD_FAB2(SCH_1):PAGE205_I78@MSTR_DISCRETE.RES(CHIPS)':
 'A': CDS_PINID='A';
NET_NAME
'VR_PVSA_CPU0_BOOT_R'
 '@BASEBOARD_FAB2_LIB.BASEBOARD_FAB2(SCH_1):VR_PVSA_CPU0_BOOT_R':
 C_SIGNAL='@baseboard_fab2_lib.baseboard_fab2(sch_1):vr_pvsa_cpu0_boot_r';
NODE_NAME     EU4C1 33
 '@BASEBOARD_FAB2_LIB.BASEBOARD_FAB2(SCH_1):PAGE205_I46@MSTR_DISCRETE.IR354XX(CHIPS)':
 'BOOST': CDS_PINID='BOOST';
NODE_NAME     RT40 2
 '@BASEBOARD_FAB2_LIB.BASEBOARD_FAB2(SCH_1):PAGE205_I78@MSTR_DISCRETE.RES(CHIPS)':
 'B': CDS_PINID='B';
NET_NAME
'VR_PVSA_CPU0_OCSET'
 '@BASEBOARD_FAB2_LIB.BASEBOARD_FAB2(SCH_1):VR_PVSA_CPU0_OCSET':
 C_SIGNAL='@baseboard_fab2_lib.baseboard_fab2(sch_1):vr_pvsa_cpu0_ocset';
NODE_NAME     EU4C1 37
 '@BASEBOARD_FAB2_LIB.BASEBOARD_FAB2(SCH_1):PAGE205_I46@MSTR_DISCRETE.IR354XX(CHIPS)':
 'OCSET': CDS_PINID='OCSET';
NODE_NAME     R4C13 1
 '@BASEBOARD_FAB2_LIB.BASEBOARD_FAB2(SCH_1):PAGE205_I62@MSTR_DISCRETE.RES(CHIPS)':
 'A': CDS_PINID='A';
NET_NAME
'VR_PVSA_CPU0_PHASE'
 '@BASEBOARD_FAB2_LIB.BASEBOARD_FAB2(SCH_1):VR_PVSA_CPU0_PHASE':
 C_SIGNAL='@baseboard_fab2_lib.baseboard_fab2(sch_1):vr_pvsa_cpu0_phase';
NODE_NAME     C4C8 2
 '@BASEBOARD_FAB2_LIB.BASEBOARD_FAB2(SCH_1):PAGE205_I25@MSTR_DISCRETE.CAP(CHIPS)':
 'B': CDS_PINID='B';
NODE_NAME     EU4C1 32
 '@BASEBOARD_FAB2_LIB.BASEBOARD_FAB2(SCH_1):PAGE205_I46@MSTR_DISCRETE.IR354XX(CHIPS)':
 'PHASE': CDS_PINID='PHASE';
NET_NAME
'VR_PVSA_CPU0_PHASE_SW'
 '@BASEBOARD_FAB2_LIB.BASEBOARD_FAB2(SCH_1):VR_PVSA_CPU0_PHASE_SW':
 C_SIGNAL='@baseboard_fab2_lib.baseboard_fab2(sch_1):vr_pvsa_cpu0_phase_sw';
NODE_NAME     EU4C1 10
 '@BASEBOARD_FAB2_LIB.BASEBOARD_FAB2(SCH_1):PAGE205_I46@MSTR_DISCRETE.IR354XX(CHIPS)':
 'SW': CDS_PINID='SW';
NODE_NAME     CT59 1
 '@BASEBOARD_FAB2_LIB.BASEBOARD_FAB2(SCH_1):PAGE205_I76@MSTR_DISCRETE.CAP(CHIPS)':
 'A': CDS_PINID='A';
NODE_NAME     L4C2 1
 '@BASEBOARD_FAB2_LIB.BASEBOARD_FAB2(SCH_1):PAGE205_I82@W_HDL.IND-300NH-20-GP(CHIPS)':
 'S': CDS_PINID='S';
NET_NAME
'VR_PVSA_CPU0_PHASE_SW_RC'
 '@BASEBOARD_FAB2_LIB.BASEBOARD_FAB2(SCH_1):VR_PVSA_CPU0_PHASE_SW_RC':
 C_SIGNAL='@baseboard_fab2_lib.baseboard_fab2(sch_1):vr_pvsa_cpu0_phase_sw_rc';
NODE_NAME     CT59 2
 '@BASEBOARD_FAB2_LIB.BASEBOARD_FAB2(SCH_1):PAGE205_I76@MSTR_DISCRETE.CAP(CHIPS)':
 'B': CDS_PINID='B';
NODE_NAME     RT39 1
 '@BASEBOARD_FAB2_LIB.BASEBOARD_FAB2(SCH_1):PAGE205_I84@W_HDL.1R3F-GP(CHIPS)':
 '1': CDS_PINID='\1\';
NET_NAME
'VR_PVSA_CPU0_PWM'
 '@BASEBOARD_FAB2_LIB.BASEBOARD_FAB2(SCH_1):VR_PVSA_CPU0_PWM':
 C_SIGNAL='@baseboard_fab2_lib.baseboard_fab2(sch_1):vr_pvsa_cpu0_pwm';
NODE_NAME     EU4D4 1
 '@BASEBOARD_FAB2_LIB.BASEBOARD_FAB2(SCH_1):PAGE201_I155@MSTR_CONTROLLER.PXE1610B(CHIPS)':
 'BPWM1': CDS_PINID='BPWM1';
NODE_NAME     EU4C1 34
 '@BASEBOARD_FAB2_LIB.BASEBOARD_FAB2(SCH_1):PAGE205_I46@MSTR_DISCRETE.IR354XX(CHIPS)':
 'PWM': CDS_PINID='PWM';
NET_NAME
'VR_PVSA_CPU0_VCIN'
 '@BASEBOARD_FAB2_LIB.BASEBOARD_FAB2(SCH_1):VR_PVSA_CPU0_VCIN':
 C_SIGNAL='@baseboard_fab2_lib.baseboard_fab2(sch_1):vr_pvsa_cpu0_vcin';
NODE_NAME     C4C6 1
 '@BASEBOARD_FAB2_LIB.BASEBOARD_FAB2(SCH_1):PAGE205_I20@MSTR_DISCRETE.CAP(CHIPS)':
 'A': CDS_PINID='A';
NODE_NAME     EU4C1 3
 '@BASEBOARD_FAB2_LIB.BASEBOARD_FAB2(SCH_1):PAGE205_I46@MSTR_DISCRETE.IR354XX(CHIPS)':
 'VCC': CDS_PINID='VCC';
NODE_NAME     R6N3 1
 '@BASEBOARD_FAB2_LIB.BASEBOARD_FAB2(SCH_1):PAGE205_I81@MSTR_DISCRETE.RES(CHIPS)':
 'A': CDS_PINID='A';
NET_NAME
'VR_PVSA_CPU1_BIREF1'
 '@BASEBOARD_FAB2_LIB.BASEBOARD_FAB2(SCH_1):VR_PVSA_CPU1_BIREF1':
 C_SIGNAL='@baseboard_fab2_lib.baseboard_fab2(sch_1):vr_pvsa_cpu1_biref1';
NODE_NAME     EU1C2 37
 '@BASEBOARD_FAB2_LIB.BASEBOARD_FAB2(SCH_1):PAGE206_I130@MSTR_CONTROLLER.PXE1610B(CHIPS)':
 'BIREF1': CDS_PINID='BIREF1';
NODE_NAME     EU1C1 39
 '@BASEBOARD_FAB2_LIB.BASEBOARD_FAB2(SCH_1):PAGE210_I51@MSTR_DISCRETE.IR354XX(CHIPS)':
 'REFIN': CDS_PINID='REFIN';
NODE_NAME     CT57 1
 '@BASEBOARD_FAB2_LIB.BASEBOARD_FAB2(SCH_1):PAGE210_I55@DEV_DISCRETE.CAP_A(CHIPS)':
 'A': CDS_PINID='A';
NODE_NAME     CF12 1
 '@BASEBOARD_FAB2_LIB.BASEBOARD_FAB2(SCH_1):PAGE206_I142@W_HDL.SC22P50V2JN-4GP(CHIPS)':
 '1': CDS_PINID='\1\';
NODE_NAME     RF12 1
 '@BASEBOARD_FAB2_LIB.BASEBOARD_FAB2(SCH_1):PAGE206_I149@MSTR_DISCRETE.RES(CHIPS)':
 'A': CDS_PINID='A';
NET_NAME
'VR_PVSA_CPU1_BOOT'
 '@BASEBOARD_FAB2_LIB.BASEBOARD_FAB2(SCH_1):VR_PVSA_CPU1_BOOT':
 C_SIGNAL='@baseboard_fab2_lib.baseboard_fab2(sch_1):vr_pvsa_cpu1_boot';
NODE_NAME     C1C12 1
 '@BASEBOARD_FAB2_LIB.BASEBOARD_FAB2(SCH_1):PAGE210_I24@MSTR_DISCRETE.CAP(CHIPS)':
 'A': CDS_PINID='A';
NODE_NAME     RT37 1
 '@BASEBOARD_FAB2_LIB.BASEBOARD_FAB2(SCH_1):PAGE210_I68@MSTR_DISCRETE.RES(CHIPS)':
 'A': CDS_PINID='A';
NET_NAME
'VR_PVSA_CPU1_BOOT_R'
 '@BASEBOARD_FAB2_LIB.BASEBOARD_FAB2(SCH_1):VR_PVSA_CPU1_BOOT_R':
 C_SIGNAL='@baseboard_fab2_lib.baseboard_fab2(sch_1):vr_pvsa_cpu1_boot_r';
NODE_NAME     EU1C1 33
 '@BASEBOARD_FAB2_LIB.BASEBOARD_FAB2(SCH_1):PAGE210_I51@MSTR_DISCRETE.IR354XX(CHIPS)':
 'BOOST': CDS_PINID='BOOST';
NODE_NAME     RT37 2
 '@BASEBOARD_FAB2_LIB.BASEBOARD_FAB2(SCH_1):PAGE210_I68@MSTR_DISCRETE.RES(CHIPS)':
 'B': CDS_PINID='B';
NET_NAME
'VR_PVSA_CPU1_OCSET'
 '@BASEBOARD_FAB2_LIB.BASEBOARD_FAB2(SCH_1):VR_PVSA_CPU1_OCSET':
 C_SIGNAL='@baseboard_fab2_lib.baseboard_fab2(sch_1):vr_pvsa_cpu1_ocset';
NODE_NAME     EU1C1 37
 '@BASEBOARD_FAB2_LIB.BASEBOARD_FAB2(SCH_1):PAGE210_I51@MSTR_DISCRETE.IR354XX(CHIPS)':
 'OCSET': CDS_PINID='OCSET';
NODE_NAME     R1C37 1
 '@BASEBOARD_FAB2_LIB.BASEBOARD_FAB2(SCH_1):PAGE210_I52@MSTR_DISCRETE.RES(CHIPS)':
 'A': CDS_PINID='A';
NET_NAME
'VR_PVSA_CPU1_PHASE'
 '@BASEBOARD_FAB2_LIB.BASEBOARD_FAB2(SCH_1):VR_PVSA_CPU1_PHASE':
 C_SIGNAL='@baseboard_fab2_lib.baseboard_fab2(sch_1):vr_pvsa_cpu1_phase';
NODE_NAME     C1C12 2
 '@BASEBOARD_FAB2_LIB.BASEBOARD_FAB2(SCH_1):PAGE210_I24@MSTR_DISCRETE.CAP(CHIPS)':
 'B': CDS_PINID='B';
NODE_NAME     EU1C1 32
 '@BASEBOARD_FAB2_LIB.BASEBOARD_FAB2(SCH_1):PAGE210_I51@MSTR_DISCRETE.IR354XX(CHIPS)':
 'PHASE': CDS_PINID='PHASE';
NET_NAME
'VR_PVSA_CPU1_PHASE_SW'
 '@BASEBOARD_FAB2_LIB.BASEBOARD_FAB2(SCH_1):VR_PVSA_CPU1_PHASE_SW':
 C_SIGNAL='@baseboard_fab2_lib.baseboard_fab2(sch_1):vr_pvsa_cpu1_phase_sw';
NODE_NAME     EU1C1 10
 '@BASEBOARD_FAB2_LIB.BASEBOARD_FAB2(SCH_1):PAGE210_I51@MSTR_DISCRETE.IR354XX(CHIPS)':
 'SW': CDS_PINID='SW';
NODE_NAME     CT56 1
 '@BASEBOARD_FAB2_LIB.BASEBOARD_FAB2(SCH_1):PAGE210_I66@MSTR_DISCRETE.CAP(CHIPS)':
 'A': CDS_PINID='A';
NODE_NAME     L1C1 1
 '@BASEBOARD_FAB2_LIB.BASEBOARD_FAB2(SCH_1):PAGE210_I72@W_HDL.IND-300NH-20-GP(CHIPS)':
 'S': CDS_PINID='S';
NET_NAME
'VR_PVSA_CPU1_PHASE_SW_RC'
 '@BASEBOARD_FAB2_LIB.BASEBOARD_FAB2(SCH_1):VR_PVSA_CPU1_PHASE_SW_RC':
 C_SIGNAL='@baseboard_fab2_lib.baseboard_fab2(sch_1):vr_pvsa_cpu1_phase_sw_rc';
NODE_NAME     CT56 2
 '@BASEBOARD_FAB2_LIB.BASEBOARD_FAB2(SCH_1):PAGE210_I66@MSTR_DISCRETE.CAP(CHIPS)':
 'B': CDS_PINID='B';
NODE_NAME     RT38 1
 '@BASEBOARD_FAB2_LIB.BASEBOARD_FAB2(SCH_1):PAGE210_I74@W_HDL.1R3F-GP(CHIPS)':
 '1': CDS_PINID='\1\';
NET_NAME
'VR_PVSA_CPU1_PWM'
 '@BASEBOARD_FAB2_LIB.BASEBOARD_FAB2(SCH_1):VR_PVSA_CPU1_PWM':
 C_SIGNAL='@baseboard_fab2_lib.baseboard_fab2(sch_1):vr_pvsa_cpu1_pwm';
NODE_NAME     EU1C2 1
 '@BASEBOARD_FAB2_LIB.BASEBOARD_FAB2(SCH_1):PAGE206_I130@MSTR_CONTROLLER.PXE1610B(CHIPS)':
 'BPWM1': CDS_PINID='BPWM1';
NODE_NAME     EU1C1 34
 '@BASEBOARD_FAB2_LIB.BASEBOARD_FAB2(SCH_1):PAGE210_I51@MSTR_DISCRETE.IR354XX(CHIPS)':
 'PWM': CDS_PINID='PWM';
NET_NAME
'VR_PVSA_CPU1_VCIN'
 '@BASEBOARD_FAB2_LIB.BASEBOARD_FAB2(SCH_1):VR_PVSA_CPU1_VCIN':
 C_SIGNAL='@baseboard_fab2_lib.baseboard_fab2(sch_1):vr_pvsa_cpu1_vcin';
NODE_NAME     C1C5 1
 '@BASEBOARD_FAB2_LIB.BASEBOARD_FAB2(SCH_1):PAGE210_I26@MSTR_DISCRETE.CAP(CHIPS)':
 'A': CDS_PINID='A';
NODE_NAME     EU1C1 3
 '@BASEBOARD_FAB2_LIB.BASEBOARD_FAB2(SCH_1):PAGE210_I51@MSTR_DISCRETE.IR354XX(CHIPS)':
 'VCC': CDS_PINID='VCC';
NODE_NAME     R9N3 1
 '@BASEBOARD_FAB2_LIB.BASEBOARD_FAB2(SCH_1):PAGE210_I71@MSTR_DISCRETE.RES(CHIPS)':
 'A': CDS_PINID='A';
NET_NAME
'VR_PVTT_ABC_BIAS'
 '@BASEBOARD_FAB2_LIB.BASEBOARD_FAB2(SCH_1):VR_PVTT_ABC_BIAS':
 C_SIGNAL='@baseboard_fab2_lib.baseboard_fab2(sch_1):vr_pvtt_abc_bias';
NODE_NAME     C4G15 1
 '@BASEBOARD_FAB2_LIB.BASEBOARD_FAB2(SCH_1):PAGE221_I13@MSTR_DISCRETE.CAP(CHIPS)':
 'A': CDS_PINID='A';
NODE_NAME     R6U4 2
 '@BASEBOARD_FAB2_LIB.BASEBOARD_FAB2(SCH_1):PAGE221_I14@MSTR_DISCRETE.RES(CHIPS)':
 'B': CDS_PINID='B';
NODE_NAME     EU4G3 2
 '@BASEBOARD_FAB2_LIB.BASEBOARD_FAB2(SCH_1):PAGE221_I15@MSTR_VREG.MIC5166(CHIPS)':
 'BIAS': CDS_PINID='BIAS';
NET_NAME
'VR_PVTT_ABC_SNS'
 '@BASEBOARD_FAB2_LIB.BASEBOARD_FAB2(SCH_1):VR_PVTT_ABC_SNS':
 C_SIGNAL='@baseboard_fab2_lib.baseboard_fab2(sch_1):vr_pvtt_abc_sns';
NODE_NAME     SH5U1 1
 '@BASEBOARD_FAB2_LIB.BASEBOARD_FAB2(SCH_1):PAGE221_I9@MSTR_MISC.SHUNT(CHIPS)':
 'A':NET_SHORT='VR_PVTT_ABC_SNS:PVTT_ABC',
 CDS_PINID='A';
NODE_NAME     EU4G3 6
 '@BASEBOARD_FAB2_LIB.BASEBOARD_FAB2(SCH_1):PAGE221_I15@MSTR_VREG.MIC5166(CHIPS)':
 'SNS': CDS_PINID='SNS';
NET_NAME
'VR_PVTT_ABC_VREF'
 '@BASEBOARD_FAB2_LIB.BASEBOARD_FAB2(SCH_1):VR_PVTT_ABC_VREF':
 C_SIGNAL='@baseboard_fab2_lib.baseboard_fab2(sch_1):vr_pvtt_abc_vref';
NODE_NAME     C4G16 1
 '@BASEBOARD_FAB2_LIB.BASEBOARD_FAB2(SCH_1):PAGE221_I22@MSTR_DISCRETE.CAP(CHIPS)':
 'A': CDS_PINID='A';
NODE_NAME     EU4G3 1
 '@BASEBOARD_FAB2_LIB.BASEBOARD_FAB2(SCH_1):PAGE221_I15@MSTR_VREG.MIC5166(CHIPS)':
 'VREF': CDS_PINID='VREF';
NET_NAME
'VR_PVTT_DEF_BIAS'
 '@BASEBOARD_FAB2_LIB.BASEBOARD_FAB2(SCH_1):VR_PVTT_DEF_BIAS':
 C_SIGNAL='@baseboard_fab2_lib.baseboard_fab2(sch_1):vr_pvtt_def_bias';
NODE_NAME     C4A10 1
 '@BASEBOARD_FAB2_LIB.BASEBOARD_FAB2(SCH_1):PAGE222_I12@MSTR_DISCRETE.CAP(CHIPS)':
 'A': CDS_PINID='A';
NODE_NAME     R6L11 2
 '@BASEBOARD_FAB2_LIB.BASEBOARD_FAB2(SCH_1):PAGE222_I10@MSTR_DISCRETE.RES(CHIPS)':
 'B': CDS_PINID='B';
NODE_NAME     EU4A1 2
 '@BASEBOARD_FAB2_LIB.BASEBOARD_FAB2(SCH_1):PAGE222_I13@MSTR_VREG.MIC5166(CHIPS)':
 'BIAS': CDS_PINID='BIAS';
NET_NAME
'VR_PVTT_DEF_SNS'
 '@BASEBOARD_FAB2_LIB.BASEBOARD_FAB2(SCH_1):VR_PVTT_DEF_SNS':
 C_SIGNAL='@baseboard_fab2_lib.baseboard_fab2(sch_1):vr_pvtt_def_sns';
NODE_NAME     EU4A1 6
 '@BASEBOARD_FAB2_LIB.BASEBOARD_FAB2(SCH_1):PAGE222_I13@MSTR_VREG.MIC5166(CHIPS)':
 'SNS': CDS_PINID='SNS';
NODE_NAME     SH5L1 1
 '@BASEBOARD_FAB2_LIB.BASEBOARD_FAB2(SCH_1):PAGE222_I30@MSTR_MISC.SHUNT(CHIPS)':
 'A':NET_SHORT='VR_PVTT_DEF_SNS:PVTT_DEF',
 CDS_PINID='A';
NET_NAME
'VR_PVTT_DEF_VREF'
 '@BASEBOARD_FAB2_LIB.BASEBOARD_FAB2(SCH_1):VR_PVTT_DEF_VREF':
 C_SIGNAL='@baseboard_fab2_lib.baseboard_fab2(sch_1):vr_pvtt_def_vref';
NODE_NAME     EU4A1 1
 '@BASEBOARD_FAB2_LIB.BASEBOARD_FAB2(SCH_1):PAGE222_I13@MSTR_VREG.MIC5166(CHIPS)':
 'VREF': CDS_PINID='VREF';
NODE_NAME     C4A9 1
 '@BASEBOARD_FAB2_LIB.BASEBOARD_FAB2(SCH_1):PAGE222_I20@MSTR_DISCRETE.CAP(CHIPS)':
 'A': CDS_PINID='A';
NET_NAME
'VR_PVTT_GHJ_BIAS'
 '@BASEBOARD_FAB2_LIB.BASEBOARD_FAB2(SCH_1):VR_PVTT_GHJ_BIAS':
 C_SIGNAL='@baseboard_fab2_lib.baseboard_fab2(sch_1):vr_pvtt_ghj_bias';
NODE_NAME     R6U7 2
 '@BASEBOARD_FAB2_LIB.BASEBOARD_FAB2(SCH_1):PAGE229_I9@MSTR_DISCRETE.RES(CHIPS)':
 'B': CDS_PINID='B';
NODE_NAME     C4G18 1
 '@BASEBOARD_FAB2_LIB.BASEBOARD_FAB2(SCH_1):PAGE229_I16@MSTR_DISCRETE.CAP(CHIPS)':
 'A': CDS_PINID='A';
NODE_NAME     EU4G2 2
 '@BASEBOARD_FAB2_LIB.BASEBOARD_FAB2(SCH_1):PAGE229_I37@MSTR_VREG.MIC5166(CHIPS)':
 'BIAS': CDS_PINID='BIAS';
NET_NAME
'VR_PVTT_GHJ_SNS'
 '@BASEBOARD_FAB2_LIB.BASEBOARD_FAB2(SCH_1):VR_PVTT_GHJ_SNS':
 C_SIGNAL='@baseboard_fab2_lib.baseboard_fab2(sch_1):vr_pvtt_ghj_sns';
NODE_NAME     SH8U1 1
 '@BASEBOARD_FAB2_LIB.BASEBOARD_FAB2(SCH_1):PAGE229_I12@MSTR_MISC.SHUNT(CHIPS)':
 'A':NET_SHORT='VR_PVTT_GHJ_SNS:PVTT_GHJ',
 CDS_PINID='A';
NODE_NAME     EU4G2 6
 '@BASEBOARD_FAB2_LIB.BASEBOARD_FAB2(SCH_1):PAGE229_I37@MSTR_VREG.MIC5166(CHIPS)':
 'SNS': CDS_PINID='SNS';
NET_NAME
'VR_PVTT_GHJ_VREF'
 '@BASEBOARD_FAB2_LIB.BASEBOARD_FAB2(SCH_1):VR_PVTT_GHJ_VREF':
 C_SIGNAL='@baseboard_fab2_lib.baseboard_fab2(sch_1):vr_pvtt_ghj_vref';
NODE_NAME     C4G21 1
 '@BASEBOARD_FAB2_LIB.BASEBOARD_FAB2(SCH_1):PAGE229_I21@MSTR_DISCRETE.CAP(CHIPS)':
 'A': CDS_PINID='A';
NODE_NAME     EU4G2 1
 '@BASEBOARD_FAB2_LIB.BASEBOARD_FAB2(SCH_1):PAGE229_I37@MSTR_VREG.MIC5166(CHIPS)':
 'VREF': CDS_PINID='VREF';
NET_NAME
'VR_PVTT_KLM_BIAS'
 '@BASEBOARD_FAB2_LIB.BASEBOARD_FAB2(SCH_1):VR_PVTT_KLM_BIAS':
 C_SIGNAL='@baseboard_fab2_lib.baseboard_fab2(sch_1):vr_pvtt_klm_bias';
NODE_NAME     C4A8 1
 '@BASEBOARD_FAB2_LIB.BASEBOARD_FAB2(SCH_1):PAGE230_I12@MSTR_DISCRETE.CAP(CHIPS)':
 'A': CDS_PINID='A';
NODE_NAME     R6L8 2
 '@BASEBOARD_FAB2_LIB.BASEBOARD_FAB2(SCH_1):PAGE230_I13@MSTR_DISCRETE.RES(CHIPS)':
 'B': CDS_PINID='B';
NODE_NAME     EU4A2 2
 '@BASEBOARD_FAB2_LIB.BASEBOARD_FAB2(SCH_1):PAGE230_I37@MSTR_VREG.MIC5166(CHIPS)':
 'BIAS': CDS_PINID='BIAS';
NET_NAME
'VR_PVTT_KLM_SNS'
 '@BASEBOARD_FAB2_LIB.BASEBOARD_FAB2(SCH_1):VR_PVTT_KLM_SNS':
 C_SIGNAL='@baseboard_fab2_lib.baseboard_fab2(sch_1):vr_pvtt_klm_sns';
NODE_NAME     SH8L1 1
 '@BASEBOARD_FAB2_LIB.BASEBOARD_FAB2(SCH_1):PAGE230_I30@MSTR_MISC.SHUNT(CHIPS)':
 'A':NET_SHORT='VR_PVTT_KLM_SNS:PVTT_KLM',
 CDS_PINID='A';
NODE_NAME     EU4A2 6
 '@BASEBOARD_FAB2_LIB.BASEBOARD_FAB2(SCH_1):PAGE230_I37@MSTR_VREG.MIC5166(CHIPS)':
 'SNS': CDS_PINID='SNS';
NET_NAME
'VR_PVTT_KLM_VREF'
 '@BASEBOARD_FAB2_LIB.BASEBOARD_FAB2(SCH_1):VR_PVTT_KLM_VREF':
 C_SIGNAL='@baseboard_fab2_lib.baseboard_fab2(sch_1):vr_pvtt_klm_vref';
NODE_NAME     C4A14 1
 '@BASEBOARD_FAB2_LIB.BASEBOARD_FAB2(SCH_1):PAGE230_I36@MSTR_DISCRETE.CAP(CHIPS)':
 'A': CDS_PINID='A';
NODE_NAME     EU4A2 1
 '@BASEBOARD_FAB2_LIB.BASEBOARD_FAB2(SCH_1):PAGE230_I37@MSTR_VREG.MIC5166(CHIPS)':
 'VREF': CDS_PINID='VREF';
NET_NAME
'VR_VB_PVPP_ABC'
 '@BASEBOARD_FAB2_LIB.BASEBOARD_FAB2(SCH_1):VR_VB_PVPP_ABC':
 C_SIGNAL='@baseboard_fab2_lib.baseboard_fab2(sch_1):vr_vb_pvpp_abc';
NODE_NAME     EU7F1 38
 '@BASEBOARD_FAB2_LIB.BASEBOARD_FAB2(SCH_1):PAGE231_I193@MSTR_VREG.NCP3232L(CHIPS)':
 'VB': CDS_PINID='VB';
NODE_NAME     C3T11 1
 '@BASEBOARD_FAB2_LIB.BASEBOARD_FAB2(SCH_1):PAGE231_I202@MSTR_DISCRETE.CAP(CHIPS)':
 'A': CDS_PINID='A';
NET_NAME
'VR_VB_PVPP_DEF'
 '@BASEBOARD_FAB2_LIB.BASEBOARD_FAB2(SCH_1):VR_VB_PVPP_DEF':
 C_SIGNAL='@baseboard_fab2_lib.baseboard_fab2(sch_1):vr_vb_pvpp_def';
NODE_NAME     EU7B1 38
 '@BASEBOARD_FAB2_LIB.BASEBOARD_FAB2(SCH_1):PAGE232_I214@MSTR_VREG.NCP3232L(CHIPS)':
 'VB': CDS_PINID='VB';
NODE_NAME     C3M10 1
 '@BASEBOARD_FAB2_LIB.BASEBOARD_FAB2(SCH_1):PAGE232_I253@MSTR_DISCRETE.CAP(CHIPS)':
 'A': CDS_PINID='A';
NET_NAME
'VR_VB_PVPP_GHJ'
 '@BASEBOARD_FAB2_LIB.BASEBOARD_FAB2(SCH_1):VR_VB_PVPP_GHJ':
 C_SIGNAL='@baseboard_fab2_lib.baseboard_fab2(sch_1):vr_vb_pvpp_ghj';
NODE_NAME     C6U6 1
 '@BASEBOARD_FAB2_LIB.BASEBOARD_FAB2(SCH_1):PAGE233_I187@MSTR_DISCRETE.CAP(CHIPS)':
 'A': CDS_PINID='A';
NODE_NAME     EU4G1 38
 '@BASEBOARD_FAB2_LIB.BASEBOARD_FAB2(SCH_1):PAGE233_I225@MSTR_VREG.NCP3232L(CHIPS)':
 'VB': CDS_PINID='VB';
NET_NAME
'VR_VB_PVPP_KLM'
 '@BASEBOARD_FAB2_LIB.BASEBOARD_FAB2(SCH_1):VR_VB_PVPP_KLM':
 C_SIGNAL='@baseboard_fab2_lib.baseboard_fab2(sch_1):vr_vb_pvpp_klm';
NODE_NAME     C6L12 1
 '@BASEBOARD_FAB2_LIB.BASEBOARD_FAB2(SCH_1):PAGE234_I144@MSTR_DISCRETE.CAP(CHIPS)':
 'A': CDS_PINID='A';
NODE_NAME     EU4A3 38
 '@BASEBOARD_FAB2_LIB.BASEBOARD_FAB2(SCH_1):PAGE234_I184@MSTR_VREG.NCP3232L(CHIPS)':
 'VB': CDS_PINID='VB';
NET_NAME
'VR_VRRDY_PVCCIN_CPU0'
 '@BASEBOARD_FAB2_LIB.BASEBOARD_FAB2(SCH_1):VR_VRRDY_PVCCIN_CPU0':
 C_SIGNAL='@baseboard_fab2_lib.baseboard_fab2(sch_1):vr_vrrdy_pvccin_cpu0';
NODE_NAME     R4D58 2
 '@BASEBOARD_FAB2_LIB.BASEBOARD_FAB2(SCH_1):PAGE201_I25@MSTR_DISCRETE.RES(CHIPS)':
 'B': CDS_PINID='B';
NODE_NAME     R4D63 1
 '@BASEBOARD_FAB2_LIB.BASEBOARD_FAB2(SCH_1):PAGE201_I124@MSTR_DISCRETE.RES(CHIPS)':
 'A': CDS_PINID='A';
NODE_NAME     C4D42 1
 '@BASEBOARD_FAB2_LIB.BASEBOARD_FAB2(SCH_1):PAGE201_I125@MSTR_DISCRETE.CAP(CHIPS)':
 'A': CDS_PINID='A';
NODE_NAME     EU4D4 11
 '@BASEBOARD_FAB2_LIB.BASEBOARD_FAB2(SCH_1):PAGE201_I155@MSTR_CONTROLLER.PXE1610B(CHIPS)':
 'AVRRDY': CDS_PINID='AVRRDY';
NET_NAME
'VR_VRRDY_PVCCIN_CPU1'
 '@BASEBOARD_FAB2_LIB.BASEBOARD_FAB2(SCH_1):VR_VRRDY_PVCCIN_CPU1':
 C_SIGNAL='@baseboard_fab2_lib.baseboard_fab2(sch_1):vr_vrrdy_pvccin_cpu1';
NODE_NAME     R1C28 2
 '@BASEBOARD_FAB2_LIB.BASEBOARD_FAB2(SCH_1):PAGE206_I35@MSTR_DISCRETE.RES(CHIPS)':
 'B': CDS_PINID='B';
NODE_NAME     R1C30 1
 '@BASEBOARD_FAB2_LIB.BASEBOARD_FAB2(SCH_1):PAGE206_I113@MSTR_DISCRETE.RES(CHIPS)':
 'A': CDS_PINID='A';
NODE_NAME     C1C23 1
 '@BASEBOARD_FAB2_LIB.BASEBOARD_FAB2(SCH_1):PAGE206_I114@MSTR_DISCRETE.CAP(CHIPS)':
 'A': CDS_PINID='A';
NODE_NAME     EU1C2 11
 '@BASEBOARD_FAB2_LIB.BASEBOARD_FAB2(SCH_1):PAGE206_I130@MSTR_CONTROLLER.PXE1610B(CHIPS)':
 'AVRRDY': CDS_PINID='AVRRDY';
NET_NAME
'VSENSE_P12V_ADM1085'
 '@BASEBOARD_FAB2_LIB.BASEBOARD_FAB2(SCH_1):VSENSE_P12V_ADM1085':
 C_SIGNAL='@baseboard_fab2_lib.baseboard_fab2(sch_1):vsense_p12v_adm1085';
NODE_NAME     U7D3 3
 '@BASEBOARD_FAB2_LIB.BASEBOARD_FAB2(SCH_1):PAGE196_I70@MSTR_ANALOG.ADM1085(CHIPS)':
 'VIN': CDS_PINID='VIN';
NODE_NAME     R3P48 2
 '@BASEBOARD_FAB2_LIB.BASEBOARD_FAB2(SCH_1):PAGE196_I74@MSTR_DISCRETE.RES(CHIPS)':
 'B': CDS_PINID='B';
NODE_NAME     R3P51 1
 '@BASEBOARD_FAB2_LIB.BASEBOARD_FAB2(SCH_1):PAGE196_I75@MSTR_DISCRETE.RES(CHIPS)':
 'A': CDS_PINID='A';
NET_NAME
'VSENSE_P1V05_PCH_STBY_AVSN'
 '@BASEBOARD_FAB2_LIB.BASEBOARD_FAB2(SCH_1):VSENSE_P1V05_PCH_STBY_AVSN':
 C_SIGNAL='@baseboard_fab2_lib.baseboard_fab2(sch_1):vsense_p1v05_pch_stby_avsn';
NODE_NAME     C2L2 2
 '@BASEBOARD_FAB2_LIB.BASEBOARD_FAB2(SCH_1):PAGE235_I153@MSTR_DISCRETE.CAP(CHIPS)':
 'B': CDS_PINID='B';
NODE_NAME     EU8A1 30
 '@BASEBOARD_FAB2_LIB.BASEBOARD_FAB2(SCH_1):PAGE235_I229@MSTR_CONTROLLER.PXE1110B(CHIPS)':
 'BVREF': CDS_PINID='BVREF';
NODE_NAME     R8B15 2
 '@BASEBOARD_FAB2_LIB.BASEBOARD_FAB2(SCH_1):PAGE236_I57@MSTR_DISCRETE.RES(CHIPS)':
 'B': CDS_PINID='B';
NODE_NAME     R8B12 1
 '@BASEBOARD_FAB2_LIB.BASEBOARD_FAB2(SCH_1):PAGE236_I59@MSTR_DISCRETE.RES(CHIPS)':
 'A': CDS_PINID='A';
NET_NAME
'VSENSE_P1V05_PCH_STBY_AVSP'
 '@BASEBOARD_FAB2_LIB.BASEBOARD_FAB2(SCH_1):VSENSE_P1V05_PCH_STBY_AVSP':
 C_SIGNAL='@baseboard_fab2_lib.baseboard_fab2(sch_1):vsense_p1v05_pch_stby_avsp';
NODE_NAME     R2L8 1
 '@BASEBOARD_FAB2_LIB.BASEBOARD_FAB2(SCH_1):PAGE235_I154@MSTR_DISCRETE.RES(CHIPS)':
 'A': CDS_PINID='A';
NODE_NAME     R8B14 1
 '@BASEBOARD_FAB2_LIB.BASEBOARD_FAB2(SCH_1):PAGE236_I56@MSTR_DISCRETE.RES(CHIPS)':
 'A': CDS_PINID='A';
NODE_NAME     R8B15 1
 '@BASEBOARD_FAB2_LIB.BASEBOARD_FAB2(SCH_1):PAGE236_I57@MSTR_DISCRETE.RES(CHIPS)':
 'A': CDS_PINID='A';
NET_NAME
'VSENSE_P1V8MCP_CPU0_SKT_VRTN'
 '@BASEBOARD_FAB2_LIB.BASEBOARD_FAB2(SCH_1):VSENSE_P1V8MCP_CPU0_SKT_VRTN':
 C_SIGNAL='@baseboard_fab2_lib.baseboard_fab2(sch_1):vsense_p1v8mcp_cpu0_skt_vrt~
n';
NODE_NAME     U5D1 AL20
 '@BASEBOARD_FAB2_LIB.BASEBOARD_FAB2(SCH_1):PAGE22_I204@CHPSET_LIB.SKX_EXT_B(CHIPS)':
 'RSVD'<215>: CDS_PINID='RSVD(215)';
NODE_NAME     J6E1 D2
 '@BASEBOARD_FAB2_LIB.BASEBOARD_FAB2(SCH_1):PAGE194_I55@MSTR_SCONN.SCONN120_H61426002(CHIPS)':
 'IOD2': CDS_PINID='IOD2';
NET_NAME
'VSENSE_P1V8MCP_CPU0_SKT_VSEN'
 '@BASEBOARD_FAB2_LIB.BASEBOARD_FAB2(SCH_1):VSENSE_P1V8MCP_CPU0_SKT_VSEN':
 C_SIGNAL='@baseboard_fab2_lib.baseboard_fab2(sch_1):vsense_p1v8mcp_cpu0_skt_vse~
n';
NODE_NAME     U5D1 AK21
 '@BASEBOARD_FAB2_LIB.BASEBOARD_FAB2(SCH_1):PAGE22_I204@CHPSET_LIB.SKX_EXT_B(CHIPS)':
 'RSVD'<221>: CDS_PINID='RSVD(221)';
NODE_NAME     J6E1 D1
 '@BASEBOARD_FAB2_LIB.BASEBOARD_FAB2(SCH_1):PAGE194_I55@MSTR_SCONN.SCONN120_H61426002(CHIPS)':
 'IOD1': CDS_PINID='IOD1';
NET_NAME
'VSENSE_P1V8MCP_CPU1_SKT_VRTN'
 '@BASEBOARD_FAB2_LIB.BASEBOARD_FAB2(SCH_1):VSENSE_P1V8MCP_CPU1_SKT_VRTN':
 C_SIGNAL='@baseboard_fab2_lib.baseboard_fab2(sch_1):vsense_p1v8mcp_cpu1_skt_vrt~
n';
NODE_NAME     U2D1 AL20
 '@BASEBOARD_FAB2_LIB.BASEBOARD_FAB2(SCH_1):PAGE56_I169@CHPSET_LIB.SKX_EXT_B(CHIPS)':
 'RSVD'<215>: CDS_PINID='RSVD(215)';
NODE_NAME     J4E1 D2
 '@BASEBOARD_FAB2_LIB.BASEBOARD_FAB2(SCH_1):PAGE193_I45@MSTR_SCONN.SCONN120_H61426002(CHIPS)':
 'IOD2': CDS_PINID='IOD2';
NET_NAME
'VSENSE_P1V8MCP_CPU1_SKT_VSEN'
 '@BASEBOARD_FAB2_LIB.BASEBOARD_FAB2(SCH_1):VSENSE_P1V8MCP_CPU1_SKT_VSEN':
 C_SIGNAL='@baseboard_fab2_lib.baseboard_fab2(sch_1):vsense_p1v8mcp_cpu1_skt_vse~
n';
NODE_NAME     U2D1 AK21
 '@BASEBOARD_FAB2_LIB.BASEBOARD_FAB2(SCH_1):PAGE56_I169@CHPSET_LIB.SKX_EXT_B(CHIPS)':
 'RSVD'<221>: CDS_PINID='RSVD(221)';
NODE_NAME     J4E1 D1
 '@BASEBOARD_FAB2_LIB.BASEBOARD_FAB2(SCH_1):PAGE193_I45@MSTR_SCONN.SCONN120_H61426002(CHIPS)':
 'IOD1': CDS_PINID='IOD1';
NET_NAME
'VSENSE_P3V3_STBY'
 '@BASEBOARD_FAB2_LIB.BASEBOARD_FAB2(SCH_1):VSENSE_P3V3_STBY':
 C_SIGNAL='@baseboard_fab2_lib.baseboard_fab2(sch_1):vsense_p3v3_stby';
NODE_NAME     R8E31 1
 '@BASEBOARD_FAB2_LIB.BASEBOARD_FAB2(SCH_1):PAGE240_I143@MSTR_DISCRETE.RES(CHIPS)':
 'A': CDS_PINID='A';
NODE_NAME     R8E25 2
 '@BASEBOARD_FAB2_LIB.BASEBOARD_FAB2(SCH_1):PAGE240_I144@MSTR_DISCRETE.RES(CHIPS)':
 'B': CDS_PINID='B';
NET_NAME
'VSENSE_PMAX_CPU0'
 '@BASEBOARD_FAB2_LIB.BASEBOARD_FAB2(SCH_1):VSENSE_PMAX_CPU0':
 C_SIGNAL='@baseboard_fab2_lib.baseboard_fab2(sch_1):vsense_pmax_cpu0';
NODE_NAME     R5D5 1
 '@BASEBOARD_FAB2_LIB.BASEBOARD_FAB2(SCH_1):PAGE37_I303@MSTR_DISCRETE.RES(CHIPS)':
 'A': CDS_PINID='A';
NODE_NAME     U5D1 AD41
 '@BASEBOARD_FAB2_LIB.BASEBOARD_FAB2(SCH_1):PAGE37_I311@CHPSET_LIB.SKX_EXT_B(CHIPS)':
 'VSENSEPMAX': CDS_PINID='VSENSEPMAX';
NODE_NAME     R5D6 2
 '@BASEBOARD_FAB2_LIB.BASEBOARD_FAB2(SCH_1):PAGE37_I312@MSTR_DISCRETE.RES(CHIPS)':
 'B': CDS_PINID='B';
NET_NAME
'VSENSE_PMAX_CPU1'
 '@BASEBOARD_FAB2_LIB.BASEBOARD_FAB2(SCH_1):VSENSE_PMAX_CPU1':
 C_SIGNAL='@baseboard_fab2_lib.baseboard_fab2(sch_1):vsense_pmax_cpu1';
NODE_NAME     R3D27 1
 '@BASEBOARD_FAB2_LIB.BASEBOARD_FAB2(SCH_1):PAGE71_I43@MSTR_DISCRETE.RES(CHIPS)':
 'A': CDS_PINID='A';
NODE_NAME     U2D1 AD41
 '@BASEBOARD_FAB2_LIB.BASEBOARD_FAB2(SCH_1):PAGE71_I51@CHPSET_LIB.SKX_EXT_B(CHIPS)':
 'VSENSEPMAX': CDS_PINID='VSENSEPMAX';
NODE_NAME     R3D32 2
 '@BASEBOARD_FAB2_LIB.BASEBOARD_FAB2(SCH_1):PAGE71_I53@MSTR_DISCRETE.RES(CHIPS)':
 'B': CDS_PINID='B';
NET_NAME
'VSENSE_PVCCIN_CPU0_AVSP'
 '@BASEBOARD_FAB2_LIB.BASEBOARD_FAB2(SCH_1):VSENSE_PVCCIN_CPU0_AVSP':
 C_SIGNAL='@baseboard_fab2_lib.baseboard_fab2(sch_1):vsense_pvccin_cpu0_avsp';
NODE_NAME     C4D45 1
 '@BASEBOARD_FAB2_LIB.BASEBOARD_FAB2(SCH_1):PAGE201_I70@MSTR_DISCRETE.CAP(CHIPS)':
 'A': CDS_PINID='A';
NODE_NAME     R4E8 2
 '@BASEBOARD_FAB2_LIB.BASEBOARD_FAB2(SCH_1):PAGE201_I109@MSTR_DISCRETE.RES(CHIPS)':
 'B': CDS_PINID='B';
NODE_NAME     EU4D4 21
 '@BASEBOARD_FAB2_LIB.BASEBOARD_FAB2(SCH_1):PAGE201_I155@MSTR_CONTROLLER.PXE1610B(CHIPS)':
 'AVSEN': CDS_PINID='AVSEN';
NET_NAME
'VSENSE_PVCCIN_CPU0_N'
 '@BASEBOARD_FAB2_LIB.BASEBOARD_FAB2(SCH_1):VSENSE_PVCCIN_CPU0_N':
 C_SIGNAL='@baseboard_fab2_lib.baseboard_fab2(sch_1):vsense_pvccin_cpu0_n';
NODE_NAME     C4D45 2
 '@BASEBOARD_FAB2_LIB.BASEBOARD_FAB2(SCH_1):PAGE201_I70@MSTR_DISCRETE.CAP(CHIPS)':
 'B': CDS_PINID='B';
NODE_NAME     EU4D4 22
 '@BASEBOARD_FAB2_LIB.BASEBOARD_FAB2(SCH_1):PAGE201_I155@MSTR_CONTROLLER.PXE1610B(CHIPS)':
 'AVREF': CDS_PINID='AVREF';
NODE_NAME     R4E17 1
 '@BASEBOARD_FAB2_LIB.BASEBOARD_FAB2(SCH_1):PAGE204_I62@MSTR_DISCRETE.RES(CHIPS)':
 'A': CDS_PINID='A';
NODE_NAME     R4E15 2
 '@BASEBOARD_FAB2_LIB.BASEBOARD_FAB2(SCH_1):PAGE204_I63@MSTR_DISCRETE.RES(CHIPS)':
 'B': CDS_PINID='B';
NODE_NAME     R4E18 1
 '@BASEBOARD_FAB2_LIB.BASEBOARD_FAB2(SCH_1):PAGE204_I64@MSTR_DISCRETE.RES(CHIPS)':
 'A': CDS_PINID='A';
NET_NAME
'VSENSE_PVCCIN_CPU0_P'
 '@BASEBOARD_FAB2_LIB.BASEBOARD_FAB2(SCH_1):VSENSE_PVCCIN_CPU0_P':
 C_SIGNAL='@baseboard_fab2_lib.baseboard_fab2(sch_1):vsense_pvccin_cpu0_p';
NODE_NAME     R4E8 1
 '@BASEBOARD_FAB2_LIB.BASEBOARD_FAB2(SCH_1):PAGE201_I109@MSTR_DISCRETE.RES(CHIPS)':
 'A': CDS_PINID='A';
NODE_NAME     R4E14 1
 '@BASEBOARD_FAB2_LIB.BASEBOARD_FAB2(SCH_1):PAGE204_I60@MSTR_DISCRETE.RES(CHIPS)':
 'A': CDS_PINID='A';
NODE_NAME     R4E16 1
 '@BASEBOARD_FAB2_LIB.BASEBOARD_FAB2(SCH_1):PAGE204_I61@MSTR_DISCRETE.RES(CHIPS)':
 'A': CDS_PINID='A';
NODE_NAME     R4E15 1
 '@BASEBOARD_FAB2_LIB.BASEBOARD_FAB2(SCH_1):PAGE204_I63@MSTR_DISCRETE.RES(CHIPS)':
 'A': CDS_PINID='A';
NET_NAME
'VSENSE_PVCCIN_CPU0_SKT_VRTN'
 '@BASEBOARD_FAB2_LIB.BASEBOARD_FAB2(SCH_1):VSENSE_PVCCIN_CPU0_SKT_VRTN':
 C_SIGNAL='@baseboard_fab2_lib.baseboard_fab2(sch_1):vsense_pvccin_cpu0_skt_vrtn~
';
NODE_NAME     U5D1 AY85
 '@BASEBOARD_FAB2_LIB.BASEBOARD_FAB2(SCH_1):PAGE37_I311@CHPSET_LIB.SKX_EXT_B(CHIPS)':
 'VSS_VCCIN_SENSE': CDS_PINID='VSS_VCCIN_SENSE';
NODE_NAME     R4E17 2
 '@BASEBOARD_FAB2_LIB.BASEBOARD_FAB2(SCH_1):PAGE204_I62@MSTR_DISCRETE.RES(CHIPS)':
 'B': CDS_PINID='B';
NET_NAME
'VSENSE_PVCCIN_CPU0_SKT_VSEN'
 '@BASEBOARD_FAB2_LIB.BASEBOARD_FAB2(SCH_1):VSENSE_PVCCIN_CPU0_SKT_VSEN':
 C_SIGNAL='@baseboard_fab2_lib.baseboard_fab2(sch_1):vsense_pvccin_cpu0_skt_vsen~
';
NODE_NAME     U5D1 BA86
 '@BASEBOARD_FAB2_LIB.BASEBOARD_FAB2(SCH_1):PAGE37_I311@CHPSET_LIB.SKX_EXT_B(CHIPS)':
 'VCCIN_SENSE': CDS_PINID='VCCIN_SENSE';
NODE_NAME     R4E16 2
 '@BASEBOARD_FAB2_LIB.BASEBOARD_FAB2(SCH_1):PAGE204_I61@MSTR_DISCRETE.RES(CHIPS)':
 'B': CDS_PINID='B';
NET_NAME
'VSENSE_PVCCIN_CPU1_AVSP'
 '@BASEBOARD_FAB2_LIB.BASEBOARD_FAB2(SCH_1):VSENSE_PVCCIN_CPU1_AVSP':
 C_SIGNAL='@baseboard_fab2_lib.baseboard_fab2(sch_1):vsense_pvccin_cpu1_avsp';
NODE_NAME     C1D1 1
 '@BASEBOARD_FAB2_LIB.BASEBOARD_FAB2(SCH_1):PAGE206_I78@MSTR_DISCRETE.CAP(CHIPS)':
 'A': CDS_PINID='A';
NODE_NAME     R1D4 2
 '@BASEBOARD_FAB2_LIB.BASEBOARD_FAB2(SCH_1):PAGE206_I79@MSTR_DISCRETE.RES(CHIPS)':
 'B': CDS_PINID='B';
NODE_NAME     EU1C2 21
 '@BASEBOARD_FAB2_LIB.BASEBOARD_FAB2(SCH_1):PAGE206_I130@MSTR_CONTROLLER.PXE1610B(CHIPS)':
 'AVSEN': CDS_PINID='AVSEN';
NET_NAME
'VSENSE_PVCCIN_CPU1_N'
 '@BASEBOARD_FAB2_LIB.BASEBOARD_FAB2(SCH_1):VSENSE_PVCCIN_CPU1_N':
 C_SIGNAL='@baseboard_fab2_lib.baseboard_fab2(sch_1):vsense_pvccin_cpu1_n';
NODE_NAME     C1D1 2
 '@BASEBOARD_FAB2_LIB.BASEBOARD_FAB2(SCH_1):PAGE206_I78@MSTR_DISCRETE.CAP(CHIPS)':
 'B': CDS_PINID='B';
NODE_NAME     EU1C2 22
 '@BASEBOARD_FAB2_LIB.BASEBOARD_FAB2(SCH_1):PAGE206_I130@MSTR_CONTROLLER.PXE1610B(CHIPS)':
 'AVREF': CDS_PINID='AVREF';
NODE_NAME     R1E5 2
 '@BASEBOARD_FAB2_LIB.BASEBOARD_FAB2(SCH_1):PAGE209_I3@MSTR_DISCRETE.RES(CHIPS)':
 'B': CDS_PINID='B';
NODE_NAME     R1E8 1
 '@BASEBOARD_FAB2_LIB.BASEBOARD_FAB2(SCH_1):PAGE209_I9@MSTR_DISCRETE.RES(CHIPS)':
 'A': CDS_PINID='A';
NODE_NAME     R1E7 1
 '@BASEBOARD_FAB2_LIB.BASEBOARD_FAB2(SCH_1):PAGE209_I10@MSTR_DISCRETE.RES(CHIPS)':
 'A': CDS_PINID='A';
NET_NAME
'VSENSE_PVCCIN_CPU1_P'
 '@BASEBOARD_FAB2_LIB.BASEBOARD_FAB2(SCH_1):VSENSE_PVCCIN_CPU1_P':
 C_SIGNAL='@baseboard_fab2_lib.baseboard_fab2(sch_1):vsense_pvccin_cpu1_p';
NODE_NAME     R1D4 1
 '@BASEBOARD_FAB2_LIB.BASEBOARD_FAB2(SCH_1):PAGE206_I79@MSTR_DISCRETE.RES(CHIPS)':
 'A': CDS_PINID='A';
NODE_NAME     R1E5 1
 '@BASEBOARD_FAB2_LIB.BASEBOARD_FAB2(SCH_1):PAGE209_I3@MSTR_DISCRETE.RES(CHIPS)':
 'A': CDS_PINID='A';
NODE_NAME     R1E6 1
 '@BASEBOARD_FAB2_LIB.BASEBOARD_FAB2(SCH_1):PAGE209_I11@MSTR_DISCRETE.RES(CHIPS)':
 'A': CDS_PINID='A';
NODE_NAME     R1E4 1
 '@BASEBOARD_FAB2_LIB.BASEBOARD_FAB2(SCH_1):PAGE209_I15@MSTR_DISCRETE.RES(CHIPS)':
 'A': CDS_PINID='A';
NET_NAME
'VSENSE_PVCCIN_CPU1_SKT_VRTN'
 '@BASEBOARD_FAB2_LIB.BASEBOARD_FAB2(SCH_1):VSENSE_PVCCIN_CPU1_SKT_VRTN':
 C_SIGNAL='@baseboard_fab2_lib.baseboard_fab2(sch_1):vsense_pvccin_cpu1_skt_vrtn~
';
NODE_NAME     U2D1 AY85
 '@BASEBOARD_FAB2_LIB.BASEBOARD_FAB2(SCH_1):PAGE71_I51@CHPSET_LIB.SKX_EXT_B(CHIPS)':
 'VSS_VCCIN_SENSE': CDS_PINID='VSS_VCCIN_SENSE';
NODE_NAME     R1E7 2
 '@BASEBOARD_FAB2_LIB.BASEBOARD_FAB2(SCH_1):PAGE209_I10@MSTR_DISCRETE.RES(CHIPS)':
 'B': CDS_PINID='B';
NET_NAME
'VSENSE_PVCCIN_CPU1_SKT_VSEN'
 '@BASEBOARD_FAB2_LIB.BASEBOARD_FAB2(SCH_1):VSENSE_PVCCIN_CPU1_SKT_VSEN':
 C_SIGNAL='@baseboard_fab2_lib.baseboard_fab2(sch_1):vsense_pvccin_cpu1_skt_vsen~
';
NODE_NAME     U2D1 BA86
 '@BASEBOARD_FAB2_LIB.BASEBOARD_FAB2(SCH_1):PAGE71_I51@CHPSET_LIB.SKX_EXT_B(CHIPS)':
 'VCCIN_SENSE': CDS_PINID='VCCIN_SENSE';
NODE_NAME     R1E6 2
 '@BASEBOARD_FAB2_LIB.BASEBOARD_FAB2(SCH_1):PAGE209_I11@MSTR_DISCRETE.RES(CHIPS)':
 'B': CDS_PINID='B';
NET_NAME
'VSENSE_PVCCIOMCP_CPU0_SKT_VRTN'
 '@BASEBOARD_FAB2_LIB.BASEBOARD_FAB2(SCH_1):VSENSE_PVCCIOMCP_CPU0_SKT_VRTN':
 C_SIGNAL='@baseboard_fab2_lib.baseboard_fab2(sch_1):vsense_pvcciomcp_cpu0_skt_v~
rtn';
NODE_NAME     U5D1 BU16
 '@BASEBOARD_FAB2_LIB.BASEBOARD_FAB2(SCH_1):PAGE39_I127@CHPSET_LIB.SKX_EXT_B(CHIPS)':
 'CD_VCCP_SENSE'<0>: CDS_PINID='CD_VCCP_SENSE(0)';
NODE_NAME     J6B1 F8
 '@BASEBOARD_FAB2_LIB.BASEBOARD_FAB2(SCH_1):PAGE194_I56@MSTR_SCONN.SCONN120_H61426002(CHIPS)':
 'IOF8': CDS_PINID='IOF8';
NET_NAME
'VSENSE_PVCCIOMCP_CPU0_SKT_VSEN'
 '@BASEBOARD_FAB2_LIB.BASEBOARD_FAB2(SCH_1):VSENSE_PVCCIOMCP_CPU0_SKT_VSEN':
 C_SIGNAL='@baseboard_fab2_lib.baseboard_fab2(sch_1):vsense_pvcciomcp_cpu0_skt_v~
sen';
NODE_NAME     U5D1 BT17
 '@BASEBOARD_FAB2_LIB.BASEBOARD_FAB2(SCH_1):PAGE39_I127@CHPSET_LIB.SKX_EXT_B(CHIPS)':
 'CD_VCCP_SENSE'<1>: CDS_PINID='CD_VCCP_SENSE(1)';
NODE_NAME     J6B1 E8
 '@BASEBOARD_FAB2_LIB.BASEBOARD_FAB2(SCH_1):PAGE194_I56@MSTR_SCONN.SCONN120_H61426002(CHIPS)':
 'IOE8': CDS_PINID='IOE8';
NET_NAME
'VSENSE_PVCCIOMCP_CPU1_SKT_VRTN'
 '@BASEBOARD_FAB2_LIB.BASEBOARD_FAB2(SCH_1):VSENSE_PVCCIOMCP_CPU1_SKT_VRTN':
 C_SIGNAL='@baseboard_fab2_lib.baseboard_fab2(sch_1):vsense_pvcciomcp_cpu1_skt_v~
rtn';
NODE_NAME     U2D1 BU16
 '@BASEBOARD_FAB2_LIB.BASEBOARD_FAB2(SCH_1):PAGE73_I107@CHPSET_LIB.SKX_EXT_B(CHIPS)':
 'CD_VCCP_SENSE'<0>: CDS_PINID='CD_VCCP_SENSE(0)';
NODE_NAME     J4B2 F8
 '@BASEBOARD_FAB2_LIB.BASEBOARD_FAB2(SCH_1):PAGE193_I46@MSTR_SCONN.SCONN120_H61426002(CHIPS)':
 'IOF8': CDS_PINID='IOF8';
NET_NAME
'VSENSE_PVCCIOMCP_CPU1_SKT_VSEN'
 '@BASEBOARD_FAB2_LIB.BASEBOARD_FAB2(SCH_1):VSENSE_PVCCIOMCP_CPU1_SKT_VSEN':
 C_SIGNAL='@baseboard_fab2_lib.baseboard_fab2(sch_1):vsense_pvcciomcp_cpu1_skt_v~
sen';
NODE_NAME     U2D1 BT17
 '@BASEBOARD_FAB2_LIB.BASEBOARD_FAB2(SCH_1):PAGE73_I107@CHPSET_LIB.SKX_EXT_B(CHIPS)':
 'CD_VCCP_SENSE'<1>: CDS_PINID='CD_VCCP_SENSE(1)';
NODE_NAME     J4B2 E8
 '@BASEBOARD_FAB2_LIB.BASEBOARD_FAB2(SCH_1):PAGE193_I46@MSTR_SCONN.SCONN120_H61426002(CHIPS)':
 'IOE8': CDS_PINID='IOE8';
NET_NAME
'VSENSE_PVCCIO_CPU0_AVSN'
 '@BASEBOARD_FAB2_LIB.BASEBOARD_FAB2(SCH_1):VSENSE_PVCCIO_CPU0_AVSN':
 C_SIGNAL='@baseboard_fab2_lib.baseboard_fab2(sch_1):vsense_pvccio_cpu0_avsn';
NODE_NAME     C3N39 2
 '@BASEBOARD_FAB2_LIB.BASEBOARD_FAB2(SCH_1):PAGE211_I83@MSTR_DISCRETE.CAP(CHIPS)':
 'B': CDS_PINID='B';
NODE_NAME     EU3P1 20
 '@BASEBOARD_FAB2_LIB.BASEBOARD_FAB2(SCH_1):PAGE211_I93@MSTR_CONTROLLER.PXE1110B(CHIPS)':
 'AVREF': CDS_PINID='AVREF';
NODE_NAME     R3N20 1
 '@BASEBOARD_FAB2_LIB.BASEBOARD_FAB2(SCH_1):PAGE212_I68@MSTR_DISCRETE.RES(CHIPS)':
 'A': CDS_PINID='A';
NODE_NAME     SH3P2 2
 '@BASEBOARD_FAB2_LIB.BASEBOARD_FAB2(SCH_1):PAGE212_I105@MSTR_MISC.SHUNT(CHIPS)':
 'B':NET_SHORT='VSENSE_PVCCIO_CPU0_SKT_VRTN:VSENSE_PVCCIO_CPU0_AVSN',
 CDS_PINID='B';
NET_NAME
'VSENSE_PVCCIO_CPU0_AVSP'
 '@BASEBOARD_FAB2_LIB.BASEBOARD_FAB2(SCH_1):VSENSE_PVCCIO_CPU0_AVSP':
 C_SIGNAL='@baseboard_fab2_lib.baseboard_fab2(sch_1):vsense_pvccio_cpu0_avsp';
NODE_NAME     R3N19 1
 '@BASEBOARD_FAB2_LIB.BASEBOARD_FAB2(SCH_1):PAGE211_I81@MSTR_DISCRETE.RES(CHIPS)':
 'A': CDS_PINID='A';
NODE_NAME     R3N21 1
 '@BASEBOARD_FAB2_LIB.BASEBOARD_FAB2(SCH_1):PAGE212_I74@MSTR_DISCRETE.RES(CHIPS)':
 'A': CDS_PINID='A';
NODE_NAME     SH3P1 2
 '@BASEBOARD_FAB2_LIB.BASEBOARD_FAB2(SCH_1):PAGE212_I104@MSTR_MISC.SHUNT(CHIPS)':
 'B':NET_SHORT='VSENSE_PVCCIO_CPU0_SKT_VSEN:VSENSE_PVCCIO_CPU0_AVSP',
 CDS_PINID='B';
NET_NAME
'VSENSE_PVCCIO_CPU0_SKT_VRTN'
 '@BASEBOARD_FAB2_LIB.BASEBOARD_FAB2(SCH_1):VSENSE_PVCCIO_CPU0_SKT_VRTN':
 C_SIGNAL='@baseboard_fab2_lib.baseboard_fab2(sch_1):vsense_pvccio_cpu0_skt_vrtn~
';
NODE_NAME     U5D1 BF5
 '@BASEBOARD_FAB2_LIB.BASEBOARD_FAB2(SCH_1):PAGE39_I127@CHPSET_LIB.SKX_EXT_B(CHIPS)':
 'VSS_VCCIO_SENSE': CDS_PINID='VSS_VCCIO_SENSE';
NODE_NAME     C3P1 2
 '@BASEBOARD_FAB2_LIB.BASEBOARD_FAB2(SCH_1):PAGE212_I60@DEV_DISCRETE.CAP_A(CHIPS)':
 'B': CDS_PINID='B';
NODE_NAME     SH3P2 1
 '@BASEBOARD_FAB2_LIB.BASEBOARD_FAB2(SCH_1):PAGE212_I105@MSTR_MISC.SHUNT(CHIPS)':
 'A':NET_SHORT='VSENSE_PVCCIO_CPU0_SKT_VRTN:VSENSE_PVCCIO_CPU0_AVSN',
 CDS_PINID='A';
NET_NAME
'VSENSE_PVCCIO_CPU0_SKT_VSEN'
 '@BASEBOARD_FAB2_LIB.BASEBOARD_FAB2(SCH_1):VSENSE_PVCCIO_CPU0_SKT_VSEN':
 C_SIGNAL='@baseboard_fab2_lib.baseboard_fab2(sch_1):vsense_pvccio_cpu0_skt_vsen~
';
NODE_NAME     U5D1 BH5
 '@BASEBOARD_FAB2_LIB.BASEBOARD_FAB2(SCH_1):PAGE39_I127@CHPSET_LIB.SKX_EXT_B(CHIPS)':
 'VCCIO_SENSE': CDS_PINID='VCCIO_SENSE';
NODE_NAME     C3P1 1
 '@BASEBOARD_FAB2_LIB.BASEBOARD_FAB2(SCH_1):PAGE212_I60@DEV_DISCRETE.CAP_A(CHIPS)':
 'A': CDS_PINID='A';
NODE_NAME     SH3P1 1
 '@BASEBOARD_FAB2_LIB.BASEBOARD_FAB2(SCH_1):PAGE212_I104@MSTR_MISC.SHUNT(CHIPS)':
 'A':NET_SHORT='VSENSE_PVCCIO_CPU0_SKT_VSEN:VSENSE_PVCCIO_CPU0_AVSP',
 CDS_PINID='A';
NET_NAME
'VSENSE_PVCCIO_CPU1_AVSN'
 '@BASEBOARD_FAB2_LIB.BASEBOARD_FAB2(SCH_1):VSENSE_PVCCIO_CPU1_AVSN':
 C_SIGNAL='@baseboard_fab2_lib.baseboard_fab2(sch_1):vsense_pvccio_cpu1_avsn';
NODE_NAME     C4D44 2
 '@BASEBOARD_FAB2_LIB.BASEBOARD_FAB2(SCH_1):PAGE213_I83@MSTR_DISCRETE.CAP(CHIPS)':
 'B': CDS_PINID='B';
NODE_NAME     EU4D5 20
 '@BASEBOARD_FAB2_LIB.BASEBOARD_FAB2(SCH_1):PAGE213_I96@MSTR_CONTROLLER.PXE1110B(CHIPS)':
 'AVREF': CDS_PINID='AVREF';
NODE_NAME     R3D28 1
 '@BASEBOARD_FAB2_LIB.BASEBOARD_FAB2(SCH_1):PAGE214_I101@MSTR_DISCRETE.RES(CHIPS)':
 'A': CDS_PINID='A';
NODE_NAME     SH3D1 2
 '@BASEBOARD_FAB2_LIB.BASEBOARD_FAB2(SCH_1):PAGE214_I130@MSTR_MISC.SHUNT(CHIPS)':
 'B':NET_SHORT='VSENSE_PVCCIO_CPU1_SKT_VRTN:VSENSE_PVCCIO_CPU1_AVSN',
 CDS_PINID='B';
NET_NAME
'VSENSE_PVCCIO_CPU1_AVSP'
 '@BASEBOARD_FAB2_LIB.BASEBOARD_FAB2(SCH_1):VSENSE_PVCCIO_CPU1_AVSP':
 C_SIGNAL='@baseboard_fab2_lib.baseboard_fab2(sch_1):vsense_pvccio_cpu1_avsp';
NODE_NAME     R4E7 1
 '@BASEBOARD_FAB2_LIB.BASEBOARD_FAB2(SCH_1):PAGE213_I84@MSTR_DISCRETE.RES(CHIPS)':
 'A': CDS_PINID='A';
NODE_NAME     R3E1 1
 '@BASEBOARD_FAB2_LIB.BASEBOARD_FAB2(SCH_1):PAGE214_I105@MSTR_DISCRETE.RES(CHIPS)':
 'A': CDS_PINID='A';
NODE_NAME     SH3D2 2
 '@BASEBOARD_FAB2_LIB.BASEBOARD_FAB2(SCH_1):PAGE214_I129@MSTR_MISC.SHUNT(CHIPS)':
 'B':NET_SHORT='VSENSE_PVCCIO_CPU1_SKT_VSEN:VSENSE_PVCCIO_CPU1_AVSP',
 CDS_PINID='B';
NET_NAME
'VSENSE_PVCCIO_CPU1_SKT_VRTN'
 '@BASEBOARD_FAB2_LIB.BASEBOARD_FAB2(SCH_1):VSENSE_PVCCIO_CPU1_SKT_VRTN':
 C_SIGNAL='@baseboard_fab2_lib.baseboard_fab2(sch_1):vsense_pvccio_cpu1_skt_vrtn~
';
NODE_NAME     U2D1 BF5
 '@BASEBOARD_FAB2_LIB.BASEBOARD_FAB2(SCH_1):PAGE73_I107@CHPSET_LIB.SKX_EXT_B(CHIPS)':
 'VSS_VCCIO_SENSE': CDS_PINID='VSS_VCCIO_SENSE';
NODE_NAME     C3D27 2
 '@BASEBOARD_FAB2_LIB.BASEBOARD_FAB2(SCH_1):PAGE214_I96@DEV_DISCRETE.CAP_A(CHIPS)':
 'B': CDS_PINID='B';
NODE_NAME     SH3D1 1
 '@BASEBOARD_FAB2_LIB.BASEBOARD_FAB2(SCH_1):PAGE214_I130@MSTR_MISC.SHUNT(CHIPS)':
 'A':NET_SHORT='VSENSE_PVCCIO_CPU1_SKT_VRTN:VSENSE_PVCCIO_CPU1_AVSN',
 CDS_PINID='A';
NET_NAME
'VSENSE_PVCCIO_CPU1_SKT_VSEN'
 '@BASEBOARD_FAB2_LIB.BASEBOARD_FAB2(SCH_1):VSENSE_PVCCIO_CPU1_SKT_VSEN':
 C_SIGNAL='@baseboard_fab2_lib.baseboard_fab2(sch_1):vsense_pvccio_cpu1_skt_vsen~
';
NODE_NAME     U2D1 BH5
 '@BASEBOARD_FAB2_LIB.BASEBOARD_FAB2(SCH_1):PAGE73_I107@CHPSET_LIB.SKX_EXT_B(CHIPS)':
 'VCCIO_SENSE': CDS_PINID='VCCIO_SENSE';
NODE_NAME     C3D27 1
 '@BASEBOARD_FAB2_LIB.BASEBOARD_FAB2(SCH_1):PAGE214_I96@DEV_DISCRETE.CAP_A(CHIPS)':
 'A': CDS_PINID='A';
NODE_NAME     SH3D2 1
 '@BASEBOARD_FAB2_LIB.BASEBOARD_FAB2(SCH_1):PAGE214_I129@MSTR_MISC.SHUNT(CHIPS)':
 'A':NET_SHORT='VSENSE_PVCCIO_CPU1_SKT_VSEN:VSENSE_PVCCIO_CPU1_AVSP',
 CDS_PINID='A';
NET_NAME
'VSENSE_PVCCMCP_CPU0_SKT_VRTN'
 '@BASEBOARD_FAB2_LIB.BASEBOARD_FAB2(SCH_1):VSENSE_PVCCMCP_CPU0_SKT_VRTN':
 C_SIGNAL='@baseboard_fab2_lib.baseboard_fab2(sch_1):vsense_pvccmcp_cpu0_skt_vrt~
n';
NODE_NAME     U5D1 BL16
 '@BASEBOARD_FAB2_LIB.BASEBOARD_FAB2(SCH_1):PAGE39_I127@CHPSET_LIB.SKX_EXT_B(CHIPS)':
 'CD_VSS_VCC_CORE_SENSE': CDS_PINID='CD_VSS_VCC_CORE_SENSE';
NODE_NAME     J6E1 B4
 '@BASEBOARD_FAB2_LIB.BASEBOARD_FAB2(SCH_1):PAGE194_I55@MSTR_SCONN.SCONN120_H61426002(CHIPS)':
 'IOB4': CDS_PINID='IOB4';
NET_NAME
'VSENSE_PVCCMCP_CPU0_SKT_VSEN'
 '@BASEBOARD_FAB2_LIB.BASEBOARD_FAB2(SCH_1):VSENSE_PVCCMCP_CPU0_SKT_VSEN':
 C_SIGNAL='@baseboard_fab2_lib.baseboard_fab2(sch_1):vsense_pvccmcp_cpu0_skt_vse~
n';
NODE_NAME     U5D1 BN16
 '@BASEBOARD_FAB2_LIB.BASEBOARD_FAB2(SCH_1):PAGE39_I127@CHPSET_LIB.SKX_EXT_B(CHIPS)':
 'CD_VCC_CORE_SENSE': CDS_PINID='CD_VCC_CORE_SENSE';
NODE_NAME     J6E1 A4
 '@BASEBOARD_FAB2_LIB.BASEBOARD_FAB2(SCH_1):PAGE194_I55@MSTR_SCONN.SCONN120_H61426002(CHIPS)':
 'IOA4': CDS_PINID='IOA4';
NET_NAME
'VSENSE_PVCCMCP_CPU1_SKT_VRTN'
 '@BASEBOARD_FAB2_LIB.BASEBOARD_FAB2(SCH_1):VSENSE_PVCCMCP_CPU1_SKT_VRTN':
 C_SIGNAL='@baseboard_fab2_lib.baseboard_fab2(sch_1):vsense_pvccmcp_cpu1_skt_vrt~
n';
NODE_NAME     U2D1 BL16
 '@BASEBOARD_FAB2_LIB.BASEBOARD_FAB2(SCH_1):PAGE73_I107@CHPSET_LIB.SKX_EXT_B(CHIPS)':
 'CD_VSS_VCC_CORE_SENSE': CDS_PINID='CD_VSS_VCC_CORE_SENSE';
NODE_NAME     J4E1 B4
 '@BASEBOARD_FAB2_LIB.BASEBOARD_FAB2(SCH_1):PAGE193_I45@MSTR_SCONN.SCONN120_H61426002(CHIPS)':
 'IOB4': CDS_PINID='IOB4';
NET_NAME
'VSENSE_PVCCMCP_CPU1_SKT_VSEN'
 '@BASEBOARD_FAB2_LIB.BASEBOARD_FAB2(SCH_1):VSENSE_PVCCMCP_CPU1_SKT_VSEN':
 C_SIGNAL='@baseboard_fab2_lib.baseboard_fab2(sch_1):vsense_pvccmcp_cpu1_skt_vse~
n';
NODE_NAME     U2D1 BN16
 '@BASEBOARD_FAB2_LIB.BASEBOARD_FAB2(SCH_1):PAGE73_I107@CHPSET_LIB.SKX_EXT_B(CHIPS)':
 'CD_VCC_CORE_SENSE': CDS_PINID='CD_VCC_CORE_SENSE';
NODE_NAME     J4E1 A4
 '@BASEBOARD_FAB2_LIB.BASEBOARD_FAB2(SCH_1):PAGE193_I45@MSTR_SCONN.SCONN120_H61426002(CHIPS)':
 'IOA4': CDS_PINID='IOA4';
NET_NAME
'VSENSE_PVDDQ_ABC_N'
 '@BASEBOARD_FAB2_LIB.BASEBOARD_FAB2(SCH_1):VSENSE_PVDDQ_ABC_N':
 C_SIGNAL='@baseboard_fab2_lib.baseboard_fab2(sch_1):vsense_pvddq_abc_n';
NODE_NAME     R4U6 2
 '@BASEBOARD_FAB2_LIB.BASEBOARD_FAB2(SCH_1):PAGE217_I74@MSTR_DISCRETE.RES(CHIPS)':
 'B': CDS_PINID='B';
NODE_NAME     SH4U1 1
 '@BASEBOARD_FAB2_LIB.BASEBOARD_FAB2(SCH_1):PAGE217_I259@MSTR_MISC.SHUNT(CHIPS)':
 'A':NET_SHORT='VSENSE_PVDDQ_ABC_N:GND',
 CDS_PINID='A';
NODE_NAME     C7G4 2
 '@BASEBOARD_FAB2_LIB.BASEBOARD_FAB2(SCH_1):PAGE215_I14@MSTR_DISCRETE.CAP(CHIPS)':
 'B': CDS_PINID='B';
NODE_NAME     EU7G1 20
 '@BASEBOARD_FAB2_LIB.BASEBOARD_FAB2(SCH_1):PAGE215_I69@MSTR_CONTROLLER.PXM1310B(CHIPS)':
 'AVREF': CDS_PINID='AVREF';
NET_NAME
'VSENSE_PVDDQ_ABC_P'
 '@BASEBOARD_FAB2_LIB.BASEBOARD_FAB2(SCH_1):VSENSE_PVDDQ_ABC_P':
 C_SIGNAL='@baseboard_fab2_lib.baseboard_fab2(sch_1):vsense_pvddq_abc_p';
NODE_NAME     R4U6 1
 '@BASEBOARD_FAB2_LIB.BASEBOARD_FAB2(SCH_1):PAGE217_I74@MSTR_DISCRETE.RES(CHIPS)':
 'A': CDS_PINID='A';
NODE_NAME     SH4U2 1
 '@BASEBOARD_FAB2_LIB.BASEBOARD_FAB2(SCH_1):PAGE217_I260@MSTR_MISC.SHUNT(CHIPS)':
 'A':NET_SHORT='VSENSE_PVDDQ_ABC_P:PVDDQ_ABC',
 CDS_PINID='A';
NODE_NAME     R7G9 1
 '@BASEBOARD_FAB2_LIB.BASEBOARD_FAB2(SCH_1):PAGE215_I12@MSTR_DISCRETE.RES(CHIPS)':
 'A': CDS_PINID='A';
NET_NAME
'VSENSE_PVDDQ_ABC_VTT'
 '@BASEBOARD_FAB2_LIB.BASEBOARD_FAB2(SCH_1):VSENSE_PVDDQ_ABC_VTT':
 C_SIGNAL='@baseboard_fab2_lib.baseboard_fab2(sch_1):vsense_pvddq_abc_vtt';
NODE_NAME     R6U5 2
 '@BASEBOARD_FAB2_LIB.BASEBOARD_FAB2(SCH_1):PAGE221_I6@MSTR_DISCRETE.RES(CHIPS)':
 'B': CDS_PINID='B';
NODE_NAME     C6U12 1
 '@BASEBOARD_FAB2_LIB.BASEBOARD_FAB2(SCH_1):PAGE221_I11@MSTR_DISCRETE.CAP(CHIPS)':
 'A': CDS_PINID='A';
NODE_NAME     EU4G3 4
 '@BASEBOARD_FAB2_LIB.BASEBOARD_FAB2(SCH_1):PAGE221_I15@MSTR_VREG.MIC5166(CHIPS)':
 'VDDQ': CDS_PINID='VDDQ';
NET_NAME
'VSENSE_PVDDQ_DEF_N'
 '@BASEBOARD_FAB2_LIB.BASEBOARD_FAB2(SCH_1):VSENSE_PVDDQ_DEF_N':
 C_SIGNAL='@baseboard_fab2_lib.baseboard_fab2(sch_1):vsense_pvddq_def_n';
NODE_NAME     R4L2 2
 '@BASEBOARD_FAB2_LIB.BASEBOARD_FAB2(SCH_1):PAGE220_I74@MSTR_DISCRETE.RES(CHIPS)':
 'B': CDS_PINID='B';
NODE_NAME     SH4L1 1
 '@BASEBOARD_FAB2_LIB.BASEBOARD_FAB2(SCH_1):PAGE220_I240@MSTR_MISC.SHUNT(CHIPS)':
 'A':NET_SHORT='VSENSE_PVDDQ_DEF_N:GND',
 CDS_PINID='A';
NODE_NAME     EU7A5 20
 '@BASEBOARD_FAB2_LIB.BASEBOARD_FAB2(SCH_1):PAGE218_I69@MSTR_CONTROLLER.PXM1310B(CHIPS)':
 'AVREF': CDS_PINID='AVREF';
NODE_NAME     C7A28 2
 '@BASEBOARD_FAB2_LIB.BASEBOARD_FAB2(SCH_1):PAGE218_I14@MSTR_DISCRETE.CAP(CHIPS)':
 'B': CDS_PINID='B';
NET_NAME
'VSENSE_PVDDQ_DEF_P'
 '@BASEBOARD_FAB2_LIB.BASEBOARD_FAB2(SCH_1):VSENSE_PVDDQ_DEF_P':
 C_SIGNAL='@baseboard_fab2_lib.baseboard_fab2(sch_1):vsense_pvddq_def_p';
NODE_NAME     R4L2 1
 '@BASEBOARD_FAB2_LIB.BASEBOARD_FAB2(SCH_1):PAGE220_I74@MSTR_DISCRETE.RES(CHIPS)':
 'A': CDS_PINID='A';
NODE_NAME     SH4L2 1
 '@BASEBOARD_FAB2_LIB.BASEBOARD_FAB2(SCH_1):PAGE220_I239@MSTR_MISC.SHUNT(CHIPS)':
 'A':NET_SHORT='VSENSE_PVDDQ_DEF_P:PVDDQ_DEF',
 CDS_PINID='A';
NODE_NAME     R7A7 1
 '@BASEBOARD_FAB2_LIB.BASEBOARD_FAB2(SCH_1):PAGE218_I13@MSTR_DISCRETE.RES(CHIPS)':
 'A': CDS_PINID='A';
NET_NAME
'VSENSE_PVDDQ_DEF_VTT'
 '@BASEBOARD_FAB2_LIB.BASEBOARD_FAB2(SCH_1):VSENSE_PVDDQ_DEF_VTT':
 C_SIGNAL='@baseboard_fab2_lib.baseboard_fab2(sch_1):vsense_pvddq_def_vtt';
NODE_NAME     R6L10 2
 '@BASEBOARD_FAB2_LIB.BASEBOARD_FAB2(SCH_1):PAGE222_I6@MSTR_DISCRETE.RES(CHIPS)':
 'B': CDS_PINID='B';
NODE_NAME     C4A11 1
 '@BASEBOARD_FAB2_LIB.BASEBOARD_FAB2(SCH_1):PAGE222_I9@MSTR_DISCRETE.CAP(CHIPS)':
 'A': CDS_PINID='A';
NODE_NAME     EU4A1 4
 '@BASEBOARD_FAB2_LIB.BASEBOARD_FAB2(SCH_1):PAGE222_I13@MSTR_VREG.MIC5166(CHIPS)':
 'VDDQ': CDS_PINID='VDDQ';
NET_NAME
'VSENSE_PVDDQ_GHJ_N'
 '@BASEBOARD_FAB2_LIB.BASEBOARD_FAB2(SCH_1):VSENSE_PVDDQ_GHJ_N':
 C_SIGNAL='@baseboard_fab2_lib.baseboard_fab2(sch_1):vsense_pvddq_ghj_n';
NODE_NAME     R7U2 2
 '@BASEBOARD_FAB2_LIB.BASEBOARD_FAB2(SCH_1):PAGE225_I74@MSTR_DISCRETE.RES(CHIPS)':
 'B': CDS_PINID='B';
NODE_NAME     SH7U2 1
 '@BASEBOARD_FAB2_LIB.BASEBOARD_FAB2(SCH_1):PAGE225_I244@MSTR_MISC.SHUNT(CHIPS)':
 'A':NET_SHORT='VSENSE_PVDDQ_GHJ_N:GND',
 CDS_PINID='A';
NODE_NAME     C1G16 2
 '@BASEBOARD_FAB2_LIB.BASEBOARD_FAB2(SCH_1):PAGE223_I12@MSTR_DISCRETE.CAP(CHIPS)':
 'B': CDS_PINID='B';
NODE_NAME     EU1G2 20
 '@BASEBOARD_FAB2_LIB.BASEBOARD_FAB2(SCH_1):PAGE223_I69@MSTR_CONTROLLER.PXM1310B(CHIPS)':
 'AVREF': CDS_PINID='AVREF';
NET_NAME
'VSENSE_PVDDQ_GHJ_P'
 '@BASEBOARD_FAB2_LIB.BASEBOARD_FAB2(SCH_1):VSENSE_PVDDQ_GHJ_P':
 C_SIGNAL='@baseboard_fab2_lib.baseboard_fab2(sch_1):vsense_pvddq_ghj_p';
NODE_NAME     R7U2 1
 '@BASEBOARD_FAB2_LIB.BASEBOARD_FAB2(SCH_1):PAGE225_I74@MSTR_DISCRETE.RES(CHIPS)':
 'A': CDS_PINID='A';
NODE_NAME     SH7U1 1
 '@BASEBOARD_FAB2_LIB.BASEBOARD_FAB2(SCH_1):PAGE225_I243@MSTR_MISC.SHUNT(CHIPS)':
 'A':NET_SHORT='VSENSE_PVDDQ_GHJ_P:PVDDQ_GHJ',
 CDS_PINID='A';
NODE_NAME     R1G5 1
 '@BASEBOARD_FAB2_LIB.BASEBOARD_FAB2(SCH_1):PAGE223_I13@MSTR_DISCRETE.RES(CHIPS)':
 'A': CDS_PINID='A';
NET_NAME
'VSENSE_PVDDQ_GHJ_VTT'
 '@BASEBOARD_FAB2_LIB.BASEBOARD_FAB2(SCH_1):VSENSE_PVDDQ_GHJ_VTT':
 C_SIGNAL='@baseboard_fab2_lib.baseboard_fab2(sch_1):vsense_pvddq_ghj_vtt';
NODE_NAME     R6U6 2
 '@BASEBOARD_FAB2_LIB.BASEBOARD_FAB2(SCH_1):PAGE229_I6@MSTR_DISCRETE.RES(CHIPS)':
 'B': CDS_PINID='B';
NODE_NAME     EU4G2 4
 '@BASEBOARD_FAB2_LIB.BASEBOARD_FAB2(SCH_1):PAGE229_I37@MSTR_VREG.MIC5166(CHIPS)':
 'VDDQ': CDS_PINID='VDDQ';
NODE_NAME     C6U11 1
 '@BASEBOARD_FAB2_LIB.BASEBOARD_FAB2(SCH_1):PAGE229_I14@MSTR_DISCRETE.CAP(CHIPS)':
 'A': CDS_PINID='A';
NET_NAME
'VSENSE_PVDDQ_KLM_N'
 '@BASEBOARD_FAB2_LIB.BASEBOARD_FAB2(SCH_1):VSENSE_PVDDQ_KLM_N':
 C_SIGNAL='@baseboard_fab2_lib.baseboard_fab2(sch_1):vsense_pvddq_klm_n';
NODE_NAME     R7L2 2
 '@BASEBOARD_FAB2_LIB.BASEBOARD_FAB2(SCH_1):PAGE228_I74@MSTR_DISCRETE.RES(CHIPS)':
 'B': CDS_PINID='B';
NODE_NAME     SH7L1 1
 '@BASEBOARD_FAB2_LIB.BASEBOARD_FAB2(SCH_1):PAGE228_I246@MSTR_MISC.SHUNT(CHIPS)':
 'A':NET_SHORT='VSENSE_PVDDQ_KLM_N:GND',
 CDS_PINID='A';
NODE_NAME     C1B12 2
 '@BASEBOARD_FAB2_LIB.BASEBOARD_FAB2(SCH_1):PAGE226_I12@MSTR_DISCRETE.CAP(CHIPS)':
 'B': CDS_PINID='B';
NODE_NAME     EU1B1 20
 '@BASEBOARD_FAB2_LIB.BASEBOARD_FAB2(SCH_1):PAGE226_I69@MSTR_CONTROLLER.PXM1310B(CHIPS)':
 'AVREF': CDS_PINID='AVREF';
NET_NAME
'VSENSE_PVDDQ_KLM_P'
 '@BASEBOARD_FAB2_LIB.BASEBOARD_FAB2(SCH_1):VSENSE_PVDDQ_KLM_P':
 C_SIGNAL='@baseboard_fab2_lib.baseboard_fab2(sch_1):vsense_pvddq_klm_p';
NODE_NAME     R7L2 1
 '@BASEBOARD_FAB2_LIB.BASEBOARD_FAB2(SCH_1):PAGE228_I74@MSTR_DISCRETE.RES(CHIPS)':
 'A': CDS_PINID='A';
NODE_NAME     SH7L2 1
 '@BASEBOARD_FAB2_LIB.BASEBOARD_FAB2(SCH_1):PAGE228_I245@MSTR_MISC.SHUNT(CHIPS)':
 'A':NET_SHORT='VSENSE_PVDDQ_KLM_P:PVDDQ_KLM',
 CDS_PINID='A';
NODE_NAME     R1B16 1
 '@BASEBOARD_FAB2_LIB.BASEBOARD_FAB2(SCH_1):PAGE226_I13@MSTR_DISCRETE.RES(CHIPS)':
 'A': CDS_PINID='A';
NET_NAME
'VSENSE_PVDDQ_KLM_VTT'
 '@BASEBOARD_FAB2_LIB.BASEBOARD_FAB2(SCH_1):VSENSE_PVDDQ_KLM_VTT':
 C_SIGNAL='@baseboard_fab2_lib.baseboard_fab2(sch_1):vsense_pvddq_klm_vtt';
NODE_NAME     R6L6 2
 '@BASEBOARD_FAB2_LIB.BASEBOARD_FAB2(SCH_1):PAGE230_I6@MSTR_DISCRETE.RES(CHIPS)':
 'B': CDS_PINID='B';
NODE_NAME     C4A7 1
 '@BASEBOARD_FAB2_LIB.BASEBOARD_FAB2(SCH_1):PAGE230_I10@MSTR_DISCRETE.CAP(CHIPS)':
 'A': CDS_PINID='A';
NODE_NAME     EU4A2 4
 '@BASEBOARD_FAB2_LIB.BASEBOARD_FAB2(SCH_1):PAGE230_I37@MSTR_VREG.MIC5166(CHIPS)':
 'VDDQ': CDS_PINID='VDDQ';
NET_NAME
'VSENSE_PVNN_PCH_STBY_AVSN'
 '@BASEBOARD_FAB2_LIB.BASEBOARD_FAB2(SCH_1):VSENSE_PVNN_PCH_STBY_AVSN':
 C_SIGNAL='@baseboard_fab2_lib.baseboard_fab2(sch_1):vsense_pvnn_pch_stby_avsn';
NODE_NAME     C8A2 2
 '@BASEBOARD_FAB2_LIB.BASEBOARD_FAB2(SCH_1):PAGE235_I209@MSTR_DISCRETE.CAP(CHIPS)':
 'B': CDS_PINID='B';
NODE_NAME     EU8A1 20
 '@BASEBOARD_FAB2_LIB.BASEBOARD_FAB2(SCH_1):PAGE235_I229@MSTR_CONTROLLER.PXE1110B(CHIPS)':
 'AVREF': CDS_PINID='AVREF';
NODE_NAME     R7A18 2
 '@BASEBOARD_FAB2_LIB.BASEBOARD_FAB2(SCH_1):PAGE236_I92@MSTR_DISCRETE.RES(CHIPS)':
 'B': CDS_PINID='B';
NET_NAME
'VSENSE_PVNN_PCH_STBY_AVSP'
 '@BASEBOARD_FAB2_LIB.BASEBOARD_FAB2(SCH_1):VSENSE_PVNN_PCH_STBY_AVSP':
 C_SIGNAL='@baseboard_fab2_lib.baseboard_fab2(sch_1):vsense_pvnn_pch_stby_avsp';
NODE_NAME     R8A1 1
 '@BASEBOARD_FAB2_LIB.BASEBOARD_FAB2(SCH_1):PAGE235_I210@MSTR_DISCRETE.RES(CHIPS)':
 'A': CDS_PINID='A';
NODE_NAME     R7A13 1
 '@BASEBOARD_FAB2_LIB.BASEBOARD_FAB2(SCH_1):PAGE236_I90@MSTR_DISCRETE.RES(CHIPS)':
 'A': CDS_PINID='A';
NODE_NAME     R7A19 2
 '@BASEBOARD_FAB2_LIB.BASEBOARD_FAB2(SCH_1):PAGE236_I93@MSTR_DISCRETE.RES(CHIPS)':
 'B': CDS_PINID='B';
NODE_NAME     R7A14 2
 '@BASEBOARD_FAB2_LIB.BASEBOARD_FAB2(SCH_1):PAGE236_I94@MSTR_DISCRETE.RES(CHIPS)':
 'B': CDS_PINID='B';
NET_NAME
'VSENSE_PVNN_PCH_STBY_FPK'
 '@BASEBOARD_FAB2_LIB.BASEBOARD_FAB2(SCH_1):VSENSE_PVNN_PCH_STBY_FPK':
 C_SIGNAL='@baseboard_fab2_lib.baseboard_fab2(sch_1):vsense_pvnn_pch_stby_fpk';
NODE_NAME     U7C1 AK36
 '@BASEBOARD_FAB2_LIB.BASEBOARD_FAB2(SCH_1):PAGE123_I21@MSTR_U_PROC.LBG_CORE_QAT_EXT_D(CHIPS)':
 'VCCPRIM_AVID_SENSE': CDS_PINID='VCCPRIM_AVID_SENSE';
NODE_NAME     R7A14 1
 '@BASEBOARD_FAB2_LIB.BASEBOARD_FAB2(SCH_1):PAGE236_I94@MSTR_DISCRETE.RES(CHIPS)':
 'A': CDS_PINID='A';
NET_NAME
'VSENSE_PVNN_PCH_STBY_QAT'
 '@BASEBOARD_FAB2_LIB.BASEBOARD_FAB2(SCH_1):VSENSE_PVNN_PCH_STBY_QAT':
 C_SIGNAL='@baseboard_fab2_lib.baseboard_fab2(sch_1):vsense_pvnn_pch_stby_qat';
NODE_NAME     U7C1 V37
 '@BASEBOARD_FAB2_LIB.BASEBOARD_FAB2(SCH_1):PAGE123_I21@MSTR_U_PROC.LBG_CORE_QAT_EXT_D(CHIPS)':
 'VCCPRIM_AVID_QAT_SENSE': CDS_PINID='VCCPRIM_AVID_QAT_SENSE';
NODE_NAME     R7A19 1
 '@BASEBOARD_FAB2_LIB.BASEBOARD_FAB2(SCH_1):PAGE236_I93@MSTR_DISCRETE.RES(CHIPS)':
 'A': CDS_PINID='A';
NET_NAME
'VSENSE_PVPP_ABC'
 '@BASEBOARD_FAB2_LIB.BASEBOARD_FAB2(SCH_1):VSENSE_PVPP_ABC':
 C_SIGNAL='@baseboard_fab2_lib.baseboard_fab2(sch_1):vsense_pvpp_abc';
NODE_NAME     R7F13 1
 '@BASEBOARD_FAB2_LIB.BASEBOARD_FAB2(SCH_1):PAGE231_I167@MSTR_DISCRETE.RES(CHIPS)':
 'A': CDS_PINID='A';
NODE_NAME     R7F12 2
 '@BASEBOARD_FAB2_LIB.BASEBOARD_FAB2(SCH_1):PAGE231_I168@MSTR_DISCRETE.RES(CHIPS)':
 'B': CDS_PINID='B';
NODE_NAME     R7F17 1
 '@BASEBOARD_FAB2_LIB.BASEBOARD_FAB2(SCH_1):PAGE231_I218@MSTR_DISCRETE.RES(CHIPS)':
 'A': CDS_PINID='A';
NET_NAME
'VSENSE_PVPP_DEF'
 '@BASEBOARD_FAB2_LIB.BASEBOARD_FAB2(SCH_1):VSENSE_PVPP_DEF':
 C_SIGNAL='@baseboard_fab2_lib.baseboard_fab2(sch_1):vsense_pvpp_def';
NODE_NAME     R7B18 1
 '@BASEBOARD_FAB2_LIB.BASEBOARD_FAB2(SCH_1):PAGE232_I298@MSTR_DISCRETE.RES(CHIPS)':
 'A': CDS_PINID='A';
NODE_NAME     R7B11 2
 '@BASEBOARD_FAB2_LIB.BASEBOARD_FAB2(SCH_1):PAGE232_I299@MSTR_DISCRETE.RES(CHIPS)':
 'B': CDS_PINID='B';
NODE_NAME     R7B15 1
 '@BASEBOARD_FAB2_LIB.BASEBOARD_FAB2(SCH_1):PAGE232_I303@MSTR_DISCRETE.RES(CHIPS)':
 'A': CDS_PINID='A';
NET_NAME
'VSENSE_PVPP_GHJ'
 '@BASEBOARD_FAB2_LIB.BASEBOARD_FAB2(SCH_1):VSENSE_PVPP_GHJ':
 C_SIGNAL='@baseboard_fab2_lib.baseboard_fab2(sch_1):vsense_pvpp_ghj';
NODE_NAME     R4G10 1
 '@BASEBOARD_FAB2_LIB.BASEBOARD_FAB2(SCH_1):PAGE233_I266@MSTR_DISCRETE.RES(CHIPS)':
 'A': CDS_PINID='A';
NODE_NAME     R4G7 1
 '@BASEBOARD_FAB2_LIB.BASEBOARD_FAB2(SCH_1):PAGE233_I270@MSTR_DISCRETE.RES(CHIPS)':
 'A': CDS_PINID='A';
NODE_NAME     R4G8 2
 '@BASEBOARD_FAB2_LIB.BASEBOARD_FAB2(SCH_1):PAGE233_I271@MSTR_DISCRETE.RES(CHIPS)':
 'B': CDS_PINID='B';
NET_NAME
'VSENSE_PVPP_KLM'
 '@BASEBOARD_FAB2_LIB.BASEBOARD_FAB2(SCH_1):VSENSE_PVPP_KLM':
 C_SIGNAL='@baseboard_fab2_lib.baseboard_fab2(sch_1):vsense_pvpp_klm';
NODE_NAME     R4B3 2
 '@BASEBOARD_FAB2_LIB.BASEBOARD_FAB2(SCH_1):PAGE234_I214@MSTR_DISCRETE.RES(CHIPS)':
 'B': CDS_PINID='B';
NODE_NAME     R4B5 1
 '@BASEBOARD_FAB2_LIB.BASEBOARD_FAB2(SCH_1):PAGE234_I215@MSTR_DISCRETE.RES(CHIPS)':
 'A': CDS_PINID='A';
NODE_NAME     R4B9 1
 '@BASEBOARD_FAB2_LIB.BASEBOARD_FAB2(SCH_1):PAGE234_I219@MSTR_DISCRETE.RES(CHIPS)':
 'A': CDS_PINID='A';
NET_NAME
'VSENSE_PVSA_CPU0_BVSP'
 '@BASEBOARD_FAB2_LIB.BASEBOARD_FAB2(SCH_1):VSENSE_PVSA_CPU0_BVSP':
 C_SIGNAL='@baseboard_fab2_lib.baseboard_fab2(sch_1):vsense_pvsa_cpu0_bvsp';
NODE_NAME     C4D29 1
 '@BASEBOARD_FAB2_LIB.BASEBOARD_FAB2(SCH_1):PAGE201_I64@MSTR_DISCRETE.CAP(CHIPS)':
 'A': CDS_PINID='A';
NODE_NAME     R4D39 2
 '@BASEBOARD_FAB2_LIB.BASEBOARD_FAB2(SCH_1):PAGE201_I110@MSTR_DISCRETE.RES(CHIPS)':
 'B': CDS_PINID='B';
NODE_NAME     EU4D4 35
 '@BASEBOARD_FAB2_LIB.BASEBOARD_FAB2(SCH_1):PAGE201_I155@MSTR_CONTROLLER.PXE1610B(CHIPS)':
 'BVSEN': CDS_PINID='BVSEN';
NET_NAME
'VSENSE_PVSA_CPU0_N'
 '@BASEBOARD_FAB2_LIB.BASEBOARD_FAB2(SCH_1):VSENSE_PVSA_CPU0_N':
 C_SIGNAL='@baseboard_fab2_lib.baseboard_fab2(sch_1):vsense_pvsa_cpu0_n';
NODE_NAME     C4D29 2
 '@BASEBOARD_FAB2_LIB.BASEBOARD_FAB2(SCH_1):PAGE201_I64@MSTR_DISCRETE.CAP(CHIPS)':
 'B': CDS_PINID='B';
NODE_NAME     EU4D4 36
 '@BASEBOARD_FAB2_LIB.BASEBOARD_FAB2(SCH_1):PAGE201_I155@MSTR_CONTROLLER.PXE1610B(CHIPS)':
 'BVREF': CDS_PINID='BVREF';
NODE_NAME     R4C1 1
 '@BASEBOARD_FAB2_LIB.BASEBOARD_FAB2(SCH_1):PAGE205_I29@MSTR_DISCRETE.RES(CHIPS)':
 'A': CDS_PINID='A';
NODE_NAME     R4C2 1
 '@BASEBOARD_FAB2_LIB.BASEBOARD_FAB2(SCH_1):PAGE205_I30@MSTR_DISCRETE.RES(CHIPS)':
 'A': CDS_PINID='A';
NODE_NAME     R4C3 2
 '@BASEBOARD_FAB2_LIB.BASEBOARD_FAB2(SCH_1):PAGE205_I37@MSTR_DISCRETE.RES(CHIPS)':
 'B': CDS_PINID='B';
NET_NAME
'VSENSE_PVSA_CPU0_P'
 '@BASEBOARD_FAB2_LIB.BASEBOARD_FAB2(SCH_1):VSENSE_PVSA_CPU0_P':
 C_SIGNAL='@baseboard_fab2_lib.baseboard_fab2(sch_1):vsense_pvsa_cpu0_p';
NODE_NAME     R4D39 1
 '@BASEBOARD_FAB2_LIB.BASEBOARD_FAB2(SCH_1):PAGE201_I110@MSTR_DISCRETE.RES(CHIPS)':
 'A': CDS_PINID='A';
NODE_NAME     R4C5 1
 '@BASEBOARD_FAB2_LIB.BASEBOARD_FAB2(SCH_1):PAGE205_I24@MSTR_DISCRETE.RES(CHIPS)':
 'A': CDS_PINID='A';
NODE_NAME     R4C4 1
 '@BASEBOARD_FAB2_LIB.BASEBOARD_FAB2(SCH_1):PAGE205_I26@MSTR_DISCRETE.RES(CHIPS)':
 'A': CDS_PINID='A';
NODE_NAME     R4C3 1
 '@BASEBOARD_FAB2_LIB.BASEBOARD_FAB2(SCH_1):PAGE205_I37@MSTR_DISCRETE.RES(CHIPS)':
 'A': CDS_PINID='A';
NET_NAME
'VSENSE_PVSA_CPU0_SKT_VRTN'
 '@BASEBOARD_FAB2_LIB.BASEBOARD_FAB2(SCH_1):VSENSE_PVSA_CPU0_SKT_VRTN':
 C_SIGNAL='@baseboard_fab2_lib.baseboard_fab2(sch_1):vsense_pvsa_cpu0_skt_vrtn';
NODE_NAME     U5D1 CG76
 '@BASEBOARD_FAB2_LIB.BASEBOARD_FAB2(SCH_1):PAGE39_I127@CHPSET_LIB.SKX_EXT_B(CHIPS)':
 'VSS_VCCSA_SENSE': CDS_PINID='VSS_VCCSA_SENSE';
NODE_NAME     R4C2 2
 '@BASEBOARD_FAB2_LIB.BASEBOARD_FAB2(SCH_1):PAGE205_I30@MSTR_DISCRETE.RES(CHIPS)':
 'B': CDS_PINID='B';
NET_NAME
'VSENSE_PVSA_CPU0_SKT_VSEN'
 '@BASEBOARD_FAB2_LIB.BASEBOARD_FAB2(SCH_1):VSENSE_PVSA_CPU0_SKT_VSEN':
 C_SIGNAL='@baseboard_fab2_lib.baseboard_fab2(sch_1):vsense_pvsa_cpu0_skt_vsen';
NODE_NAME     U5D1 CE76
 '@BASEBOARD_FAB2_LIB.BASEBOARD_FAB2(SCH_1):PAGE39_I127@CHPSET_LIB.SKX_EXT_B(CHIPS)':
 'VCCSA_SENSE': CDS_PINID='VCCSA_SENSE';
NODE_NAME     R4C4 2
 '@BASEBOARD_FAB2_LIB.BASEBOARD_FAB2(SCH_1):PAGE205_I26@MSTR_DISCRETE.RES(CHIPS)':
 'B': CDS_PINID='B';
NET_NAME
'VSENSE_PVSA_CPU1_BVSP'
 '@BASEBOARD_FAB2_LIB.BASEBOARD_FAB2(SCH_1):VSENSE_PVSA_CPU1_BVSP':
 C_SIGNAL='@baseboard_fab2_lib.baseboard_fab2(sch_1):vsense_pvsa_cpu1_bvsp';
NODE_NAME     C1C16 1
 '@BASEBOARD_FAB2_LIB.BASEBOARD_FAB2(SCH_1):PAGE206_I68@MSTR_DISCRETE.CAP(CHIPS)':
 'A': CDS_PINID='A';
NODE_NAME     R1C21 2
 '@BASEBOARD_FAB2_LIB.BASEBOARD_FAB2(SCH_1):PAGE206_I77@MSTR_DISCRETE.RES(CHIPS)':
 'B': CDS_PINID='B';
NODE_NAME     EU1C2 35
 '@BASEBOARD_FAB2_LIB.BASEBOARD_FAB2(SCH_1):PAGE206_I130@MSTR_CONTROLLER.PXE1610B(CHIPS)':
 'BVSEN': CDS_PINID='BVSEN';
NET_NAME
'VSENSE_PVSA_CPU1_N'
 '@BASEBOARD_FAB2_LIB.BASEBOARD_FAB2(SCH_1):VSENSE_PVSA_CPU1_N':
 C_SIGNAL='@baseboard_fab2_lib.baseboard_fab2(sch_1):vsense_pvsa_cpu1_n';
NODE_NAME     C1C16 2
 '@BASEBOARD_FAB2_LIB.BASEBOARD_FAB2(SCH_1):PAGE206_I68@MSTR_DISCRETE.CAP(CHIPS)':
 'B': CDS_PINID='B';
NODE_NAME     EU1C2 36
 '@BASEBOARD_FAB2_LIB.BASEBOARD_FAB2(SCH_1):PAGE206_I130@MSTR_CONTROLLER.PXE1610B(CHIPS)':
 'BVREF': CDS_PINID='BVREF';
NODE_NAME     R1C5 1
 '@BASEBOARD_FAB2_LIB.BASEBOARD_FAB2(SCH_1):PAGE210_I32@MSTR_DISCRETE.RES(CHIPS)':
 'A': CDS_PINID='A';
NODE_NAME     R1C4 1
 '@BASEBOARD_FAB2_LIB.BASEBOARD_FAB2(SCH_1):PAGE210_I33@MSTR_DISCRETE.RES(CHIPS)':
 'A': CDS_PINID='A';
NODE_NAME     R1C6 2
 '@BASEBOARD_FAB2_LIB.BASEBOARD_FAB2(SCH_1):PAGE210_I34@MSTR_DISCRETE.RES(CHIPS)':
 'B': CDS_PINID='B';
NET_NAME
'VSENSE_PVSA_CPU1_P'
 '@BASEBOARD_FAB2_LIB.BASEBOARD_FAB2(SCH_1):VSENSE_PVSA_CPU1_P':
 C_SIGNAL='@baseboard_fab2_lib.baseboard_fab2(sch_1):vsense_pvsa_cpu1_p';
NODE_NAME     R1C21 1
 '@BASEBOARD_FAB2_LIB.BASEBOARD_FAB2(SCH_1):PAGE206_I77@MSTR_DISCRETE.RES(CHIPS)':
 'A': CDS_PINID='A';
NODE_NAME     R1C12 1
 '@BASEBOARD_FAB2_LIB.BASEBOARD_FAB2(SCH_1):PAGE210_I29@MSTR_DISCRETE.RES(CHIPS)':
 'A': CDS_PINID='A';
NODE_NAME     R1C7 1
 '@BASEBOARD_FAB2_LIB.BASEBOARD_FAB2(SCH_1):PAGE210_I31@MSTR_DISCRETE.RES(CHIPS)':
 'A': CDS_PINID='A';
NODE_NAME     R1C6 1
 '@BASEBOARD_FAB2_LIB.BASEBOARD_FAB2(SCH_1):PAGE210_I34@MSTR_DISCRETE.RES(CHIPS)':
 'A': CDS_PINID='A';
NET_NAME
'VSENSE_PVSA_CPU1_SKT_VRTN'
 '@BASEBOARD_FAB2_LIB.BASEBOARD_FAB2(SCH_1):VSENSE_PVSA_CPU1_SKT_VRTN':
 C_SIGNAL='@baseboard_fab2_lib.baseboard_fab2(sch_1):vsense_pvsa_cpu1_skt_vrtn';
NODE_NAME     U2D1 CG76
 '@BASEBOARD_FAB2_LIB.BASEBOARD_FAB2(SCH_1):PAGE73_I107@CHPSET_LIB.SKX_EXT_B(CHIPS)':
 'VSS_VCCSA_SENSE': CDS_PINID='VSS_VCCSA_SENSE';
NODE_NAME     R1C5 2
 '@BASEBOARD_FAB2_LIB.BASEBOARD_FAB2(SCH_1):PAGE210_I32@MSTR_DISCRETE.RES(CHIPS)':
 'B': CDS_PINID='B';
NET_NAME
'VSENSE_PVSA_CPU1_SKT_VSEN'
 '@BASEBOARD_FAB2_LIB.BASEBOARD_FAB2(SCH_1):VSENSE_PVSA_CPU1_SKT_VSEN':
 C_SIGNAL='@baseboard_fab2_lib.baseboard_fab2(sch_1):vsense_pvsa_cpu1_skt_vsen';
NODE_NAME     U2D1 CE76
 '@BASEBOARD_FAB2_LIB.BASEBOARD_FAB2(SCH_1):PAGE73_I107@CHPSET_LIB.SKX_EXT_B(CHIPS)':
 'VCCSA_SENSE': CDS_PINID='VCCSA_SENSE';
NODE_NAME     R1C7 2
 '@BASEBOARD_FAB2_LIB.BASEBOARD_FAB2(SCH_1):PAGE210_I31@MSTR_DISCRETE.RES(CHIPS)':
 'B': CDS_PINID='B';
NET_NAME
'VSENSE_RGND_P3V3_STBY'
 '@BASEBOARD_FAB2_LIB.BASEBOARD_FAB2(SCH_1):VSENSE_RGND_P3V3_STBY':
 C_SIGNAL='@baseboard_fab2_lib.baseboard_fab2(sch_1):vsense_rgnd_p3v3_stby';
NODE_NAME     EU8F1 7
 '@BASEBOARD_FAB2_LIB.BASEBOARD_FAB2(SCH_1):PAGE240_I125@MSTR_VREG.RT8240(CHIPS)':
 'RGND': CDS_PINID='RGND';
NODE_NAME     R8E38 1
 '@BASEBOARD_FAB2_LIB.BASEBOARD_FAB2(SCH_1):PAGE240_I140@MSTR_DISCRETE.RES(CHIPS)':
 'A': CDS_PINID='A';
NET_NAME
'VSENSE_VCCINR2PMAX_CPU0'
 '@BASEBOARD_FAB2_LIB.BASEBOARD_FAB2(SCH_1):VSENSE_VCCINR2PMAX_CPU0':
 C_SIGNAL='@baseboard_fab2_lib.baseboard_fab2(sch_1):vsense_vccinr2pmax_cpu0';
NODE_NAME     R5P1 2
 '@BASEBOARD_FAB2_LIB.BASEBOARD_FAB2(SCH_1):PAGE37_I309@MSTR_DISCRETE.RES(CHIPS)':
 'B': CDS_PINID='B';
NODE_NAME     U5D1 AW86
 '@BASEBOARD_FAB2_LIB.BASEBOARD_FAB2(SCH_1):PAGE37_I311@CHPSET_LIB.SKX_EXT_B(CHIPS)':
 'VCCINPMAX'<0>: CDS_PINID='VCCINPMAX(0)';
NODE_NAME     U5D1 AV85
 '@BASEBOARD_FAB2_LIB.BASEBOARD_FAB2(SCH_1):PAGE37_I311@CHPSET_LIB.SKX_EXT_B(CHIPS)':
 'VCCINPMAX'<1>: CDS_PINID='VCCINPMAX(1)';
NET_NAME
'VSENSE_VCCINR2PMAX_CPU1'
 '@BASEBOARD_FAB2_LIB.BASEBOARD_FAB2(SCH_1):VSENSE_VCCINR2PMAX_CPU1':
 C_SIGNAL='@baseboard_fab2_lib.baseboard_fab2(sch_1):vsense_vccinr2pmax_cpu1';
NODE_NAME     RT8P1 2
 '@BASEBOARD_FAB2_LIB.BASEBOARD_FAB2(SCH_1):PAGE71_I49@MSTR_DISCRETE.RES(CHIPS)':
 'B': CDS_PINID='B';
NODE_NAME     U2D1 AW86
 '@BASEBOARD_FAB2_LIB.BASEBOARD_FAB2(SCH_1):PAGE71_I51@CHPSET_LIB.SKX_EXT_B(CHIPS)':
 'VCCINPMAX'<0>: CDS_PINID='VCCINPMAX(0)';
NODE_NAME     U2D1 AV85
 '@BASEBOARD_FAB2_LIB.BASEBOARD_FAB2(SCH_1):PAGE71_I51@CHPSET_LIB.SKX_EXT_B(CHIPS)':
 'VCCINPMAX'<1>: CDS_PINID='VCCINPMAX(1)';
NET_NAME
'VSENSE_VOUT_P3V3_STBY'
 '@BASEBOARD_FAB2_LIB.BASEBOARD_FAB2(SCH_1):VSENSE_VOUT_P3V3_STBY':
 C_SIGNAL='@baseboard_fab2_lib.baseboard_fab2(sch_1):vsense_vout_p3v3_stby';
NODE_NAME     EU8F1 6
 '@BASEBOARD_FAB2_LIB.BASEBOARD_FAB2(SCH_1):PAGE240_I125@MSTR_VREG.RT8240(CHIPS)':
 'VOUT': CDS_PINID='VOUT';
NODE_NAME     R8E34 1
 '@BASEBOARD_FAB2_LIB.BASEBOARD_FAB2(SCH_1):PAGE240_I142@MSTR_DISCRETE.RES(CHIPS)':
 'A': CDS_PINID='A';
NODE_NAME     R8E31 2
 '@BASEBOARD_FAB2_LIB.BASEBOARD_FAB2(SCH_1):PAGE240_I143@MSTR_DISCRETE.RES(CHIPS)':
 'B': CDS_PINID='B';
NET_NAME
'V_IBMC_5V_DDC_SCL_J'
 '@BASEBOARD_FAB2_LIB.BASEBOARD_FAB2(SCH_1):V_IBMC_5V_DDC_SCL_J':
 C_SIGNAL='@baseboard_fab2_lib.baseboard_fab2(sch_1):v_ibmc_5v_ddc_scl_j';
NODE_NAME     R25W133 2
 '@BASEBOARD_FAB2_LIB.BASEBOARD_FAB2(SCH_1):PAGE255_I34@MSTR_DISCRETE.RES(CHIPS)':
 'B': CDS_PINID='B';
NODE_NAME     C25W78 1
 '@BASEBOARD_FAB2_LIB.BASEBOARD_FAB2(SCH_1):PAGE255_I35@MSTR_DISCRETE.CAP(CHIPS)':
 'A': CDS_PINID='A';
NODE_NAME     CR25W2 2
 '@BASEBOARD_FAB2_LIB.BASEBOARD_FAB2(SCH_1):PAGE255_I131@MSTR_DISCRETE.DIODEAC_DUAL_ARRAY(CHIPS)':
 'AC1': CDS_PINID='AC1';
NODE_NAME     CR25W2 8
 '@BASEBOARD_FAB2_LIB.BASEBOARD_FAB2(SCH_1):PAGE255_I131@MSTR_DISCRETE.DIODEAC_DUAL_ARRAY(CHIPS)':
 'OUT1': CDS_PINID='OUT1';
NODE_NAME     J25W1 12
 '@BASEBOARD_FAB2_LIB.BASEBOARD_FAB2(SCH_1):PAGE255_I136@W_HDL.SMC-CON13-GP(CHIPS)':
 '12': CDS_PINID='\12\';
NET_NAME
'V_IBMC_5V_DDC_SDA_J'
 '@BASEBOARD_FAB2_LIB.BASEBOARD_FAB2(SCH_1):V_IBMC_5V_DDC_SDA_J':
 C_SIGNAL='@baseboard_fab2_lib.baseboard_fab2(sch_1):v_ibmc_5v_ddc_sda_j';
NODE_NAME     R25W136 2
 '@BASEBOARD_FAB2_LIB.BASEBOARD_FAB2(SCH_1):PAGE255_I38@MSTR_DISCRETE.RES(CHIPS)':
 'B': CDS_PINID='B';
NODE_NAME     C25W79 1
 '@BASEBOARD_FAB2_LIB.BASEBOARD_FAB2(SCH_1):PAGE255_I39@MSTR_DISCRETE.CAP(CHIPS)':
 'A': CDS_PINID='A';
NODE_NAME     CR25W2 1
 '@BASEBOARD_FAB2_LIB.BASEBOARD_FAB2(SCH_1):PAGE255_I131@MSTR_DISCRETE.DIODEAC_DUAL_ARRAY(CHIPS)':
 'AC0': CDS_PINID='AC0';
NODE_NAME     CR25W2 9
 '@BASEBOARD_FAB2_LIB.BASEBOARD_FAB2(SCH_1):PAGE255_I131@MSTR_DISCRETE.DIODEAC_DUAL_ARRAY(CHIPS)':
 'OUT0': CDS_PINID='OUT0';
NODE_NAME     J25W1 11
 '@BASEBOARD_FAB2_LIB.BASEBOARD_FAB2(SCH_1):PAGE255_I136@W_HDL.SMC-CON13-GP(CHIPS)':
 '11': CDS_PINID='\11\';
NET_NAME
'V_IO_B_J'
 '@BASEBOARD_FAB2_LIB.BASEBOARD_FAB2(SCH_1):V_IO_B_J':
 C_SIGNAL='@baseboard_fab2_lib.baseboard_fab2(sch_1):v_io_b_j';
NODE_NAME     C25W75 1
 '@BASEBOARD_FAB2_LIB.BASEBOARD_FAB2(SCH_1):PAGE255_I21@MSTR_DISCRETE.CAP(CHIPS)':
 'A': CDS_PINID='A';
NODE_NAME     R25W126 1
 '@BASEBOARD_FAB2_LIB.BASEBOARD_FAB2(SCH_1):PAGE255_I26@MSTR_DISCRETE.RES(CHIPS)':
 'A': CDS_PINID='A';
NODE_NAME     L25W1 2
 '@BASEBOARD_FAB2_LIB.BASEBOARD_FAB2(SCH_1):PAGE255_I76@W_HDL.IND-68NH-15-GP(CHIPS)':
 '2': CDS_PINID='\2\';
NODE_NAME     CR25W1 1
 '@BASEBOARD_FAB2_LIB.BASEBOARD_FAB2(SCH_1):PAGE255_I129@MSTR_DISCRETE.DIODEAC_DUAL_ARRAY(CHIPS)':
 'AC0': CDS_PINID='AC0';
NODE_NAME     CR25W1 9
 '@BASEBOARD_FAB2_LIB.BASEBOARD_FAB2(SCH_1):PAGE255_I129@MSTR_DISCRETE.DIODEAC_DUAL_ARRAY(CHIPS)':
 'OUT0': CDS_PINID='OUT0';
NODE_NAME     J25W1 5
 '@BASEBOARD_FAB2_LIB.BASEBOARD_FAB2(SCH_1):PAGE255_I136@W_HDL.SMC-CON13-GP(CHIPS)':
 '5': CDS_PINID='\5\';
NET_NAME
'V_IO_G_J'
 '@BASEBOARD_FAB2_LIB.BASEBOARD_FAB2(SCH_1):V_IO_G_J':
 C_SIGNAL='@baseboard_fab2_lib.baseboard_fab2(sch_1):v_io_g_j';
NODE_NAME     C25W76 1
 '@BASEBOARD_FAB2_LIB.BASEBOARD_FAB2(SCH_1):PAGE255_I18@MSTR_DISCRETE.CAP(CHIPS)':
 'A': CDS_PINID='A';
NODE_NAME     R25W127 1
 '@BASEBOARD_FAB2_LIB.BASEBOARD_FAB2(SCH_1):PAGE255_I24@MSTR_DISCRETE.RES(CHIPS)':
 'A': CDS_PINID='A';
NODE_NAME     L25W2 2
 '@BASEBOARD_FAB2_LIB.BASEBOARD_FAB2(SCH_1):PAGE255_I77@W_HDL.IND-68NH-15-GP(CHIPS)':
 '2': CDS_PINID='\2\';
NODE_NAME     CR25W1 2
 '@BASEBOARD_FAB2_LIB.BASEBOARD_FAB2(SCH_1):PAGE255_I129@MSTR_DISCRETE.DIODEAC_DUAL_ARRAY(CHIPS)':
 'AC1': CDS_PINID='AC1';
NODE_NAME     CR25W1 8
 '@BASEBOARD_FAB2_LIB.BASEBOARD_FAB2(SCH_1):PAGE255_I129@MSTR_DISCRETE.DIODEAC_DUAL_ARRAY(CHIPS)':
 'OUT1': CDS_PINID='OUT1';
NODE_NAME     J25W1 3
 '@BASEBOARD_FAB2_LIB.BASEBOARD_FAB2(SCH_1):PAGE255_I136@W_HDL.SMC-CON13-GP(CHIPS)':
 '3': CDS_PINID='\3\';
NET_NAME
'V_IO_HSYNC_J'
 '@BASEBOARD_FAB2_LIB.BASEBOARD_FAB2(SCH_1):V_IO_HSYNC_J':
 C_SIGNAL='@baseboard_fab2_lib.baseboard_fab2(sch_1):v_io_hsync_j';
NODE_NAME     R25W138 2
 '@BASEBOARD_FAB2_LIB.BASEBOARD_FAB2(SCH_1):PAGE255_I49@MSTR_DISCRETE.RES(CHIPS)':
 'B': CDS_PINID='B';
NODE_NAME     C25W81 1
 '@BASEBOARD_FAB2_LIB.BASEBOARD_FAB2(SCH_1):PAGE255_I60@MSTR_DISCRETE.CAP(CHIPS)':
 'A': CDS_PINID='A';
NODE_NAME     CR25W2 5
 '@BASEBOARD_FAB2_LIB.BASEBOARD_FAB2(SCH_1):PAGE255_I131@MSTR_DISCRETE.DIODEAC_DUAL_ARRAY(CHIPS)':
 'AC3': CDS_PINID='AC3';
NODE_NAME     CR25W2 6
 '@BASEBOARD_FAB2_LIB.BASEBOARD_FAB2(SCH_1):PAGE255_I131@MSTR_DISCRETE.DIODEAC_DUAL_ARRAY(CHIPS)':
 'OUT3': CDS_PINID='OUT3';
NODE_NAME     J25W1 9
 '@BASEBOARD_FAB2_LIB.BASEBOARD_FAB2(SCH_1):PAGE255_I136@W_HDL.SMC-CON13-GP(CHIPS)':
 '9': CDS_PINID='\9\';
NET_NAME
'V_IO_R_J'
 '@BASEBOARD_FAB2_LIB.BASEBOARD_FAB2(SCH_1):V_IO_R_J':
 C_SIGNAL='@baseboard_fab2_lib.baseboard_fab2(sch_1):v_io_r_j';
NODE_NAME     C25W77 1
 '@BASEBOARD_FAB2_LIB.BASEBOARD_FAB2(SCH_1):PAGE255_I16@MSTR_DISCRETE.CAP(CHIPS)':
 'A': CDS_PINID='A';
NODE_NAME     R25W128 1
 '@BASEBOARD_FAB2_LIB.BASEBOARD_FAB2(SCH_1):PAGE255_I22@MSTR_DISCRETE.RES(CHIPS)':
 'A': CDS_PINID='A';
NODE_NAME     L25W3 2
 '@BASEBOARD_FAB2_LIB.BASEBOARD_FAB2(SCH_1):PAGE255_I78@W_HDL.IND-68NH-15-GP(CHIPS)':
 '2': CDS_PINID='\2\';
NODE_NAME     CR25W1 4
 '@BASEBOARD_FAB2_LIB.BASEBOARD_FAB2(SCH_1):PAGE255_I129@MSTR_DISCRETE.DIODEAC_DUAL_ARRAY(CHIPS)':
 'AC2': CDS_PINID='AC2';
NODE_NAME     CR25W1 7
 '@BASEBOARD_FAB2_LIB.BASEBOARD_FAB2(SCH_1):PAGE255_I129@MSTR_DISCRETE.DIODEAC_DUAL_ARRAY(CHIPS)':
 'OUT2': CDS_PINID='OUT2';
NODE_NAME     J25W1 1
 '@BASEBOARD_FAB2_LIB.BASEBOARD_FAB2(SCH_1):PAGE255_I136@W_HDL.SMC-CON13-GP(CHIPS)':
 '1': CDS_PINID='\1\';
NET_NAME
'V_IO_VSYNC_J'
 '@BASEBOARD_FAB2_LIB.BASEBOARD_FAB2(SCH_1):V_IO_VSYNC_J':
 C_SIGNAL='@baseboard_fab2_lib.baseboard_fab2(sch_1):v_io_vsync_j';
NODE_NAME     R25W139 2
 '@BASEBOARD_FAB2_LIB.BASEBOARD_FAB2(SCH_1):PAGE255_I59@MSTR_DISCRETE.RES(CHIPS)':
 'B': CDS_PINID='B';
NODE_NAME     C25W82 1
 '@BASEBOARD_FAB2_LIB.BASEBOARD_FAB2(SCH_1):PAGE255_I62@MSTR_DISCRETE.CAP(CHIPS)':
 'A': CDS_PINID='A';
NODE_NAME     CR25W2 4
 '@BASEBOARD_FAB2_LIB.BASEBOARD_FAB2(SCH_1):PAGE255_I131@MSTR_DISCRETE.DIODEAC_DUAL_ARRAY(CHIPS)':
 'AC2': CDS_PINID='AC2';
NODE_NAME     CR25W2 7
 '@BASEBOARD_FAB2_LIB.BASEBOARD_FAB2(SCH_1):PAGE255_I131@MSTR_DISCRETE.DIODEAC_DUAL_ARRAY(CHIPS)':
 'OUT2': CDS_PINID='OUT2';
NODE_NAME     J25W1 7
 '@BASEBOARD_FAB2_LIB.BASEBOARD_FAB2(SCH_1):PAGE255_I136@W_HDL.SMC-CON13-GP(CHIPS)':
 '7': CDS_PINID='\7\';
NET_NAME
'XDP_CPU0_TDO'
 '@BASEBOARD_FAB2_LIB.BASEBOARD_FAB2(SCH_1):XDP_CPU0_TDO':
 C_SIGNAL='@baseboard_fab2_lib.baseboard_fab2(sch_1):xdp_cpu0_tdo';
NODE_NAME     U5D1 AE14
 '@BASEBOARD_FAB2_LIB.BASEBOARD_FAB2(SCH_1):PAGE21_I259@CHPSET_LIB.SKX_EXT_B(CHIPS)':
 'TDO': CDS_PINID='TDO';
NODE_NAME     U1M7 1
 '@BASEBOARD_FAB2_LIB.BASEBOARD_FAB2(SCH_1):PAGE112_I40@MSTR_ANALOG.NC7SB3157(CHIPS)':
 'B1': CDS_PINID='B1';
NODE_NAME     R4P23 2
 '@BASEBOARD_FAB2_LIB.BASEBOARD_FAB2(SCH_1):PAGE112_I58@MSTR_DISCRETE.RES(CHIPS)':
 'B': CDS_PINID='B';
NODE_NAME     U1M4 2
 '@BASEBOARD_FAB2_LIB.BASEBOARD_FAB2(SCH_1):PAGE112_I127@MSTR_TTL.74CBTLV1G125(CHIPS)':
 'A': CDS_PINID='A';
NET_NAME
'XDP_CPU1_TDI'
 '@BASEBOARD_FAB2_LIB.BASEBOARD_FAB2(SCH_1):XDP_CPU1_TDI':
 C_SIGNAL='@baseboard_fab2_lib.baseboard_fab2(sch_1):xdp_cpu1_tdi';
NODE_NAME     U2D1 AC14
 '@BASEBOARD_FAB2_LIB.BASEBOARD_FAB2(SCH_1):PAGE55_I172@CHPSET_LIB.SKX_EXT_B(CHIPS)':
 'TDI': CDS_PINID='TDI';
NODE_NAME     R6T6 2
 '@BASEBOARD_FAB2_LIB.BASEBOARD_FAB2(SCH_1):PAGE112_I56@MSTR_DISCRETE.RES(CHIPS)':
 'B': CDS_PINID='B';
NODE_NAME     U1M4 4
 '@BASEBOARD_FAB2_LIB.BASEBOARD_FAB2(SCH_1):PAGE112_I127@MSTR_TTL.74CBTLV1G125(CHIPS)':
 'B': CDS_PINID='B';
NET_NAME
'XDP_CPU1_TDO'
 '@BASEBOARD_FAB2_LIB.BASEBOARD_FAB2(SCH_1):XDP_CPU1_TDO':
 C_SIGNAL='@baseboard_fab2_lib.baseboard_fab2(sch_1):xdp_cpu1_tdo';
NODE_NAME     U2D1 AE14
 '@BASEBOARD_FAB2_LIB.BASEBOARD_FAB2(SCH_1):PAGE55_I172@CHPSET_LIB.SKX_EXT_B(CHIPS)':
 'TDO': CDS_PINID='TDO';
NODE_NAME     U1M7 3
 '@BASEBOARD_FAB2_LIB.BASEBOARD_FAB2(SCH_1):PAGE112_I40@MSTR_ANALOG.NC7SB3157(CHIPS)':
 'B0': CDS_PINID='B0';
NODE_NAME     R6T7 2
 '@BASEBOARD_FAB2_LIB.BASEBOARD_FAB2(SCH_1):PAGE112_I55@MSTR_DISCRETE.RES(CHIPS)':
 'B': CDS_PINID='B';
NET_NAME
'XDP_CPU_GTL_TCK_R2'
 '@BASEBOARD_FAB2_LIB.BASEBOARD_FAB2(SCH_1):XDP_CPU_GTL_TCK_R2':
 C_SIGNAL='@baseboard_fab2_lib.baseboard_fab2(sch_1):xdp_cpu_gtl_tck_r2';
NODE_NAME     R9A2 2
 '@BASEBOARD_FAB2_LIB.BASEBOARD_FAB2(SCH_1):PAGE111_I83@MSTR_DISCRETE.RES(CHIPS)':
 'B': CDS_PINID='B';
NODE_NAME     Q9A1 1
 '@BASEBOARD_FAB2_LIB.BASEBOARD_FAB2(SCH_1):PAGE111_I93@MSTR_DISCRETE.NPN_DUAL(CHIPS)':
 'E'<0>: CDS_PINID='E(0)';
NET_NAME
'XDP_CPU_MBP0_N'
 '@BASEBOARD_FAB2_LIB.BASEBOARD_FAB2(SCH_1):XDP_CPU_MBP0_N':
 C_SIGNAL='@baseboard_fab2_lib.baseboard_fab2(sch_1):xdp_cpu_mbp0_n';
NODE_NAME     U5D1 AJ10
 '@BASEBOARD_FAB2_LIB.BASEBOARD_FAB2(SCH_1):PAGE21_I259@CHPSET_LIB.SKX_EXT_B(CHIPS)':
 'BPM_N'<0>: CDS_PINID='BPM_N(0)';
NODE_NAME     U2D1 AJ10
 '@BASEBOARD_FAB2_LIB.BASEBOARD_FAB2(SCH_1):PAGE55_I172@CHPSET_LIB.SKX_EXT_B(CHIPS)':
 'BPM_N'<0>: CDS_PINID='BPM_N(0)';
NODE_NAME     R7P30 2
 '@BASEBOARD_FAB2_LIB.BASEBOARD_FAB2(SCH_1):PAGE112_I50@MSTR_DISCRETE.RES(CHIPS)':
 'B': CDS_PINID='B';
NODE_NAME     R4P12 2
 '@BASEBOARD_FAB2_LIB.BASEBOARD_FAB2(SCH_1):PAGE112_I57@MSTR_DISCRETE.RES(CHIPS)':
 'B': CDS_PINID='B';
NET_NAME
'XDP_CPU_MBP1_N'
 '@BASEBOARD_FAB2_LIB.BASEBOARD_FAB2(SCH_1):XDP_CPU_MBP1_N':
 C_SIGNAL='@baseboard_fab2_lib.baseboard_fab2(sch_1):xdp_cpu_mbp1_n';
NODE_NAME     U5D1 AH11
 '@BASEBOARD_FAB2_LIB.BASEBOARD_FAB2(SCH_1):PAGE21_I259@CHPSET_LIB.SKX_EXT_B(CHIPS)':
 'BPM_N'<1>: CDS_PINID='BPM_N(1)';
NODE_NAME     U2D1 AH11
 '@BASEBOARD_FAB2_LIB.BASEBOARD_FAB2(SCH_1):PAGE55_I172@CHPSET_LIB.SKX_EXT_B(CHIPS)':
 'BPM_N'<1>: CDS_PINID='BPM_N(1)';
NODE_NAME     R6P46 2
 '@BASEBOARD_FAB2_LIB.BASEBOARD_FAB2(SCH_1):PAGE112_I49@MSTR_DISCRETE.RES(CHIPS)':
 'B': CDS_PINID='B';
NODE_NAME     R4P15 2
 '@BASEBOARD_FAB2_LIB.BASEBOARD_FAB2(SCH_1):PAGE112_I53@MSTR_DISCRETE.RES(CHIPS)':
 'B': CDS_PINID='B';
NET_NAME
'XDP_CPU_OBSFN_B0_MBP6_N'
 '@BASEBOARD_FAB2_LIB.BASEBOARD_FAB2(SCH_1):XDP_CPU_OBSFN_B0_MBP6_N':
 C_SIGNAL='@baseboard_fab2_lib.baseboard_fab2(sch_1):xdp_cpu_obsfn_b0_mbp6_n';
NODE_NAME     U5D1 AE12
 '@BASEBOARD_FAB2_LIB.BASEBOARD_FAB2(SCH_1):PAGE21_I259@CHPSET_LIB.SKX_EXT_B(CHIPS)':
 'BPM_N'<6>: CDS_PINID='BPM_N(6)';
NODE_NAME     U2D1 AE12
 '@BASEBOARD_FAB2_LIB.BASEBOARD_FAB2(SCH_1):PAGE55_I172@CHPSET_LIB.SKX_EXT_B(CHIPS)':
 'BPM_N'<6>: CDS_PINID='BPM_N(6)';
NODE_NAME     U1L5 6
 '@BASEBOARD_FAB2_LIB.BASEBOARD_FAB2(SCH_1):PAGE112_I109@MSTR_TTL.TTL3126(CHIPS)'(2):
 'B'<2>: CDS_PINID='B(2)';
NODE_NAME     R6T8 2
 '@BASEBOARD_FAB2_LIB.BASEBOARD_FAB2(SCH_1):PAGE112_I121@MSTR_DISCRETE.RES(CHIPS)':
 'B': CDS_PINID='B';
NET_NAME
'XDP_CPU_OBSFN_B1_MBP7_N'
 '@BASEBOARD_FAB2_LIB.BASEBOARD_FAB2(SCH_1):XDP_CPU_OBSFN_B1_MBP7_N':
 C_SIGNAL='@baseboard_fab2_lib.baseboard_fab2(sch_1):xdp_cpu_obsfn_b1_mbp7_n';
NODE_NAME     U5D1 AC12
 '@BASEBOARD_FAB2_LIB.BASEBOARD_FAB2(SCH_1):PAGE21_I259@CHPSET_LIB.SKX_EXT_B(CHIPS)':
 'BPM_N'<7>: CDS_PINID='BPM_N(7)';
NODE_NAME     U2D1 AC12
 '@BASEBOARD_FAB2_LIB.BASEBOARD_FAB2(SCH_1):PAGE55_I172@CHPSET_LIB.SKX_EXT_B(CHIPS)':
 'BPM_N'<7>: CDS_PINID='BPM_N(7)';
NODE_NAME     U1L5 3
 '@BASEBOARD_FAB2_LIB.BASEBOARD_FAB2(SCH_1):PAGE112_I109@MSTR_TTL.TTL3126(CHIPS)'(3):
 'B'<3>: CDS_PINID='B(3)';
NODE_NAME     R6T9 2
 '@BASEBOARD_FAB2_LIB.BASEBOARD_FAB2(SCH_1):PAGE112_I120@MSTR_DISCRETE.RES(CHIPS)':
 'B': CDS_PINID='B';
NET_NAME
'XDP_CPU_PRDY_N'
 '@BASEBOARD_FAB2_LIB.BASEBOARD_FAB2(SCH_1):XDP_CPU_PRDY_N':
 C_SIGNAL='@baseboard_fab2_lib.baseboard_fab2(sch_1):xdp_cpu_prdy_n';
NODE_NAME     U5D1 AG16
 '@BASEBOARD_FAB2_LIB.BASEBOARD_FAB2(SCH_1):PAGE21_I259@CHPSET_LIB.SKX_EXT_B(CHIPS)':
 'PRDY_N': CDS_PINID='PRDY_N';
NODE_NAME     U2D1 AG16
 '@BASEBOARD_FAB2_LIB.BASEBOARD_FAB2(SCH_1):PAGE55_I172@CHPSET_LIB.SKX_EXT_B(CHIPS)':
 'PRDY_N': CDS_PINID='PRDY_N';
NODE_NAME     R1M3 2
 '@BASEBOARD_FAB2_LIB.BASEBOARD_FAB2(SCH_1):PAGE112_I51@MSTR_DISCRETE.RES(CHIPS)':
 'B': CDS_PINID='B';
NODE_NAME     U1L5 8
 '@BASEBOARD_FAB2_LIB.BASEBOARD_FAB2(SCH_1):PAGE112_I109@MSTR_TTL.TTL3126(CHIPS)'(1):
 'B'<1>: CDS_PINID='B(1)';
NET_NAME
'XDP_CPU_PREQ_N'
 '@BASEBOARD_FAB2_LIB.BASEBOARD_FAB2(SCH_1):XDP_CPU_PREQ_N':
 C_SIGNAL='@baseboard_fab2_lib.baseboard_fab2(sch_1):xdp_cpu_preq_n';
NODE_NAME     U5D1 AR12
 '@BASEBOARD_FAB2_LIB.BASEBOARD_FAB2(SCH_1):PAGE21_I259@CHPSET_LIB.SKX_EXT_B(CHIPS)':
 'PREQ_N': CDS_PINID='PREQ_N';
NODE_NAME     U2D1 AR12
 '@BASEBOARD_FAB2_LIB.BASEBOARD_FAB2(SCH_1):PAGE55_I172@CHPSET_LIB.SKX_EXT_B(CHIPS)':
 'PREQ_N': CDS_PINID='PREQ_N';
NODE_NAME     R1M4 2
 '@BASEBOARD_FAB2_LIB.BASEBOARD_FAB2(SCH_1):PAGE112_I54@MSTR_DISCRETE.RES(CHIPS)':
 'B': CDS_PINID='B';
NODE_NAME     U1L5 11
 '@BASEBOARD_FAB2_LIB.BASEBOARD_FAB2(SCH_1):PAGE112_I109@MSTR_TTL.TTL3126(CHIPS)'(0):
 'B'<0>: CDS_PINID='B(0)';
NET_NAME
'XDP_CPU_PWR_DEBUG_N'
 '@BASEBOARD_FAB2_LIB.BASEBOARD_FAB2(SCH_1):XDP_CPU_PWR_DEBUG_N':
 C_SIGNAL='@baseboard_fab2_lib.baseboard_fab2(sch_1):xdp_cpu_pwr_debug_n';
NODE_NAME     U5D1 AP17
 '@BASEBOARD_FAB2_LIB.BASEBOARD_FAB2(SCH_1):PAGE22_I204@CHPSET_LIB.SKX_EXT_B(CHIPS)':
 'PWR_DEBUG_N': CDS_PINID='PWR_DEBUG_N';
NODE_NAME     U2D1 AP17
 '@BASEBOARD_FAB2_LIB.BASEBOARD_FAB2(SCH_1):PAGE56_I169@CHPSET_LIB.SKX_EXT_B(CHIPS)':
 'PWR_DEBUG_N': CDS_PINID='PWR_DEBUG_N';
NODE_NAME     J9A3 45
 '@BASEBOARD_FAB2_LIB.BASEBOARD_FAB2(SCH_1):PAGE111_I26@MSTR_SCONN.SCONN60_C21100002(CHIPS)':
 'IO45': CDS_PINID='IO45';
NODE_NAME     R1L17 1
 '@BASEBOARD_FAB2_LIB.BASEBOARD_FAB2(SCH_1):PAGE111_I56@MSTR_DISCRETE.RES(CHIPS)':
 'A': CDS_PINID='A';
NODE_NAME     C9A4 1
 '@BASEBOARD_FAB2_LIB.BASEBOARD_FAB2(SCH_1):PAGE111_I59@DEV_DISCRETE.CAP_A(CHIPS)':
 'A': CDS_PINID='A';
NODE_NAME     U7D1 4
 '@BASEBOARD_FAB2_LIB.BASEBOARD_FAB2(SCH_1):PAGE118_I142@MSTR_TTL.74CBTLV1G125(CHIPS)':
 'B': CDS_PINID='B';
NODE_NAME     U25W10 3
 '@BASEBOARD_FAB2_LIB.BASEBOARD_FAB2(SCH_1):PAGE269_I49@MSTR_DIGITAL.GTL2014(CHIPS)':
 'B1': CDS_PINID='B1';
NET_NAME
'XDP_CPU_TCK0'
 '@BASEBOARD_FAB2_LIB.BASEBOARD_FAB2(SCH_1):XDP_CPU_TCK0':
 C_SIGNAL='@baseboard_fab2_lib.baseboard_fab2(sch_1):xdp_cpu_tck0';
NODE_NAME     U5D1 AA14
 '@BASEBOARD_FAB2_LIB.BASEBOARD_FAB2(SCH_1):PAGE21_I259@CHPSET_LIB.SKX_EXT_B(CHIPS)':
 'TCK': CDS_PINID='TCK';
NODE_NAME     U2D1 AA14
 '@BASEBOARD_FAB2_LIB.BASEBOARD_FAB2(SCH_1):PAGE55_I172@CHPSET_LIB.SKX_EXT_B(CHIPS)':
 'TCK': CDS_PINID='TCK';
NODE_NAME     J9A3 57
 '@BASEBOARD_FAB2_LIB.BASEBOARD_FAB2(SCH_1):PAGE111_I26@MSTR_SCONN.SCONN60_C21100002(CHIPS)':
 'IO57': CDS_PINID='IO57';
NODE_NAME     R9A3 2
 '@BASEBOARD_FAB2_LIB.BASEBOARD_FAB2(SCH_1):PAGE111_I74@MSTR_DISCRETE.RES(CHIPS)':
 'B': CDS_PINID='B';
NODE_NAME     Q9A1 4
 '@BASEBOARD_FAB2_LIB.BASEBOARD_FAB2(SCH_1):PAGE111_I94@MSTR_DISCRETE.NPN_DUAL(CHIPS)':
 'E'<0>: CDS_PINID='E(0)';
NODE_NAME     R7P29 1
 '@BASEBOARD_FAB2_LIB.BASEBOARD_FAB2(SCH_1):PAGE112_I61@MSTR_DISCRETE.RES(CHIPS)':
 'A': CDS_PINID='A';
NODE_NAME     FB25W1 2
 '@BASEBOARD_FAB2_LIB.BASEBOARD_FAB2(SCH_1):PAGE269_I71@W_HDL.BLM15AG121SN-1GP(CHIPS)':
 '2': CDS_PINID='\2\';
NET_NAME
'XDP_CPU_TCK0_R'
 '@BASEBOARD_FAB2_LIB.BASEBOARD_FAB2(SCH_1):XDP_CPU_TCK0_R':
 C_SIGNAL='@baseboard_fab2_lib.baseboard_fab2(sch_1):xdp_cpu_tck0_r';
NODE_NAME     U25W12 6
 '@BASEBOARD_FAB2_LIB.BASEBOARD_FAB2(SCH_1):PAGE269_I33@MSTR_TTL.TTL3126(CHIPS)'(2):
 'B'<2>: CDS_PINID='B(2)';
NODE_NAME     FB25W1 1
 '@BASEBOARD_FAB2_LIB.BASEBOARD_FAB2(SCH_1):PAGE269_I71@W_HDL.BLM15AG121SN-1GP(CHIPS)':
 '1': CDS_PINID='\1\';
NET_NAME
'XDP_CPU_TCK_BUF'
 '@BASEBOARD_FAB2_LIB.BASEBOARD_FAB2(SCH_1):XDP_CPU_TCK_BUF':
 C_SIGNAL='@baseboard_fab2_lib.baseboard_fab2(sch_1):xdp_cpu_tck_buf';
NODE_NAME     Q9A1 2
 '@BASEBOARD_FAB2_LIB.BASEBOARD_FAB2(SCH_1):PAGE111_I93@MSTR_DISCRETE.NPN_DUAL(CHIPS)':
 'B'<0>: CDS_PINID='B(0)';
NODE_NAME     Q9A1 6
 '@BASEBOARD_FAB2_LIB.BASEBOARD_FAB2(SCH_1):PAGE111_I93@MSTR_DISCRETE.NPN_DUAL(CHIPS)':
 'C'<0>: CDS_PINID='C(0)';
NODE_NAME     Q9A1 5
 '@BASEBOARD_FAB2_LIB.BASEBOARD_FAB2(SCH_1):PAGE111_I94@MSTR_DISCRETE.NPN_DUAL(CHIPS)':
 'B'<0>: CDS_PINID='B(0)';
NODE_NAME     R9A1 2
 '@BASEBOARD_FAB2_LIB.BASEBOARD_FAB2(SCH_1):PAGE111_I95@MSTR_DISCRETE.RES(CHIPS)':
 'B': CDS_PINID='B';
NET_NAME
'XDP_CPU_TDI'
 '@BASEBOARD_FAB2_LIB.BASEBOARD_FAB2(SCH_1):XDP_CPU_TDI':
 C_SIGNAL='@baseboard_fab2_lib.baseboard_fab2(sch_1):xdp_cpu_tdi';
NODE_NAME     U5D1 AC14
 '@BASEBOARD_FAB2_LIB.BASEBOARD_FAB2(SCH_1):PAGE21_I259@CHPSET_LIB.SKX_EXT_B(CHIPS)':
 'TDI': CDS_PINID='TDI';
NODE_NAME     R4P24 2
 '@BASEBOARD_FAB2_LIB.BASEBOARD_FAB2(SCH_1):PAGE112_I59@MSTR_DISCRETE.RES(CHIPS)':
 'B': CDS_PINID='B';
NODE_NAME     U1L1 11
 '@BASEBOARD_FAB2_LIB.BASEBOARD_FAB2(SCH_1):PAGE112_I108@MSTR_TTL.TTL3126(CHIPS)'(0):
 'B'<0>: CDS_PINID='B(0)';
NET_NAME
'XDP_CPU_TDO'
 '@BASEBOARD_FAB2_LIB.BASEBOARD_FAB2(SCH_1):XDP_CPU_TDO':
 C_SIGNAL='@baseboard_fab2_lib.baseboard_fab2(sch_1):xdp_cpu_tdo';
NODE_NAME     U1M7 4
 '@BASEBOARD_FAB2_LIB.BASEBOARD_FAB2(SCH_1):PAGE112_I40@MSTR_ANALOG.NC7SB3157(CHIPS)':
 'A': CDS_PINID='A';
NODE_NAME     U1L1 8
 '@BASEBOARD_FAB2_LIB.BASEBOARD_FAB2(SCH_1):PAGE112_I108@MSTR_TTL.TTL3126(CHIPS)'(1):
 'B'<1>: CDS_PINID='B(1)';
NET_NAME
'XDP_CPU_TMS'
 '@BASEBOARD_FAB2_LIB.BASEBOARD_FAB2(SCH_1):XDP_CPU_TMS':
 C_SIGNAL='@baseboard_fab2_lib.baseboard_fab2(sch_1):xdp_cpu_tms';
NODE_NAME     U5D1 W14
 '@BASEBOARD_FAB2_LIB.BASEBOARD_FAB2(SCH_1):PAGE21_I259@CHPSET_LIB.SKX_EXT_B(CHIPS)':
 'TMS': CDS_PINID='TMS';
NODE_NAME     U2D1 W14
 '@BASEBOARD_FAB2_LIB.BASEBOARD_FAB2(SCH_1):PAGE55_I172@CHPSET_LIB.SKX_EXT_B(CHIPS)':
 'TMS': CDS_PINID='TMS';
NODE_NAME     R1L15 2
 '@BASEBOARD_FAB2_LIB.BASEBOARD_FAB2(SCH_1):PAGE112_I60@MSTR_DISCRETE.RES(CHIPS)':
 'B': CDS_PINID='B';
NODE_NAME     U1L1 6
 '@BASEBOARD_FAB2_LIB.BASEBOARD_FAB2(SCH_1):PAGE112_I108@MSTR_TTL.TTL3126(CHIPS)'(2):
 'B'<2>: CDS_PINID='B(2)';
NET_NAME
'XDP_CPU_TRST_N'
 '@BASEBOARD_FAB2_LIB.BASEBOARD_FAB2(SCH_1):XDP_CPU_TRST_N':
 C_SIGNAL='@baseboard_fab2_lib.baseboard_fab2(sch_1):xdp_cpu_trst_n';
NODE_NAME     U5D1 Y13
 '@BASEBOARD_FAB2_LIB.BASEBOARD_FAB2(SCH_1):PAGE21_I259@CHPSET_LIB.SKX_EXT_B(CHIPS)':
 'TRST_N': CDS_PINID='TRST_N';
NODE_NAME     U2D1 Y13
 '@BASEBOARD_FAB2_LIB.BASEBOARD_FAB2(SCH_1):PAGE55_I172@CHPSET_LIB.SKX_EXT_B(CHIPS)':
 'TRST_N': CDS_PINID='TRST_N';
NODE_NAME     R6T5 1
 '@BASEBOARD_FAB2_LIB.BASEBOARD_FAB2(SCH_1):PAGE112_I62@MSTR_DISCRETE.RES(CHIPS)':
 'A': CDS_PINID='A';
NODE_NAME     U1L1 3
 '@BASEBOARD_FAB2_LIB.BASEBOARD_FAB2(SCH_1):PAGE112_I108@MSTR_TTL.TTL3126(CHIPS)'(3):
 'B'<3>: CDS_PINID='B(3)';
NET_NAME
'XDP_DEBUG_CONSENT_N'
 '@BASEBOARD_FAB2_LIB.BASEBOARD_FAB2(SCH_1):XDP_DEBUG_CONSENT_N':
 C_SIGNAL='@baseboard_fab2_lib.baseboard_fab2(sch_1):xdp_debug_consent_n';
NODE_NAME     J9A3 1
 '@BASEBOARD_FAB2_LIB.BASEBOARD_FAB2(SCH_1):PAGE111_I26@MSTR_SCONN.SCONN60_C21100002(CHIPS)':
 'IO1': CDS_PINID='IO1';
NODE_NAME     R2P2 2
 '@BASEBOARD_FAB2_LIB.BASEBOARD_FAB2(SCH_1):PAGE111_I37@MSTR_DISCRETE.RES(CHIPS)':
 'B': CDS_PINID='B';
NET_NAME
'XDP_ITP_PMODE'
 '@BASEBOARD_FAB2_LIB.BASEBOARD_FAB2(SCH_1):XDP_ITP_PMODE':
 C_SIGNAL='@baseboard_fab2_lib.baseboard_fab2(sch_1):xdp_itp_pmode';
NODE_NAME     J9A3 46
 '@BASEBOARD_FAB2_LIB.BASEBOARD_FAB2(SCH_1):PAGE111_I26@MSTR_SCONN.SCONN60_C21100002(CHIPS)':
 'IO46': CDS_PINID='IO46';
NODE_NAME     R9A17 1
 '@BASEBOARD_FAB2_LIB.BASEBOARD_FAB2(SCH_1):PAGE111_I57@MSTR_DISCRETE.RES(CHIPS)':
 'A': CDS_PINID='A';
NODE_NAME     U7C1 AR54
 '@BASEBOARD_FAB2_LIB.BASEBOARD_FAB2(SCH_1):PAGE118_I73@MSTR_U_PROC.LBG_CORE_QAT_EXT_D(CHIPS)':
 'ITP_PMODE': CDS_PINID='ITP_PMODE';
NET_NAME
'XDP_OBSFN_B0_MBP6_N'
 '@BASEBOARD_FAB2_LIB.BASEBOARD_FAB2(SCH_1):XDP_OBSFN_B0_MBP6_N':
 C_SIGNAL='@baseboard_fab2_lib.baseboard_fab2(sch_1):xdp_obsfn_b0_mbp6_n';
NODE_NAME     J9A3 22
 '@BASEBOARD_FAB2_LIB.BASEBOARD_FAB2(SCH_1):PAGE111_I26@MSTR_SCONN.SCONN60_C21100002(CHIPS)':
 'IO22': CDS_PINID='IO22';
NODE_NAME     U1L5 5
 '@BASEBOARD_FAB2_LIB.BASEBOARD_FAB2(SCH_1):PAGE112_I109@MSTR_TTL.TTL3126(CHIPS)'(2):
 'A'<2>: CDS_PINID='A(2)';
NET_NAME
'XDP_OBSFN_B1_MBP7_N'
 '@BASEBOARD_FAB2_LIB.BASEBOARD_FAB2(SCH_1):XDP_OBSFN_B1_MBP7_N':
 C_SIGNAL='@baseboard_fab2_lib.baseboard_fab2(sch_1):xdp_obsfn_b1_mbp7_n';
NODE_NAME     J9A3 24
 '@BASEBOARD_FAB2_LIB.BASEBOARD_FAB2(SCH_1):PAGE111_I26@MSTR_SCONN.SCONN60_C21100002(CHIPS)':
 'IO24': CDS_PINID='IO24';
NODE_NAME     U1L5 2
 '@BASEBOARD_FAB2_LIB.BASEBOARD_FAB2(SCH_1):PAGE112_I109@MSTR_TTL.TTL3126(CHIPS)'(3):
 'A'<3>: CDS_PINID='A(3)';
NET_NAME
'XDP_PCH_CPU_TCK0'
 '@BASEBOARD_FAB2_LIB.BASEBOARD_FAB2(SCH_1):XDP_PCH_CPU_TCK0':
 C_SIGNAL='@baseboard_fab2_lib.baseboard_fab2(sch_1):xdp_pch_cpu_tck0';
NODE_NAME     R9A3 1
 '@BASEBOARD_FAB2_LIB.BASEBOARD_FAB2(SCH_1):PAGE111_I74@MSTR_DISCRETE.RES(CHIPS)':
 'A': CDS_PINID='A';
NODE_NAME     R9A2 1
 '@BASEBOARD_FAB2_LIB.BASEBOARD_FAB2(SCH_1):PAGE111_I83@MSTR_DISCRETE.RES(CHIPS)':
 'A': CDS_PINID='A';
NODE_NAME     R3M10 1
 '@BASEBOARD_FAB2_LIB.BASEBOARD_FAB2(SCH_1):PAGE112_I85@MSTR_DISCRETE.RES(CHIPS)':
 'A': CDS_PINID='A';
NODE_NAME     U7C1 AF54
 '@BASEBOARD_FAB2_LIB.BASEBOARD_FAB2(SCH_1):PAGE118_I73@MSTR_U_PROC.LBG_CORE_QAT_EXT_D(CHIPS)':
 'JTAGX': CDS_PINID='JTAGX';
NET_NAME
'XDP_PCH_PWR_DEBUG_N'
 '@BASEBOARD_FAB2_LIB.BASEBOARD_FAB2(SCH_1):XDP_PCH_PWR_DEBUG_N':
 C_SIGNAL='@baseboard_fab2_lib.baseboard_fab2(sch_1):xdp_pch_pwr_debug_n';
NODE_NAME     U7C1 G15
 '@BASEBOARD_FAB2_LIB.BASEBOARD_FAB2(SCH_1):PAGE118_I73@MSTR_U_PROC.LBG_CORE_QAT_EXT_D(CHIPS)':
 'GPD0': CDS_PINID='GPD0';
NODE_NAME     U7D1 2
 '@BASEBOARD_FAB2_LIB.BASEBOARD_FAB2(SCH_1):PAGE118_I142@MSTR_TTL.74CBTLV1G125(CHIPS)':
 'A': CDS_PINID='A';
NODE_NAME     R7C23 2
 '@BASEBOARD_FAB2_LIB.BASEBOARD_FAB2(SCH_1):PAGE118_I144@MSTR_DISCRETE.RES(CHIPS)':
 'B': CDS_PINID='B';
NET_NAME
'XDP_PCH_TCK1'
 '@BASEBOARD_FAB2_LIB.BASEBOARD_FAB2(SCH_1):XDP_PCH_TCK1':
 C_SIGNAL='@baseboard_fab2_lib.baseboard_fab2(sch_1):xdp_pch_tck1';
NODE_NAME     J9A3 55
 '@BASEBOARD_FAB2_LIB.BASEBOARD_FAB2(SCH_1):PAGE111_I26@MSTR_SCONN.SCONN60_C21100002(CHIPS)':
 'IO55': CDS_PINID='IO55';
NODE_NAME     R8B1 1
 '@BASEBOARD_FAB2_LIB.BASEBOARD_FAB2(SCH_1):PAGE112_I95@MSTR_DISCRETE.RES(CHIPS)':
 'A': CDS_PINID='A';
NODE_NAME     U7C1 AL56
 '@BASEBOARD_FAB2_LIB.BASEBOARD_FAB2(SCH_1):PAGE118_I73@MSTR_U_PROC.LBG_CORE_QAT_EXT_D(CHIPS)':
 'JTAG_TCK': CDS_PINID='JTAG_TCK';
NODE_NAME     FB25W2 2
 '@BASEBOARD_FAB2_LIB.BASEBOARD_FAB2(SCH_1):PAGE269_I72@W_HDL.BLM15AG121SN-1GP(CHIPS)':
 '2': CDS_PINID='\2\';
NET_NAME
'XDP_PCH_TCK1_R'
 '@BASEBOARD_FAB2_LIB.BASEBOARD_FAB2(SCH_1):XDP_PCH_TCK1_R':
 C_SIGNAL='@baseboard_fab2_lib.baseboard_fab2(sch_1):xdp_pch_tck1_r';
NODE_NAME     U25W12 8
 '@BASEBOARD_FAB2_LIB.BASEBOARD_FAB2(SCH_1):PAGE269_I33@MSTR_TTL.TTL3126(CHIPS)'(1):
 'B'<1>: CDS_PINID='B(1)';
NODE_NAME     FB25W2 1
 '@BASEBOARD_FAB2_LIB.BASEBOARD_FAB2(SCH_1):PAGE269_I72@W_HDL.BLM15AG121SN-1GP(CHIPS)':
 '1': CDS_PINID='\1\';
NET_NAME
'XDP_PRDY_N'
 '@BASEBOARD_FAB2_LIB.BASEBOARD_FAB2(SCH_1):XDP_PRDY_N':
 C_SIGNAL='@baseboard_fab2_lib.baseboard_fab2(sch_1):xdp_prdy_n';
NODE_NAME     J9A3 5
 '@BASEBOARD_FAB2_LIB.BASEBOARD_FAB2(SCH_1):PAGE111_I26@MSTR_SCONN.SCONN60_C21100002(CHIPS)':
 'IO5': CDS_PINID='IO5';
NODE_NAME     R1L39 2
 '@BASEBOARD_FAB2_LIB.BASEBOARD_FAB2(SCH_1):PAGE112_I76@MSTR_DISCRETE.RES(CHIPS)':
 'B': CDS_PINID='B';
NODE_NAME     U1L5 9
 '@BASEBOARD_FAB2_LIB.BASEBOARD_FAB2(SCH_1):PAGE112_I109@MSTR_TTL.TTL3126(CHIPS)'(1):
 'A'<1>: CDS_PINID='A(1)';
NODE_NAME     U7C1 AD54
 '@BASEBOARD_FAB2_LIB.BASEBOARD_FAB2(SCH_1):PAGE118_I73@MSTR_U_PROC.LBG_CORE_QAT_EXT_D(CHIPS)':
 'PRDY_N': CDS_PINID='PRDY_N';
NODE_NAME     U25W11 3
 '@BASEBOARD_FAB2_LIB.BASEBOARD_FAB2(SCH_1):PAGE268_I33@MSTR_DIGITAL.GTL2014(CHIPS)':
 'B1': CDS_PINID='B1';
NET_NAME
'XDP_PREQ_N'
 '@BASEBOARD_FAB2_LIB.BASEBOARD_FAB2(SCH_1):XDP_PREQ_N':
 C_SIGNAL='@baseboard_fab2_lib.baseboard_fab2(sch_1):xdp_preq_n';
NODE_NAME     J9A3 3
 '@BASEBOARD_FAB2_LIB.BASEBOARD_FAB2(SCH_1):PAGE111_I26@MSTR_SCONN.SCONN60_C21100002(CHIPS)':
 'IO3': CDS_PINID='IO3';
NODE_NAME     R1L41 2
 '@BASEBOARD_FAB2_LIB.BASEBOARD_FAB2(SCH_1):PAGE112_I77@MSTR_DISCRETE.RES(CHIPS)':
 'B': CDS_PINID='B';
NODE_NAME     U1L5 12
 '@BASEBOARD_FAB2_LIB.BASEBOARD_FAB2(SCH_1):PAGE112_I109@MSTR_TTL.TTL3126(CHIPS)'(0):
 'A'<0>: CDS_PINID='A(0)';
NODE_NAME     U7C1 U54
 '@BASEBOARD_FAB2_LIB.BASEBOARD_FAB2(SCH_1):PAGE118_I73@MSTR_U_PROC.LBG_CORE_QAT_EXT_D(CHIPS)':
 'PREQ_N': CDS_PINID='PREQ_N';
NODE_NAME     U25W10 2
 '@BASEBOARD_FAB2_LIB.BASEBOARD_FAB2(SCH_1):PAGE269_I49@MSTR_DIGITAL.GTL2014(CHIPS)':
 'B0': CDS_PINID='B0';
NET_NAME
'XDP_PRESENT_N'
 '@BASEBOARD_FAB2_LIB.BASEBOARD_FAB2(SCH_1):XDP_PRESENT_N':
 C_SIGNAL='@baseboard_fab2_lib.baseboard_fab2(sch_1):xdp_present_n';
NODE_NAME     J9A3 60
 '@BASEBOARD_FAB2_LIB.BASEBOARD_FAB2(SCH_1):PAGE111_I26@MSTR_SCONN.SCONN60_C21100002(CHIPS)':
 'IO60': CDS_PINID='IO60';
NODE_NAME     U25W4 W19
 '@BASEBOARD_FAB2_LIB.BASEBOARD_FAB2(SCH_1):PAGE146_I105@W_HDL.AST2520A1-GP-GP(CHIPS)':
 'GPIOR4_SPI2MOSI': CDS_PINID='GPIOR4_SPI2MOSI';
NODE_NAME     R25W179 2
 '@BASEBOARD_FAB2_LIB.BASEBOARD_FAB2(SCH_1):PAGE268_I7@MSTR_DISCRETE.RES(CHIPS)':
 'B': CDS_PINID='B';
NODE_NAME     U25W14 2
 '@BASEBOARD_FAB2_LIB.BASEBOARD_FAB2(SCH_1):PAGE268_I13@MSTR_TTL.TTL1G07_A(CHIPS)':
 'A': CDS_PINID='A';
NODE_NAME     U25W18 1
 '@BASEBOARD_FAB2_LIB.BASEBOARD_FAB2(SCH_1):PAGE268_I57@MSTR_TTL.TTL1G08(CHIPS)':
 'A'<0>: CDS_PINID='A(0)';
NET_NAME
'XDP_PWRGD_RST_N'
 '@BASEBOARD_FAB2_LIB.BASEBOARD_FAB2(SCH_1):XDP_PWRGD_RST_N':
 C_SIGNAL='@baseboard_fab2_lib.baseboard_fab2(sch_1):xdp_pwrgd_rst_n';
NODE_NAME     R1L23 1
 '@BASEBOARD_FAB2_LIB.BASEBOARD_FAB2(SCH_1):PAGE111_I13@MSTR_DISCRETE.RES(CHIPS)':
 'A': CDS_PINID='A';
NODE_NAME     C1L8 1
 '@BASEBOARD_FAB2_LIB.BASEBOARD_FAB2(SCH_1):PAGE111_I14@DEV_DISCRETE.CAP_A(CHIPS)':
 'A': CDS_PINID='A';
NODE_NAME     J9A3 41
 '@BASEBOARD_FAB2_LIB.BASEBOARD_FAB2(SCH_1):PAGE111_I26@MSTR_SCONN.SCONN60_C21100002(CHIPS)':
 'IO41': CDS_PINID='IO41';
NODE_NAME     U8D7 M11
 '@BASEBOARD_FAB2_LIB.BASEBOARD_FAB2(SCH_1):PAGE190_I179@MSTR_MEMORY.LCMXO2_A(CHIPS)':
 'PB19D': CDS_PINID='PB19D';
NET_NAME
'XDP_RSMRST_N'
 '@BASEBOARD_FAB2_LIB.BASEBOARD_FAB2(SCH_1):XDP_RSMRST_N':
 C_SIGNAL='@baseboard_fab2_lib.baseboard_fab2(sch_1):xdp_rsmrst_n';
NODE_NAME     J9A3 39
 '@BASEBOARD_FAB2_LIB.BASEBOARD_FAB2(SCH_1):PAGE111_I26@MSTR_SCONN.SCONN60_C21100002(CHIPS)':
 'IO39': CDS_PINID='IO39';
NODE_NAME     R9A15 2
 '@BASEBOARD_FAB2_LIB.BASEBOARD_FAB2(SCH_1):PAGE111_I60@MSTR_DISCRETE.RES(CHIPS)':
 'B': CDS_PINID='B';
NET_NAME
'XDP_RST_CO_N'
 '@BASEBOARD_FAB2_LIB.BASEBOARD_FAB2(SCH_1):XDP_RST_CO_N':
 C_SIGNAL='@baseboard_fab2_lib.baseboard_fab2(sch_1):xdp_rst_co_n';
NODE_NAME     R9A14 1
 '@BASEBOARD_FAB2_LIB.BASEBOARD_FAB2(SCH_1):PAGE111_I11@MSTR_DISCRETE.RES(CHIPS)':
 'A': CDS_PINID='A';
NODE_NAME     C9A5 1
 '@BASEBOARD_FAB2_LIB.BASEBOARD_FAB2(SCH_1):PAGE111_I12@DEV_DISCRETE.CAP_A(CHIPS)':
 'A': CDS_PINID='A';
NODE_NAME     J9A3 48
 '@BASEBOARD_FAB2_LIB.BASEBOARD_FAB2(SCH_1):PAGE111_I26@MSTR_SCONN.SCONN60_C21100002(CHIPS)':
 'IO48': CDS_PINID='IO48';
NODE_NAME     U1L4 2
 '@BASEBOARD_FAB2_LIB.BASEBOARD_FAB2(SCH_1):PAGE111_I85@MSTR_TTL.TTL1G07_A(CHIPS)':
 'A': CDS_PINID='A';
NET_NAME
'XDP_SPI_PCH_MOSI_BOOT_HALT_N'
 '@BASEBOARD_FAB2_LIB.BASEBOARD_FAB2(SCH_1):XDP_SPI_PCH_MOSI_BOOT_HALT_N':
 C_SIGNAL='@baseboard_fab2_lib.baseboard_fab2(sch_1):xdp_spi_pch_mosi_boot_halt_~
n';
NODE_NAME     J9A3 6
 '@BASEBOARD_FAB2_LIB.BASEBOARD_FAB2(SCH_1):PAGE111_I26@MSTR_SCONN.SCONN60_C21100002(CHIPS)':
 'IO6': CDS_PINID='IO6';
NODE_NAME     R8E2 1
 '@BASEBOARD_FAB2_LIB.BASEBOARD_FAB2(SCH_1):PAGE111_I89@MSTR_DISCRETE.RES(CHIPS)':
 'A': CDS_PINID='A';
NET_NAME
'XDP_SYSPWROK'
 '@BASEBOARD_FAB2_LIB.BASEBOARD_FAB2(SCH_1):XDP_SYSPWROK':
 C_SIGNAL='@baseboard_fab2_lib.baseboard_fab2(sch_1):xdp_syspwrok';
NODE_NAME     R1L13 1
 '@BASEBOARD_FAB2_LIB.BASEBOARD_FAB2(SCH_1):PAGE111_I6@MSTR_DISCRETE.RES(CHIPS)':
 'A': CDS_PINID='A';
NODE_NAME     C9A2 1
 '@BASEBOARD_FAB2_LIB.BASEBOARD_FAB2(SCH_1):PAGE111_I10@DEV_DISCRETE.CAP_A(CHIPS)':
 'A': CDS_PINID='A';
NODE_NAME     J9A3 47
 '@BASEBOARD_FAB2_LIB.BASEBOARD_FAB2(SCH_1):PAGE111_I26@MSTR_SCONN.SCONN60_C21100002(CHIPS)':
 'IO47': CDS_PINID='IO47';
NODE_NAME     U8D7 N11
 '@BASEBOARD_FAB2_LIB.BASEBOARD_FAB2(SCH_1):PAGE190_I179@MSTR_MEMORY.LCMXO2_A(CHIPS)':
 'PB21D': CDS_PINID='PB21D';
NODE_NAME     R25W182 1
 '@BASEBOARD_FAB2_LIB.BASEBOARD_FAB2(SCH_1):PAGE144_I151@MSTR_DISCRETE.RES(CHIPS)':
 'A': CDS_PINID='A';
NET_NAME
'XDP_TDI'
 '@BASEBOARD_FAB2_LIB.BASEBOARD_FAB2(SCH_1):XDP_TDI':
 C_SIGNAL='@baseboard_fab2_lib.baseboard_fab2(sch_1):xdp_tdi';
NODE_NAME     J9A3 56
 '@BASEBOARD_FAB2_LIB.BASEBOARD_FAB2(SCH_1):PAGE111_I26@MSTR_SCONN.SCONN60_C21100002(CHIPS)':
 'IO56': CDS_PINID='IO56';
NODE_NAME     R8A13 2
 '@BASEBOARD_FAB2_LIB.BASEBOARD_FAB2(SCH_1):PAGE112_I79@MSTR_DISCRETE.RES(CHIPS)':
 'B': CDS_PINID='B';
NODE_NAME     U1L1 12
 '@BASEBOARD_FAB2_LIB.BASEBOARD_FAB2(SCH_1):PAGE112_I108@MSTR_TTL.TTL3126(CHIPS)'(0):
 'A'<0>: CDS_PINID='A(0)';
NODE_NAME     U7C1 AN54
 '@BASEBOARD_FAB2_LIB.BASEBOARD_FAB2(SCH_1):PAGE118_I73@MSTR_U_PROC.LBG_CORE_QAT_EXT_D(CHIPS)':
 'JTAG_TDI': CDS_PINID='JTAG_TDI';
NODE_NAME     FB25W4 2
 '@BASEBOARD_FAB2_LIB.BASEBOARD_FAB2(SCH_1):PAGE269_I75@W_HDL.BLM15AG121SN-1GP(CHIPS)':
 '2': CDS_PINID='\2\';
NET_NAME
'XDP_TDI_R'
 '@BASEBOARD_FAB2_LIB.BASEBOARD_FAB2(SCH_1):XDP_TDI_R':
 C_SIGNAL='@baseboard_fab2_lib.baseboard_fab2(sch_1):xdp_tdi_r';
NODE_NAME     U25W10 5
 '@BASEBOARD_FAB2_LIB.BASEBOARD_FAB2(SCH_1):PAGE269_I49@MSTR_DIGITAL.GTL2014(CHIPS)':
 'B2': CDS_PINID='B2';
NODE_NAME     FB25W4 1
 '@BASEBOARD_FAB2_LIB.BASEBOARD_FAB2(SCH_1):PAGE269_I75@W_HDL.BLM15AG121SN-1GP(CHIPS)':
 '1': CDS_PINID='\1\';
NET_NAME
'XDP_TDO'
 '@BASEBOARD_FAB2_LIB.BASEBOARD_FAB2(SCH_1):XDP_TDO':
 C_SIGNAL='@baseboard_fab2_lib.baseboard_fab2(sch_1):xdp_tdo';
NODE_NAME     J9A3 52
 '@BASEBOARD_FAB2_LIB.BASEBOARD_FAB2(SCH_1):PAGE111_I26@MSTR_SCONN.SCONN60_C21100002(CHIPS)':
 'IO52': CDS_PINID='IO52';
NODE_NAME     R9A11 2
 '@BASEBOARD_FAB2_LIB.BASEBOARD_FAB2(SCH_1):PAGE112_I78@MSTR_DISCRETE.RES(CHIPS)':
 'B': CDS_PINID='B';
NODE_NAME     U1L1 9
 '@BASEBOARD_FAB2_LIB.BASEBOARD_FAB2(SCH_1):PAGE112_I108@MSTR_TTL.TTL3126(CHIPS)'(1):
 'A'<1>: CDS_PINID='A(1)';
NODE_NAME     U7C1 AP56
 '@BASEBOARD_FAB2_LIB.BASEBOARD_FAB2(SCH_1):PAGE118_I73@MSTR_U_PROC.LBG_CORE_QAT_EXT_D(CHIPS)':
 'JTAG_TDO': CDS_PINID='JTAG_TDO';
NODE_NAME     U25W11 6
 '@BASEBOARD_FAB2_LIB.BASEBOARD_FAB2(SCH_1):PAGE268_I33@MSTR_DIGITAL.GTL2014(CHIPS)':
 'B3': CDS_PINID='B3';
NET_NAME
'XDP_TMS'
 '@BASEBOARD_FAB2_LIB.BASEBOARD_FAB2(SCH_1):XDP_TMS':
 C_SIGNAL='@baseboard_fab2_lib.baseboard_fab2(sch_1):xdp_tms';
NODE_NAME     J9A3 58
 '@BASEBOARD_FAB2_LIB.BASEBOARD_FAB2(SCH_1):PAGE111_I26@MSTR_SCONN.SCONN60_C21100002(CHIPS)':
 'IO58': CDS_PINID='IO58';
NODE_NAME     R8A14 2
 '@BASEBOARD_FAB2_LIB.BASEBOARD_FAB2(SCH_1):PAGE112_I80@MSTR_DISCRETE.RES(CHIPS)':
 'B': CDS_PINID='B';
NODE_NAME     U1L1 5
 '@BASEBOARD_FAB2_LIB.BASEBOARD_FAB2(SCH_1):PAGE112_I108@MSTR_TTL.TTL3126(CHIPS)'(2):
 'A'<2>: CDS_PINID='A(2)';
NODE_NAME     U7C1 AH54
 '@BASEBOARD_FAB2_LIB.BASEBOARD_FAB2(SCH_1):PAGE118_I73@MSTR_U_PROC.LBG_CORE_QAT_EXT_D(CHIPS)':
 'JTAG_TMS': CDS_PINID='JTAG_TMS';
NODE_NAME     FB25W5 2
 '@BASEBOARD_FAB2_LIB.BASEBOARD_FAB2(SCH_1):PAGE269_I74@W_HDL.BLM15AG121SN-1GP(CHIPS)':
 '2': CDS_PINID='\2\';
NET_NAME
'XDP_TMS_R'
 '@BASEBOARD_FAB2_LIB.BASEBOARD_FAB2(SCH_1):XDP_TMS_R':
 C_SIGNAL='@baseboard_fab2_lib.baseboard_fab2(sch_1):xdp_tms_r';
NODE_NAME     U25W10 6
 '@BASEBOARD_FAB2_LIB.BASEBOARD_FAB2(SCH_1):PAGE269_I49@MSTR_DIGITAL.GTL2014(CHIPS)':
 'B3': CDS_PINID='B3';
NODE_NAME     FB25W5 1
 '@BASEBOARD_FAB2_LIB.BASEBOARD_FAB2(SCH_1):PAGE269_I74@W_HDL.BLM15AG121SN-1GP(CHIPS)':
 '1': CDS_PINID='\1\';
NET_NAME
'XDP_TRST_N'
 '@BASEBOARD_FAB2_LIB.BASEBOARD_FAB2(SCH_1):XDP_TRST_N':
 C_SIGNAL='@baseboard_fab2_lib.baseboard_fab2(sch_1):xdp_trst_n';
NODE_NAME     J9A3 54
 '@BASEBOARD_FAB2_LIB.BASEBOARD_FAB2(SCH_1):PAGE111_I26@MSTR_SCONN.SCONN60_C21100002(CHIPS)':
 'IO54': CDS_PINID='IO54';
NODE_NAME     R8B2 1
 '@BASEBOARD_FAB2_LIB.BASEBOARD_FAB2(SCH_1):PAGE112_I94@MSTR_DISCRETE.RES(CHIPS)':
 'A': CDS_PINID='A';
NODE_NAME     U1L1 2
 '@BASEBOARD_FAB2_LIB.BASEBOARD_FAB2(SCH_1):PAGE112_I108@MSTR_TTL.TTL3126(CHIPS)'(3):
 'A'<3>: CDS_PINID='A(3)';
NODE_NAME     U7C1 AT56
 '@BASEBOARD_FAB2_LIB.BASEBOARD_FAB2(SCH_1):PAGE118_I73@MSTR_U_PROC.LBG_CORE_QAT_EXT_D(CHIPS)':
 'CPU_TRST_N': CDS_PINID='CPU_TRST_N';
NODE_NAME     FB25W3 2
 '@BASEBOARD_FAB2_LIB.BASEBOARD_FAB2(SCH_1):PAGE269_I73@W_HDL.BLM15AG121SN-1GP(CHIPS)':
 '2': CDS_PINID='\2\';
NET_NAME
'XDP_TRST_R_N'
 '@BASEBOARD_FAB2_LIB.BASEBOARD_FAB2(SCH_1):XDP_TRST_R_N':
 C_SIGNAL='@baseboard_fab2_lib.baseboard_fab2(sch_1):xdp_trst_r_n';
NODE_NAME     U25W12 11
 '@BASEBOARD_FAB2_LIB.BASEBOARD_FAB2(SCH_1):PAGE269_I33@MSTR_TTL.TTL3126(CHIPS)'(0):
 'B'<0>: CDS_PINID='B(0)';
NODE_NAME     FB25W3 1
 '@BASEBOARD_FAB2_LIB.BASEBOARD_FAB2(SCH_1):PAGE269_I73@W_HDL.BLM15AG121SN-1GP(CHIPS)':
 '1': CDS_PINID='\1\';
NET_NAME
'XTAL_25MHZ_IN'
 '@BASEBOARD_FAB2_LIB.BASEBOARD_FAB2(SCH_1):XTAL_25MHZ_IN':
 C_SIGNAL='@baseboard_fab2_lib.baseboard_fab2(sch_1):xtal_25mhz_in';
NODE_NAME     Y9E1 1
 '@BASEBOARD_FAB2_LIB.BASEBOARD_FAB2(SCH_1):PAGE139_I109@MSTR_DISCRETE.CRYSTAL(CHIPS)':
 'A': CDS_PINID='A';
NODE_NAME     R9E20 1
 '@BASEBOARD_FAB2_LIB.BASEBOARD_FAB2(SCH_1):PAGE139_I110@MSTR_DISCRETE.RES(CHIPS)':
 'A': CDS_PINID='A';
NODE_NAME     C9E9 1
 '@BASEBOARD_FAB2_LIB.BASEBOARD_FAB2(SCH_1):PAGE139_I249@MSTR_DISCRETE.CAP(CHIPS)':
 'A': CDS_PINID='A';
NET_NAME
'XTAL_25MHZ_IN_R'
 '@BASEBOARD_FAB2_LIB.BASEBOARD_FAB2(SCH_1):XTAL_25MHZ_IN_R':
 C_SIGNAL='@baseboard_fab2_lib.baseboard_fab2(sch_1):xtal_25mhz_in_r';
NODE_NAME     EU9E1 46
 '@BASEBOARD_FAB2_LIB.BASEBOARD_FAB2(SCH_1):PAGE139_I72@MSTR_INTEL.SPRINGVILLE(CHIPS)':
 'XTAL1': CDS_PINID='XTAL1';
NODE_NAME     R9E20 2
 '@BASEBOARD_FAB2_LIB.BASEBOARD_FAB2(SCH_1):PAGE139_I110@MSTR_DISCRETE.RES(CHIPS)':
 'B': CDS_PINID='B';
NET_NAME
'XTAL_25MHZ_OUT'
 '@BASEBOARD_FAB2_LIB.BASEBOARD_FAB2(SCH_1):XTAL_25MHZ_OUT':
 C_SIGNAL='@baseboard_fab2_lib.baseboard_fab2(sch_1):xtal_25mhz_out';
NODE_NAME     EU9E1 45
 '@BASEBOARD_FAB2_LIB.BASEBOARD_FAB2(SCH_1):PAGE139_I72@MSTR_INTEL.SPRINGVILLE(CHIPS)':
 'XTAL2': CDS_PINID='XTAL2';
NODE_NAME     R9E18 2
 '@BASEBOARD_FAB2_LIB.BASEBOARD_FAB2(SCH_1):PAGE139_I201@MSTR_DISCRETE.RES(CHIPS)':
 'B': CDS_PINID='B';
NET_NAME
'XTAL_25MHZ_OUT_R'
 '@BASEBOARD_FAB2_LIB.BASEBOARD_FAB2(SCH_1):XTAL_25MHZ_OUT_R':
 C_SIGNAL='@baseboard_fab2_lib.baseboard_fab2(sch_1):xtal_25mhz_out_r';
NODE_NAME     Y9E1 3
 '@BASEBOARD_FAB2_LIB.BASEBOARD_FAB2(SCH_1):PAGE139_I109@MSTR_DISCRETE.CRYSTAL(CHIPS)':
 'B': CDS_PINID='B';
NODE_NAME     R9E18 1
 '@BASEBOARD_FAB2_LIB.BASEBOARD_FAB2(SCH_1):PAGE139_I201@MSTR_DISCRETE.RES(CHIPS)':
 'A': CDS_PINID='A';
NODE_NAME     C9E8 1
 '@BASEBOARD_FAB2_LIB.BASEBOARD_FAB2(SCH_1):PAGE139_I250@MSTR_DISCRETE.CAP(CHIPS)':
 'A': CDS_PINID='A';
NET_NAME
'XTAL_33K_RTC1'
 '@BASEBOARD_FAB2_LIB.BASEBOARD_FAB2(SCH_1):XTAL_33K_RTC1':
 C_SIGNAL='@baseboard_fab2_lib.baseboard_fab2(sch_1):xtal_33k_rtc1';
NODE_NAME     U7C1 K17
 '@BASEBOARD_FAB2_LIB.BASEBOARD_FAB2(SCH_1):PAGE114_I40@MSTR_U_PROC.LBG_CORE_QAT_EXT_D(CHIPS)':
 'RTCX1': CDS_PINID='RTCX1';
NODE_NAME     R7C6 1
 '@BASEBOARD_FAB2_LIB.BASEBOARD_FAB2(SCH_1):PAGE114_I54@MSTR_DISCRETE.RES(CHIPS)':
 'A': CDS_PINID='A';
NODE_NAME     Y7C2 1
 '@BASEBOARD_FAB2_LIB.BASEBOARD_FAB2(SCH_1):PAGE114_I55@MSTR_DISCRETE.CRYSTAL(CHIPS)':
 'A': CDS_PINID='A';
NODE_NAME     C7C13 1
 '@BASEBOARD_FAB2_LIB.BASEBOARD_FAB2(SCH_1):PAGE114_I195@MSTR_DISCRETE.CAP(CHIPS)':
 'A': CDS_PINID='A';
NET_NAME
'XTAL_33K_RTC2'
 '@BASEBOARD_FAB2_LIB.BASEBOARD_FAB2(SCH_1):XTAL_33K_RTC2':
 C_SIGNAL='@baseboard_fab2_lib.baseboard_fab2(sch_1):xtal_33k_rtc2';
NODE_NAME     U7C1 H17
 '@BASEBOARD_FAB2_LIB.BASEBOARD_FAB2(SCH_1):PAGE114_I40@MSTR_U_PROC.LBG_CORE_QAT_EXT_D(CHIPS)':
 'RTCX2': CDS_PINID='RTCX2';
NODE_NAME     R7C6 2
 '@BASEBOARD_FAB2_LIB.BASEBOARD_FAB2(SCH_1):PAGE114_I54@MSTR_DISCRETE.RES(CHIPS)':
 'B': CDS_PINID='B';
NODE_NAME     Y7C2 2
 '@BASEBOARD_FAB2_LIB.BASEBOARD_FAB2(SCH_1):PAGE114_I55@MSTR_DISCRETE.CRYSTAL(CHIPS)':
 'B': CDS_PINID='B';
NODE_NAME     C7C15 1
 '@BASEBOARD_FAB2_LIB.BASEBOARD_FAB2(SCH_1):PAGE114_I196@MSTR_DISCRETE.CAP(CHIPS)':
 'A': CDS_PINID='A';
NET_NAME
'XTAL_CK_MNG_IN'
 '@BASEBOARD_FAB2_LIB.BASEBOARD_FAB2(SCH_1):XTAL_CK_MNG_IN':
 C_SIGNAL='@baseboard_fab2_lib.baseboard_fab2(sch_1):xtal_ck_mng_in';
NODE_NAME     EU8F2 19
 '@BASEBOARD_FAB2_LIB.BASEBOARD_FAB2(SCH_1):PAGE101_I34@MSTR_CLOCK.ICS9FGP204(CHIPS)':
 'X1_25': CDS_PINID='X1_25';
NODE_NAME     Y8F1 1
 '@BASEBOARD_FAB2_LIB.BASEBOARD_FAB2(SCH_1):PAGE101_I52@MSTR_DISCRETE.CRYSTAL(CHIPS)':
 'A': CDS_PINID='A';
NODE_NAME     C8F18 1
 '@BASEBOARD_FAB2_LIB.BASEBOARD_FAB2(SCH_1):PAGE101_I147@MSTR_DISCRETE.CAP(CHIPS)':
 'A': CDS_PINID='A';
NET_NAME
'XTAL_CK_MNG_OUT'
 '@BASEBOARD_FAB2_LIB.BASEBOARD_FAB2(SCH_1):XTAL_CK_MNG_OUT':
 C_SIGNAL='@baseboard_fab2_lib.baseboard_fab2(sch_1):xtal_ck_mng_out';
NODE_NAME     Y8F1 3
 '@BASEBOARD_FAB2_LIB.BASEBOARD_FAB2(SCH_1):PAGE101_I52@MSTR_DISCRETE.CRYSTAL(CHIPS)':
 'B': CDS_PINID='B';
NODE_NAME     R1W24 1
 '@BASEBOARD_FAB2_LIB.BASEBOARD_FAB2(SCH_1):PAGE101_I138@MSTR_DISCRETE.RES(CHIPS)':
 'A': CDS_PINID='A';
NODE_NAME     C8F19 1
 '@BASEBOARD_FAB2_LIB.BASEBOARD_FAB2(SCH_1):PAGE101_I146@MSTR_DISCRETE.CAP(CHIPS)':
 'A': CDS_PINID='A';
NET_NAME
'XTAL_CK_MNG_OUT_R'
 '@BASEBOARD_FAB2_LIB.BASEBOARD_FAB2(SCH_1):XTAL_CK_MNG_OUT_R':
 C_SIGNAL='@baseboard_fab2_lib.baseboard_fab2(sch_1):xtal_ck_mng_out_r';
NODE_NAME     EU8F2 20
 '@BASEBOARD_FAB2_LIB.BASEBOARD_FAB2(SCH_1):PAGE101_I34@MSTR_CLOCK.ICS9FGP204(CHIPS)':
 'X2_25': CDS_PINID='X2_25';
NODE_NAME     R1W24 2
 '@BASEBOARD_FAB2_LIB.BASEBOARD_FAB2(SCH_1):PAGE101_I138@MSTR_DISCRETE.RES(CHIPS)':
 'B': CDS_PINID='B';
NET_NAME
'XTAL_KR_25M_IN'
 '@BASEBOARD_FAB2_LIB.BASEBOARD_FAB2(SCH_1):XTAL_KR_25M_IN':
 C_SIGNAL='@baseboard_fab2_lib.baseboard_fab2(sch_1):xtal_kr_25m_in';
NODE_NAME     U7C1 BV16
 '@BASEBOARD_FAB2_LIB.BASEBOARD_FAB2(SCH_1):PAGE118_I73@MSTR_U_PROC.LBG_CORE_QAT_EXT_D(CHIPS)':
 'LAN_XTAL_IN': CDS_PINID='LAN_XTAL_IN';
NODE_NAME     Y8C1 1
 '@BASEBOARD_FAB2_LIB.BASEBOARD_FAB2(SCH_1):PAGE118_I76@MSTR_DISCRETE.CRYSTAL(CHIPS)':
 'A': CDS_PINID='A';
NODE_NAME     C8C1 1
 '@BASEBOARD_FAB2_LIB.BASEBOARD_FAB2(SCH_1):PAGE118_I178@MSTR_DISCRETE.CAP(CHIPS)':
 'A': CDS_PINID='A';
NET_NAME
'XTAL_KR_25M_OUT'
 '@BASEBOARD_FAB2_LIB.BASEBOARD_FAB2(SCH_1):XTAL_KR_25M_OUT':
 C_SIGNAL='@baseboard_fab2_lib.baseboard_fab2(sch_1):xtal_kr_25m_out';
NODE_NAME     U7C1 BY16
 '@BASEBOARD_FAB2_LIB.BASEBOARD_FAB2(SCH_1):PAGE118_I73@MSTR_U_PROC.LBG_CORE_QAT_EXT_D(CHIPS)':
 'LAN_XTAL_OUT': CDS_PINID='LAN_XTAL_OUT';
NODE_NAME     Y8C1 3
 '@BASEBOARD_FAB2_LIB.BASEBOARD_FAB2(SCH_1):PAGE118_I76@MSTR_DISCRETE.CRYSTAL(CHIPS)':
 'B': CDS_PINID='B';
NODE_NAME     C8C2 1
 '@BASEBOARD_FAB2_LIB.BASEBOARD_FAB2(SCH_1):PAGE118_I179@MSTR_DISCRETE.CAP(CHIPS)':
 'A': CDS_PINID='A';
NET_NAME
'XTAL_PCH_48M_IN'
 '@BASEBOARD_FAB2_LIB.BASEBOARD_FAB2(SCH_1):XTAL_PCH_48M_IN':
 C_SIGNAL='@baseboard_fab2_lib.baseboard_fab2(sch_1):xtal_pch_48m_in';
NODE_NAME     U7C1 B35
 '@BASEBOARD_FAB2_LIB.BASEBOARD_FAB2(SCH_1):PAGE114_I40@MSTR_U_PROC.LBG_CORE_QAT_EXT_D(CHIPS)':
 'XTAL_IN': CDS_PINID='XTAL_IN';
NODE_NAME     R7C1 1
 '@BASEBOARD_FAB2_LIB.BASEBOARD_FAB2(SCH_1):PAGE114_I48@MSTR_DISCRETE.RES(CHIPS)':
 'A': CDS_PINID='A';
NODE_NAME     Y7C1 1
 '@BASEBOARD_FAB2_LIB.BASEBOARD_FAB2(SCH_1):PAGE114_I49@MSTR_DISCRETE.CRYSTAL(CHIPS)':
 'A': CDS_PINID='A';
NODE_NAME     C7C4 1
 '@BASEBOARD_FAB2_LIB.BASEBOARD_FAB2(SCH_1):PAGE114_I50@MSTR_DISCRETE.CAP(CHIPS)':
 'A': CDS_PINID='A';
NET_NAME
'XTAL_PCH_48M_OUT'
 '@BASEBOARD_FAB2_LIB.BASEBOARD_FAB2(SCH_1):XTAL_PCH_48M_OUT':
 C_SIGNAL='@baseboard_fab2_lib.baseboard_fab2(sch_1):xtal_pch_48m_out';
NODE_NAME     U7C1 D35
 '@BASEBOARD_FAB2_LIB.BASEBOARD_FAB2(SCH_1):PAGE114_I40@MSTR_U_PROC.LBG_CORE_QAT_EXT_D(CHIPS)':
 'XTAL_OUT': CDS_PINID='XTAL_OUT';
NODE_NAME     C7C5 1
 '@BASEBOARD_FAB2_LIB.BASEBOARD_FAB2(SCH_1):PAGE114_I47@MSTR_DISCRETE.CAP(CHIPS)':
 'A': CDS_PINID='A';
NODE_NAME     R7C1 2
 '@BASEBOARD_FAB2_LIB.BASEBOARD_FAB2(SCH_1):PAGE114_I48@MSTR_DISCRETE.RES(CHIPS)':
 'B': CDS_PINID='B';
NODE_NAME     Y7C1 3
 '@BASEBOARD_FAB2_LIB.BASEBOARD_FAB2(SCH_1):PAGE114_I49@MSTR_DISCRETE.CRYSTAL(CHIPS)':
 'B': CDS_PINID='B';
END.
